(kicad_pcb
	(version 20260206)
	(generator "pcbnew")
	(generator_version "10.0")
	(general
		(thickness 1.6)
		(legacy_teardrops no)
	)
	(paper "A4")
	(layers
		(0 "F.Cu" signal "TOP")
		(4 "In1.Cu" signal "GND")
		(6 "In2.Cu" signal "IN1")
		(8 "In3.Cu" signal "GND1")
		(10 "In4.Cu" signal "IN2")
		(12 "In5.Cu" signal "GND2")
		(14 "In6.Cu" signal "IN3")
		(16 "In7.Cu" signal "GND3")
		(18 "In8.Cu" signal "VCC")
		(20 "In9.Cu" signal "VCC1")
		(22 "In10.Cu" signal "GND4")
		(24 "In11.Cu" signal "IN4")
		(26 "In12.Cu" signal "GND5")
		(28 "In13.Cu" signal "IN5")
		(30 "In14.Cu" signal "GND6")
		(32 "In15.Cu" signal "IN6")
		(34 "In16.Cu" signal "GND7")
		(2 "B.Cu" signal "BOTTOM")
		(9 "F.Adhes" user "F.Adhesive")
		(11 "B.Adhes" user "B.Adhesive")
		(13 "F.Paste" user "Package Geometry/Pastemask Top")
		(15 "B.Paste" user "Package Geometry/Pastemask Bottom")
		(5 "F.SilkS" user "Ref Des/Silkscreen Top")
		(7 "B.SilkS" user "Ref Des/Silkscreen Bottom")
		(1 "F.Mask" user "Board Geometry/Soldermask Top")
		(3 "B.Mask" user "Board Geometry/Soldermask Bottom")
		(17 "Dwgs.User" user "User.Drawings")
		(19 "Cmts.User" user "User.Comments")
		(21 "Eco1.User" user "User.Eco1")
		(23 "Eco2.User" user "User.Eco2")
		(25 "Edge.Cuts" user "Board Geometry/Outline")
		(27 "Margin" user)
		(31 "F.CrtYd" user "Package Geometry/Place Bound Top")
		(29 "B.CrtYd" user "Package Geometry/Place Bound Bottom")
		(35 "F.Fab" user "Ref Des/Assembly Top")
		(33 "B.Fab" user "Ref Des/Assembly Bottom")
	)
	(setup
		(pad_to_mask_clearance 0)
		(allow_soldermask_bridges_in_footprints no)
		(tenting
			(front yes)
			(back yes)
		)
		(covering
			(front no)
			(back no)
		)
		(plugging
			(front no)
			(back no)
		)
		(capping no)
		(filling no)
		(pcbplotparams
			(layerselection 0x00000000_00000000_55555555_5755f5ff)
			(plot_on_all_layers_selection 0x00000000_00000000_00000000_00000000)
			(disableapertmacros no)
			(usegerberextensions no)
			(usegerberattributes yes)
			(usegerberadvancedattributes yes)
			(creategerberjobfile yes)
			(dashed_line_dash_ratio 12)
			(dashed_line_gap_ratio 3)
			(svgprecision 4)
			(plotframeref no)
			(mode 1)
			(useauxorigin no)
			(pdf_front_fp_property_popups yes)
			(pdf_back_fp_property_popups yes)
			(pdf_metadata yes)
			(pdf_single_document no)
			(dxfpolygonmode yes)
			(dxfimperialunits yes)
			(dxfusepcbnewfont yes)
			(psnegative no)
			(psa4output no)
			(plot_black_and_white yes)
			(sketchpadsonfab no)
			(plotpadnumbers no)
			(hidednponfab no)
			(sketchdnponfab yes)
			(crossoutdnponfab yes)
			(subtractmaskfromsilk no)
			(outputformat 1)
			(mirror no)
			(drillshape 1)
			(scaleselection 1)
			(outputdirectory "")
		)
	)
	(zone
		(layers "F.Cu" "B.Cu" "In1.Cu" "In2.Cu" "In3.Cu" "In4.Cu" "In5.Cu" "In6.Cu"
			"In7.Cu" "In8.Cu" "In9.Cu" "In10.Cu" "In11.Cu" "In12.Cu" "In13.Cu" "In14.Cu"
			"In15.Cu" "In16.Cu"
		)
		(hatch none 0.5)
		(connect_pads
			(clearance 0)
		)
		(min_thickness 0.25)
		(keepout
			(tracks not_allowed)
			(vias allowed)
			(pads allowed)
			(copperpour not_allowed)
			(footprints allowed)
		)
		(placement
			(enabled no)
			(sheetname "")
		)
		(fill
			(thermal_gap 0.5)
			(thermal_bridge_width 0.5)
			(island_removal_mode 0)
		)
		(polygon
			(pts
				(arc
					(start 340.753446 -288.917126)
					(mid 340.095586 -288.917126)
					(end 340.753446 -288.917126)
				)
			)
		)
	)
	(zone
		(layers "F.Cu" "B.Cu" "In1.Cu" "In2.Cu" "In3.Cu" "In4.Cu" "In5.Cu" "In6.Cu"
			"In7.Cu" "In8.Cu" "In9.Cu" "In10.Cu" "In11.Cu" "In12.Cu" "In13.Cu" "In14.Cu"
			"In15.Cu" "In16.Cu"
		)
		(hatch none 0.5)
		(connect_pads
			(clearance 0)
		)
		(min_thickness 0.25)
		(keepout
			(tracks not_allowed)
			(vias allowed)
			(pads allowed)
			(copperpour not_allowed)
			(footprints allowed)
		)
		(placement
			(enabled no)
			(sheetname "")
		)
		(fill
			(thermal_gap 0.5)
			(thermal_bridge_width 0.5)
			(island_removal_mode 0)
		)
		(polygon
			(pts
				(arc
					(start 372.59641 -217.064336)
					(mid 371.93855 -217.064336)
					(end 372.59641 -217.064336)
				)
			)
		)
	)
	(zone
		(layers "F.Cu" "B.Cu" "In1.Cu" "In2.Cu" "In3.Cu" "In4.Cu" "In5.Cu" "In6.Cu"
			"In7.Cu" "In8.Cu" "In9.Cu" "In10.Cu" "In11.Cu" "In12.Cu" "In13.Cu" "In14.Cu"
			"In15.Cu" "In16.Cu"
		)
		(hatch none 0.5)
		(connect_pads
			(clearance 0)
		)
		(min_thickness 0.25)
		(keepout
			(tracks not_allowed)
			(vias allowed)
			(pads allowed)
			(copperpour not_allowed)
			(footprints allowed)
		)
		(placement
			(enabled no)
			(sheetname "")
		)
		(fill
			(thermal_gap 0.5)
			(thermal_bridge_width 0.5)
			(island_removal_mode 0)
		)
		(polygon
			(pts
				(arc
					(start 351.451164 -224.389442)
					(mid 350.793304 -224.389442)
					(end 351.451164 -224.389442)
				)
			)
		)
	)
	(zone
		(layers "F.Cu" "B.Cu" "In1.Cu" "In2.Cu" "In3.Cu" "In4.Cu" "In5.Cu" "In6.Cu"
			"In7.Cu" "In8.Cu" "In9.Cu" "In10.Cu" "In11.Cu" "In12.Cu" "In13.Cu" "In14.Cu"
			"In15.Cu" "In16.Cu"
		)
		(hatch none 0.5)
		(connect_pads
			(clearance 0)
		)
		(min_thickness 0.25)
		(keepout
			(tracks not_allowed)
			(vias allowed)
			(pads allowed)
			(copperpour not_allowed)
			(footprints allowed)
		)
		(placement
			(enabled no)
			(sheetname "")
		)
		(fill
			(thermal_gap 0.5)
			(thermal_bridge_width 0.5)
			(island_removal_mode 0)
		)
		(polygon
			(pts
				(arc
					(start 372.54053 -289.003232)
					(mid 372.556454 -288.961481)
					(end 372.561866 -288.917126)
				)
				(arc
					(start 372.561866 -288.917126)
					(mid 372.50793 -288.786912)
					(end 372.377716 -288.732976)
				)
				(arc
					(start 372.377716 -288.732976)
					(mid 372.282696 -288.759384)
					(end 372.214902 -288.83102)
				)
				(arc
					(start 371.744748 -289.721036)
					(mid 371.728824 -289.762787)
					(end 371.723412 -289.807142)
				)
				(arc
					(start 371.723412 -289.807142)
					(mid 371.777348 -289.937356)
					(end 371.907562 -289.991292)
				)
				(arc
					(start 371.907562 -289.991292)
					(mid 372.002582 -289.964884)
					(end 372.070376 -289.893248)
				)
			)
		)
	)
	(zone
		(layers "F.Cu" "B.Cu" "In1.Cu" "In2.Cu" "In3.Cu" "In4.Cu" "In5.Cu" "In6.Cu"
			"In7.Cu" "In8.Cu" "In9.Cu" "In10.Cu" "In11.Cu" "In12.Cu" "In13.Cu" "In14.Cu"
			"In15.Cu" "In16.Cu"
		)
		(hatch none 0.5)
		(connect_pads
			(clearance 0)
		)
		(min_thickness 0.25)
		(keepout
			(tracks not_allowed)
			(vias allowed)
			(pads allowed)
			(copperpour not_allowed)
			(footprints allowed)
		)
		(placement
			(enabled no)
			(sheetname "")
		)
		(fill
			(thermal_gap 0.5)
			(thermal_bridge_width 0.5)
			(island_removal_mode 0)
		)
		(polygon
			(pts
				(arc
					(start 429.497236 -17.220438)
					(mid 429.116236 -17.601438)
					(end 429.497236 -17.982438)
				)
				(arc
					(start 430.360836 -17.982438)
					(mid 430.741836 -17.601438)
					(end 430.360836 -17.220438)
				)
			)
		)
	)
	(zone
		(layers "F.Cu" "B.Cu" "In1.Cu" "In2.Cu" "In3.Cu" "In4.Cu" "In5.Cu" "In6.Cu"
			"In7.Cu" "In8.Cu" "In9.Cu" "In10.Cu" "In11.Cu" "In12.Cu" "In13.Cu" "In14.Cu"
			"In15.Cu" "In16.Cu"
		)
		(hatch none 0.5)
		(connect_pads
			(clearance 0)
		)
		(min_thickness 0.25)
		(keepout
			(tracks not_allowed)
			(vias allowed)
			(pads allowed)
			(copperpour not_allowed)
			(footprints allowed)
		)
		(placement
			(enabled no)
			(sheetname "")
		)
		(fill
			(thermal_gap 0.5)
			(thermal_bridge_width 0.5)
			(island_removal_mode 0)
		)
		(polygon
			(pts
				(arc
					(start 91.1352 -217.780108)
					(mid 91.063211 -217.707949)
					(end 90.964766 -217.681556)
				)
				(arc
					(start 90.964766 -217.681556)
					(mid 90.825572 -217.739212)
					(end 90.767916 -217.878406)
				)
				(arc
					(start 90.767916 -217.878406)
					(mid 90.774673 -217.929287)
					(end 90.794332 -217.976704)
				)
				(arc
					(start 91.263978 -218.79052)
					(mid 91.335967 -218.862679)
					(end 91.434412 -218.889072)
				)
				(arc
					(start 91.434412 -218.889072)
					(mid 91.573606 -218.831416)
					(end 91.631262 -218.692222)
				)
				(arc
					(start 91.631262 -218.692222)
					(mid 91.624505 -218.641341)
					(end 91.604846 -218.593924)
				)
			)
		)
	)
	(zone
		(layers "F.Cu" "B.Cu" "In1.Cu" "In2.Cu" "In3.Cu" "In4.Cu" "In5.Cu" "In6.Cu"
			"In7.Cu" "In8.Cu" "In9.Cu" "In10.Cu" "In11.Cu" "In12.Cu" "In13.Cu" "In14.Cu"
			"In15.Cu" "In16.Cu"
		)
		(hatch none 0.5)
		(connect_pads
			(clearance 0)
		)
		(min_thickness 0.25)
		(keepout
			(tracks not_allowed)
			(vias allowed)
			(pads allowed)
			(copperpour not_allowed)
			(footprints allowed)
		)
		(placement
			(enabled no)
			(sheetname "")
		)
		(fill
			(thermal_gap 0.5)
			(thermal_bridge_width 0.5)
			(island_removal_mode 0)
		)
		(polygon
			(pts
				(arc
					(start 372.706646 -288.917126)
					(mid 372.048786 -288.917126)
					(end 372.706646 -288.917126)
				)
			)
		)
	)
	(zone
		(layers "F.Cu" "B.Cu" "In1.Cu" "In2.Cu" "In3.Cu" "In4.Cu" "In5.Cu" "In6.Cu"
			"In7.Cu" "In8.Cu" "In9.Cu" "In10.Cu" "In11.Cu" "In12.Cu" "In13.Cu" "In14.Cu"
			"In15.Cu" "In16.Cu"
		)
		(hatch none 0.5)
		(connect_pads
			(clearance 0)
		)
		(min_thickness 0.25)
		(keepout
			(tracks not_allowed)
			(vias allowed)
			(pads allowed)
			(copperpour not_allowed)
			(footprints allowed)
		)
		(placement
			(enabled no)
			(sheetname "")
		)
		(fill
			(thermal_gap 0.5)
			(thermal_bridge_width 0.5)
			(island_removal_mode 0)
		)
		(polygon
			(pts
				(arc
					(start 348.631764 -217.878406)
					(mid 347.973904 -217.878406)
					(end 348.631764 -217.878406)
				)
			)
		)
	)
	(zone
		(layers "F.Cu" "B.Cu" "In1.Cu" "In2.Cu" "In3.Cu" "In4.Cu" "In5.Cu" "In6.Cu"
			"In7.Cu" "In8.Cu" "In9.Cu" "In10.Cu" "In11.Cu" "In12.Cu" "In13.Cu" "In14.Cu"
			"In15.Cu" "In16.Cu"
		)
		(hatch none 0.5)
		(connect_pads
			(clearance 0)
		)
		(min_thickness 0.25)
		(keepout
			(tracks not_allowed)
			(vias allowed)
			(pads allowed)
			(copperpour not_allowed)
			(footprints allowed)
		)
		(placement
			(enabled no)
			(sheetname "")
		)
		(fill
			(thermal_gap 0.5)
			(thermal_bridge_width 0.5)
			(island_removal_mode 0)
		)
		(polygon
			(pts
				(arc
					(start 338.76361 -217.064336)
					(mid 338.10575 -217.064336)
					(end 338.76361 -217.064336)
				)
			)
		)
	)
	(zone
		(layers "F.Cu" "B.Cu" "In1.Cu" "In2.Cu" "In3.Cu" "In4.Cu" "In5.Cu" "In6.Cu"
			"In7.Cu" "In8.Cu" "In9.Cu" "In10.Cu" "In11.Cu" "In12.Cu" "In13.Cu" "In14.Cu"
			"In15.Cu" "In16.Cu"
		)
		(hatch none 0.5)
		(connect_pads
			(clearance 0)
		)
		(min_thickness 0.25)
		(keepout
			(tracks not_allowed)
			(vias allowed)
			(pads allowed)
			(copperpour not_allowed)
			(footprints allowed)
		)
		(placement
			(enabled no)
			(sheetname "")
		)
		(fill
			(thermal_gap 0.5)
			(thermal_bridge_width 0.5)
			(island_removal_mode 0)
		)
		(polygon
			(pts
				(xy 777.712186 -391.095738) (xy 782.711922 -391.095738) (xy 782.407122 -391.400538) (xy 778.016986 -391.400538)
			)
		)
	)
	(zone
		(layers "F.Cu" "B.Cu" "In1.Cu" "In2.Cu" "In3.Cu" "In4.Cu" "In5.Cu" "In6.Cu"
			"In7.Cu" "In8.Cu" "In9.Cu" "In10.Cu" "In11.Cu" "In12.Cu" "In13.Cu" "In14.Cu"
			"In15.Cu" "In16.Cu"
		)
		(hatch none 0.5)
		(connect_pads
			(clearance 0)
		)
		(min_thickness 0.25)
		(keepout
			(tracks not_allowed)
			(vias allowed)
			(pads allowed)
			(copperpour not_allowed)
			(footprints allowed)
		)
		(placement
			(enabled no)
			(sheetname "")
		)
		(fill
			(thermal_gap 0.5)
			(thermal_bridge_width 0.5)
			(island_removal_mode 0)
		)
		(polygon
			(pts
				(arc
					(start 124.186188 -214.622634)
					(mid 123.528328 -214.622634)
					(end 124.186188 -214.622634)
				)
			)
		)
	)
	(zone
		(layers "F.Cu" "B.Cu" "In1.Cu" "In2.Cu" "In3.Cu" "In4.Cu" "In5.Cu" "In6.Cu"
			"In7.Cu" "In8.Cu" "In9.Cu" "In10.Cu" "In11.Cu" "In12.Cu" "In13.Cu" "In14.Cu"
			"In15.Cu" "In16.Cu"
		)
		(hatch none 0.5)
		(connect_pads
			(clearance 0)
		)
		(min_thickness 0.25)
		(keepout
			(tracks not_allowed)
			(vias allowed)
			(pads allowed)
			(copperpour not_allowed)
			(footprints allowed)
		)
		(placement
			(enabled no)
			(sheetname "")
		)
		(fill
			(thermal_gap 0.5)
			(thermal_bridge_width 0.5)
			(island_removal_mode 0)
		)
		(polygon
			(pts
				(arc
					(start 100.5332 -224.291144)
					(mid 100.461211 -224.218985)
					(end 100.362766 -224.192592)
				)
				(arc
					(start 100.362766 -224.192592)
					(mid 100.223572 -224.250248)
					(end 100.165916 -224.389442)
				)
				(arc
					(start 100.165916 -224.389442)
					(mid 100.172673 -224.440323)
					(end 100.192332 -224.48774)
				)
				(arc
					(start 100.661978 -225.301556)
					(mid 100.733967 -225.373715)
					(end 100.832412 -225.400108)
				)
				(arc
					(start 100.832412 -225.400108)
					(mid 100.971606 -225.342452)
					(end 101.029262 -225.203258)
				)
				(arc
					(start 101.029262 -225.203258)
					(mid 101.022505 -225.152377)
					(end 101.002846 -225.10496)
				)
			)
		)
	)
	(zone
		(layers "F.Cu" "B.Cu" "In1.Cu" "In2.Cu" "In3.Cu" "In4.Cu" "In5.Cu" "In6.Cu"
			"In7.Cu" "In8.Cu" "In9.Cu" "In10.Cu" "In11.Cu" "In12.Cu" "In13.Cu" "In14.Cu"
			"In15.Cu" "In16.Cu"
		)
		(hatch none 0.5)
		(connect_pads
			(clearance 0)
		)
		(min_thickness 0.25)
		(keepout
			(tracks not_allowed)
			(vias allowed)
			(pads allowed)
			(copperpour not_allowed)
			(footprints allowed)
		)
		(placement
			(enabled no)
			(sheetname "")
		)
		(fill
			(thermal_gap 0.5)
			(thermal_bridge_width 0.5)
			(island_removal_mode 0)
		)
		(polygon
			(pts
				(arc
					(start 351.090992 -275.8948)
					(mid 350.433132 -275.8948)
					(end 351.090992 -275.8948)
				)
			)
		)
	)
	(zone
		(layers "F.Cu" "B.Cu" "In1.Cu" "In2.Cu" "In3.Cu" "In4.Cu" "In5.Cu" "In6.Cu"
			"In7.Cu" "In8.Cu" "In9.Cu" "In10.Cu" "In11.Cu" "In12.Cu" "In13.Cu" "In14.Cu"
			"In15.Cu" "In16.Cu"
		)
		(hatch none 0.5)
		(connect_pads
			(clearance 0)
		)
		(min_thickness 0.25)
		(keepout
			(tracks not_allowed)
			(vias allowed)
			(pads allowed)
			(copperpour not_allowed)
			(footprints allowed)
		)
		(placement
			(enabled no)
			(sheetname "")
		)
		(fill
			(thermal_gap 0.5)
			(thermal_bridge_width 0.5)
			(island_removal_mode 0)
		)
		(polygon
			(pts
				(arc
					(start 91.215718 -288.917126)
					(mid 91.873578 -288.917126)
					(end 91.215718 -288.917126)
				)
			)
		)
	)
	(zone
		(layers "F.Cu" "B.Cu" "In1.Cu" "In2.Cu" "In3.Cu" "In4.Cu" "In5.Cu" "In6.Cu"
			"In7.Cu" "In8.Cu" "In9.Cu" "In10.Cu" "In11.Cu" "In12.Cu" "In13.Cu" "In14.Cu"
			"In15.Cu" "In16.Cu"
		)
		(hatch none 0.5)
		(connect_pads
			(clearance 0)
		)
		(min_thickness 0.25)
		(keepout
			(tracks not_allowed)
			(vias allowed)
			(pads allowed)
			(copperpour not_allowed)
			(footprints allowed)
		)
		(placement
			(enabled no)
			(sheetname "")
		)
		(fill
			(thermal_gap 0.5)
			(thermal_bridge_width 0.5)
			(island_removal_mode 0)
		)
		(polygon
			(pts
				(arc
					(start 110.089696 -224.389442)
					(mid 109.431836 -224.389442)
					(end 110.089696 -224.389442)
				)
			)
		)
	)
	(zone
		(layers "F.Cu" "B.Cu" "In1.Cu" "In2.Cu" "In3.Cu" "In4.Cu" "In5.Cu" "In6.Cu"
			"In7.Cu" "In8.Cu" "In9.Cu" "In10.Cu" "In11.Cu" "In12.Cu" "In13.Cu" "In14.Cu"
			"In15.Cu" "In16.Cu"
		)
		(hatch none 0.5)
		(connect_pads
			(clearance 0)
		)
		(min_thickness 0.25)
		(keepout
			(tracks not_allowed)
			(vias allowed)
			(pads allowed)
			(copperpour not_allowed)
			(footprints allowed)
		)
		(placement
			(enabled no)
			(sheetname "")
		)
		(fill
			(thermal_gap 0.5)
			(thermal_bridge_width 0.5)
			(island_removal_mode 0)
		)
		(polygon
			(pts
				(arc
					(start 349.10141 -218.692222)
					(mid 348.44355 -218.692222)
					(end 349.10141 -218.692222)
				)
			)
		)
	)
	(zone
		(layers "F.Cu" "B.Cu" "In1.Cu" "In2.Cu" "In3.Cu" "In4.Cu" "In5.Cu" "In6.Cu"
			"In7.Cu" "In8.Cu" "In9.Cu" "In10.Cu" "In11.Cu" "In12.Cu" "In13.Cu" "In14.Cu"
			"In15.Cu" "In16.Cu"
		)
		(hatch none 0.5)
		(connect_pads
			(clearance 0)
		)
		(min_thickness 0.25)
		(keepout
			(tracks not_allowed)
			(vias allowed)
			(pads allowed)
			(copperpour not_allowed)
			(footprints allowed)
		)
		(placement
			(enabled no)
			(sheetname "")
		)
		(fill
			(thermal_gap 0.5)
			(thermal_bridge_width 0.5)
			(island_removal_mode 0)
		)
		(polygon
			(pts
				(arc
					(start 374.787668 -224.291144)
					(mid 374.715679 -224.218985)
					(end 374.617234 -224.192592)
				)
				(arc
					(start 374.617234 -224.192592)
					(mid 374.47804 -224.250248)
					(end 374.420384 -224.389442)
				)
				(arc
					(start 374.420384 -224.389442)
					(mid 374.427141 -224.440323)
					(end 374.4468 -224.48774)
				)
				(arc
					(start 374.916446 -225.301556)
					(mid 374.988435 -225.373715)
					(end 375.08688 -225.400108)
				)
				(arc
					(start 375.08688 -225.400108)
					(mid 375.226074 -225.342452)
					(end 375.28373 -225.203258)
				)
				(arc
					(start 375.28373 -225.203258)
					(mid 375.276973 -225.152377)
					(end 375.257314 -225.10496)
				)
			)
		)
	)
	(zone
		(layers "F.Cu" "B.Cu" "In1.Cu" "In2.Cu" "In3.Cu" "In4.Cu" "In5.Cu" "In6.Cu"
			"In7.Cu" "In8.Cu" "In9.Cu" "In10.Cu" "In11.Cu" "In12.Cu" "In13.Cu" "In14.Cu"
			"In15.Cu" "In16.Cu"
		)
		(hatch none 0.5)
		(connect_pads
			(clearance 0)
		)
		(min_thickness 0.25)
		(keepout
			(tracks not_allowed)
			(vias allowed)
			(pads allowed)
			(copperpour not_allowed)
			(footprints allowed)
		)
		(placement
			(enabled no)
			(sheetname "")
		)
		(fill
			(thermal_gap 0.5)
			(thermal_bridge_width 0.5)
			(island_removal_mode 0)
		)
		(polygon
			(pts
				(arc
					(start 406.46477 -406.62352)
					(mid 406.08377 -407.00452)
					(end 406.46477 -407.38552)
				)
				(arc
					(start 407.32837 -407.38552)
					(mid 407.70937 -407.00452)
					(end 407.32837 -406.62352)
				)
			)
		)
	)
	(zone
		(layers "F.Cu" "B.Cu" "In1.Cu" "In2.Cu" "In3.Cu" "In4.Cu" "In5.Cu" "In6.Cu"
			"In7.Cu" "In8.Cu" "In9.Cu" "In10.Cu" "In11.Cu" "In12.Cu" "In13.Cu" "In14.Cu"
			"In15.Cu" "In16.Cu"
		)
		(hatch none 0.5)
		(connect_pads
			(clearance 0)
		)
		(min_thickness 0.25)
		(keepout
			(tracks not_allowed)
			(vias allowed)
			(pads allowed)
			(copperpour not_allowed)
			(footprints allowed)
		)
		(placement
			(enabled no)
			(sheetname "")
		)
		(fill
			(thermal_gap 0.5)
			(thermal_bridge_width 0.5)
			(island_removal_mode 0)
		)
		(polygon
			(pts
				(arc
					(start 369.307364 -221.133924)
					(mid 368.649504 -221.133924)
					(end 369.307364 -221.133924)
				)
			)
		)
	)
	(zone
		(layers "F.Cu" "B.Cu" "In1.Cu" "In2.Cu" "In3.Cu" "In4.Cu" "In5.Cu" "In6.Cu"
			"In7.Cu" "In8.Cu" "In9.Cu" "In10.Cu" "In11.Cu" "In12.Cu" "In13.Cu" "In14.Cu"
			"In15.Cu" "In16.Cu"
		)
		(hatch none 0.5)
		(connect_pads
			(clearance 0)
		)
		(min_thickness 0.25)
		(keepout
			(tracks not_allowed)
			(vias allowed)
			(pads allowed)
			(copperpour not_allowed)
			(footprints allowed)
		)
		(placement
			(enabled no)
			(sheetname "")
		)
		(fill
			(thermal_gap 0.5)
			(thermal_bridge_width 0.5)
			(island_removal_mode 0)
		)
		(polygon
			(pts
				(arc
					(start 353.17176 -221.231968)
					(mid 353.191444 -221.184558)
					(end 353.198176 -221.13367)
				)
				(arc
					(start 353.198176 -221.13367)
					(mid 353.14052 -220.994476)
					(end 353.001326 -220.93682)
				)
				(arc
					(start 353.001326 -220.93682)
					(mid 352.902895 -220.963236)
					(end 352.830892 -221.035372)
				)
				(arc
					(start 352.361246 -221.849442)
					(mid 352.341562 -221.896852)
					(end 352.33483 -221.94774)
				)
				(arc
					(start 352.33483 -221.94774)
					(mid 352.392486 -222.086934)
					(end 352.53168 -222.14459)
				)
				(arc
					(start 352.53168 -222.14459)
					(mid 352.630111 -222.118174)
					(end 352.702114 -222.046038)
				)
			)
		)
	)
	(zone
		(layers "F.Cu" "B.Cu" "In1.Cu" "In2.Cu" "In3.Cu" "In4.Cu" "In5.Cu" "In6.Cu"
			"In7.Cu" "In8.Cu" "In9.Cu" "In10.Cu" "In11.Cu" "In12.Cu" "In13.Cu" "In14.Cu"
			"In15.Cu" "In16.Cu"
		)
		(hatch none 0.5)
		(connect_pads
			(clearance 0)
		)
		(min_thickness 0.25)
		(keepout
			(tracks not_allowed)
			(vias allowed)
			(pads allowed)
			(copperpour not_allowed)
			(footprints allowed)
		)
		(placement
			(enabled no)
			(sheetname "")
		)
		(fill
			(thermal_gap 0.5)
			(thermal_bridge_width 0.5)
			(island_removal_mode 0)
		)
		(polygon
			(pts
				(arc
					(start 130.765296 -224.389442)
					(mid 130.107436 -224.389442)
					(end 130.765296 -224.389442)
				)
			)
		)
	)
	(zone
		(layers "F.Cu" "B.Cu" "In1.Cu" "In2.Cu" "In3.Cu" "In4.Cu" "In5.Cu" "In6.Cu"
			"In7.Cu" "In8.Cu" "In9.Cu" "In10.Cu" "In11.Cu" "In12.Cu" "In13.Cu" "In14.Cu"
			"In15.Cu" "In16.Cu"
		)
		(hatch none 0.5)
		(connect_pads
			(clearance 0)
		)
		(min_thickness 0.25)
		(keepout
			(tracks not_allowed)
			(vias allowed)
			(pads allowed)
			(copperpour not_allowed)
			(footprints allowed)
		)
		(placement
			(enabled no)
			(sheetname "")
		)
		(fill
			(thermal_gap 0.5)
			(thermal_bridge_width 0.5)
			(island_removal_mode 0)
		)
		(polygon
			(pts
				(arc
					(start 347.801946 -286.475424)
					(mid 347.144086 -286.475424)
					(end 347.801946 -286.475424)
				)
			)
		)
	)
	(zone
		(layers "F.Cu" "B.Cu" "In1.Cu" "In2.Cu" "In3.Cu" "In4.Cu" "In5.Cu" "In6.Cu"
			"In7.Cu" "In8.Cu" "In9.Cu" "In10.Cu" "In11.Cu" "In12.Cu" "In13.Cu" "In14.Cu"
			"In15.Cu" "In16.Cu"
		)
		(hatch none 0.5)
		(connect_pads
			(clearance 0)
		)
		(min_thickness 0.25)
		(keepout
			(tracks not_allowed)
			(vias allowed)
			(pads allowed)
			(copperpour not_allowed)
			(footprints allowed)
		)
		(placement
			(enabled no)
			(sheetname "")
		)
		(fill
			(thermal_gap 0.5)
			(thermal_bridge_width 0.5)
			(island_removal_mode 0)
		)
		(polygon
			(pts
				(arc
					(start 120.426988 -214.622634)
					(mid 119.769128 -214.622634)
					(end 120.426988 -214.622634)
				)
			)
		)
	)
	(zone
		(layers "F.Cu" "B.Cu" "In1.Cu" "In2.Cu" "In3.Cu" "In4.Cu" "In5.Cu" "In6.Cu"
			"In7.Cu" "In8.Cu" "In9.Cu" "In10.Cu" "In11.Cu" "In12.Cu" "In13.Cu" "In14.Cu"
			"In15.Cu" "In16.Cu"
		)
		(hatch none 0.5)
		(connect_pads
			(clearance 0)
		)
		(min_thickness 0.25)
		(keepout
			(tracks not_allowed)
			(vias allowed)
			(pads allowed)
			(copperpour not_allowed)
			(footprints allowed)
		)
		(placement
			(enabled no)
			(sheetname "")
		)
		(fill
			(thermal_gap 0.5)
			(thermal_bridge_width 0.5)
			(island_removal_mode 0)
		)
		(polygon
			(pts
				(arc
					(start 345.34221 -225.203258)
					(mid 344.68435 -225.203258)
					(end 345.34221 -225.203258)
				)
			)
		)
	)
	(zone
		(layers "F.Cu" "B.Cu" "In1.Cu" "In2.Cu" "In3.Cu" "In4.Cu" "In5.Cu" "In6.Cu"
			"In7.Cu" "In8.Cu" "In9.Cu" "In10.Cu" "In11.Cu" "In12.Cu" "In13.Cu" "In14.Cu"
			"In15.Cu" "In16.Cu"
		)
		(hatch none 0.5)
		(connect_pads
			(clearance 0)
		)
		(min_thickness 0.25)
		(keepout
			(tracks not_allowed)
			(vias allowed)
			(pads allowed)
			(copperpour not_allowed)
			(footprints allowed)
		)
		(placement
			(enabled no)
			(sheetname "")
		)
		(fill
			(thermal_gap 0.5)
			(thermal_bridge_width 0.5)
			(island_removal_mode 0)
		)
		(polygon
			(pts
				(arc
					(start 356.700328 -276.610318)
					(mid 356.680644 -276.657728)
					(end 356.673912 -276.708616)
				)
				(arc
					(start 356.673912 -276.708616)
					(mid 356.731568 -276.84781)
					(end 356.870762 -276.905466)
				)
				(arc
					(start 356.870762 -276.905466)
					(mid 356.969193 -276.87905)
					(end 357.041196 -276.806914)
				)
				(arc
					(start 357.511096 -275.992844)
					(mid 357.53078 -275.945434)
					(end 357.537512 -275.894546)
				)
				(arc
					(start 357.537512 -275.894546)
					(mid 357.479856 -275.755352)
					(end 357.340662 -275.697696)
				)
				(arc
					(start 357.340662 -275.697696)
					(mid 357.242231 -275.724112)
					(end 357.170228 -275.796248)
				)
			)
		)
	)
	(zone
		(layers "F.Cu" "B.Cu" "In1.Cu" "In2.Cu" "In3.Cu" "In4.Cu" "In5.Cu" "In6.Cu"
			"In7.Cu" "In8.Cu" "In9.Cu" "In10.Cu" "In11.Cu" "In12.Cu" "In13.Cu" "In14.Cu"
			"In15.Cu" "In16.Cu"
		)
		(hatch none 0.5)
		(connect_pads
			(clearance 0)
		)
		(min_thickness 0.25)
		(keepout
			(tracks not_allowed)
			(vias allowed)
			(pads allowed)
			(copperpour not_allowed)
			(footprints allowed)
		)
		(placement
			(enabled no)
			(sheetname "")
		)
		(fill
			(thermal_gap 0.5)
			(thermal_bridge_width 0.5)
			(island_removal_mode 0)
		)
		(polygon
			(pts
				(arc
					(start 418.838888 -4.57073)
					(mid 418.457888 -4.95173)
					(end 418.838888 -5.33273)
				)
				(arc
					(start 419.702488 -5.33273)
					(mid 420.083488 -4.95173)
					(end 419.702488 -4.57073)
				)
			)
		)
	)
	(zone
		(layers "F.Cu" "B.Cu" "In1.Cu" "In2.Cu" "In3.Cu" "In4.Cu" "In5.Cu" "In6.Cu"
			"In7.Cu" "In8.Cu" "In9.Cu" "In10.Cu" "In11.Cu" "In12.Cu" "In13.Cu" "In14.Cu"
			"In15.Cu" "In16.Cu"
		)
		(hatch none 0.5)
		(connect_pads
			(clearance 0)
		)
		(min_thickness 0.25)
		(keepout
			(tracks not_allowed)
			(vias allowed)
			(pads allowed)
			(copperpour not_allowed)
			(footprints allowed)
		)
		(placement
			(enabled no)
			(sheetname "")
		)
		(fill
			(thermal_gap 0.5)
			(thermal_bridge_width 0.5)
			(island_removal_mode 0)
		)
		(polygon
			(pts
				(arc
					(start 144.660874 -400.477228)
					(mid 144.279874 -400.858228)
					(end 144.660874 -401.239228)
				)
				(arc
					(start 145.524474 -401.239228)
					(mid 145.905474 -400.858228)
					(end 145.524474 -400.477228)
				)
			)
		)
	)
	(zone
		(layers "F.Cu" "B.Cu" "In1.Cu" "In2.Cu" "In3.Cu" "In4.Cu" "In5.Cu" "In6.Cu"
			"In7.Cu" "In8.Cu" "In9.Cu" "In10.Cu" "In11.Cu" "In12.Cu" "In13.Cu" "In14.Cu"
			"In15.Cu" "In16.Cu"
		)
		(hatch none 0.5)
		(connect_pads
			(clearance 0)
		)
		(min_thickness 0.25)
		(keepout
			(tracks not_allowed)
			(vias allowed)
			(pads allowed)
			(copperpour not_allowed)
			(footprints allowed)
		)
		(placement
			(enabled no)
			(sheetname "")
		)
		(fill
			(thermal_gap 0.5)
			(thermal_bridge_width 0.5)
			(island_removal_mode 0)
		)
		(polygon
			(pts
				(arc
					(start 94.112588 -214.622634)
					(mid 93.454728 -214.622634)
					(end 94.112588 -214.622634)
				)
			)
		)
	)
	(zone
		(layers "F.Cu" "B.Cu" "In1.Cu" "In2.Cu" "In3.Cu" "In4.Cu" "In5.Cu" "In6.Cu"
			"In7.Cu" "In8.Cu" "In9.Cu" "In10.Cu" "In11.Cu" "In12.Cu" "In13.Cu" "In14.Cu"
			"In15.Cu" "In16.Cu"
		)
		(hatch none 0.5)
		(connect_pads
			(clearance 0)
		)
		(min_thickness 0.25)
		(keepout
			(tracks not_allowed)
			(vias allowed)
			(pads allowed)
			(copperpour not_allowed)
			(footprints allowed)
		)
		(placement
			(enabled no)
			(sheetname "")
		)
		(fill
			(thermal_gap 0.5)
			(thermal_bridge_width 0.5)
			(island_removal_mode 0)
		)
		(polygon
			(pts
				(arc
					(start 380.225046 -288.917126)
					(mid 379.567186 -288.917126)
					(end 380.225046 -288.917126)
				)
			)
		)
	)
	(zone
		(layers "F.Cu" "B.Cu" "In1.Cu" "In2.Cu" "In3.Cu" "In4.Cu" "In5.Cu" "In6.Cu"
			"In7.Cu" "In8.Cu" "In9.Cu" "In10.Cu" "In11.Cu" "In12.Cu" "In13.Cu" "In14.Cu"
			"In15.Cu" "In16.Cu"
		)
		(hatch none 0.5)
		(connect_pads
			(clearance 0)
		)
		(min_thickness 0.25)
		(keepout
			(tracks not_allowed)
			(vias allowed)
			(pads allowed)
			(copperpour not_allowed)
			(footprints allowed)
		)
		(placement
			(enabled no)
			(sheetname "")
		)
		(fill
			(thermal_gap 0.5)
			(thermal_bridge_width 0.5)
			(island_removal_mode 0)
		)
		(polygon
			(pts
				(arc
					(start 120.154954 -403.502876)
					(mid 119.773954 -403.883876)
					(end 120.154954 -404.264876)
				)
				(arc
					(start 121.018554 -404.264876)
					(mid 121.399554 -403.883876)
					(end 121.018554 -403.502876)
				)
			)
		)
	)
	(zone
		(layers "F.Cu" "B.Cu" "In1.Cu" "In2.Cu" "In3.Cu" "In4.Cu" "In5.Cu" "In6.Cu"
			"In7.Cu" "In8.Cu" "In9.Cu" "In10.Cu" "In11.Cu" "In12.Cu" "In13.Cu" "In14.Cu"
			"In15.Cu" "In16.Cu"
		)
		(hatch none 0.5)
		(connect_pads
			(clearance 0)
		)
		(min_thickness 0.25)
		(keepout
			(tracks not_allowed)
			(vias allowed)
			(pads allowed)
			(copperpour not_allowed)
			(footprints allowed)
		)
		(placement
			(enabled no)
			(sheetname "")
		)
		(fill
			(thermal_gap 0.5)
			(thermal_bridge_width 0.5)
			(island_removal_mode 0)
		)
		(polygon
			(pts
				(arc
					(start 21.121878 -17.23136)
					(mid 20.740878 -17.61236)
					(end 21.121878 -17.99336)
				)
				(arc
					(start 21.985478 -17.99336)
					(mid 22.366478 -17.61236)
					(end 21.985478 -17.23136)
				)
			)
		)
	)
	(zone
		(layers "F.Cu" "B.Cu" "In1.Cu" "In2.Cu" "In3.Cu" "In4.Cu" "In5.Cu" "In6.Cu"
			"In7.Cu" "In8.Cu" "In9.Cu" "In10.Cu" "In11.Cu" "In12.Cu" "In13.Cu" "In14.Cu"
			"In15.Cu" "In16.Cu"
		)
		(hatch none 0.5)
		(connect_pads
			(clearance 0)
		)
		(min_thickness 0.25)
		(keepout
			(tracks not_allowed)
			(vias allowed)
			(pads allowed)
			(copperpour not_allowed)
			(footprints allowed)
		)
		(placement
			(enabled no)
			(sheetname "")
		)
		(fill
			(thermal_gap 0.5)
			(thermal_bridge_width 0.5)
			(island_removal_mode 0)
		)
		(polygon
			(pts
				(arc
					(start 104.920542 -218.692222)
					(mid 104.262682 -218.692222)
					(end 104.920542 -218.692222)
				)
			)
		)
	)
	(zone
		(layers "F.Cu" "B.Cu" "In1.Cu" "In2.Cu" "In3.Cu" "In4.Cu" "In5.Cu" "In6.Cu"
			"In7.Cu" "In8.Cu" "In9.Cu" "In10.Cu" "In11.Cu" "In12.Cu" "In13.Cu" "In14.Cu"
			"In15.Cu" "In16.Cu"
		)
		(hatch none 0.5)
		(connect_pads
			(clearance 0)
		)
		(min_thickness 0.25)
		(keepout
			(tracks not_allowed)
			(vias allowed)
			(pads allowed)
			(copperpour not_allowed)
			(footprints allowed)
		)
		(placement
			(enabled no)
			(sheetname "")
		)
		(fill
			(thermal_gap 0.5)
			(thermal_bridge_width 0.5)
			(island_removal_mode 0)
		)
		(polygon
			(pts
				(arc
					(start 246.325644 -122.057414)
					(mid 245.944644 -121.676414)
					(end 245.563644 -122.057414)
				)
				(arc
					(start 245.563644 -122.921014)
					(mid 245.944644 -123.302014)
					(end 246.325644 -122.921014)
				)
			)
		)
	)
	(zone
		(layers "F.Cu" "B.Cu" "In1.Cu" "In2.Cu" "In3.Cu" "In4.Cu" "In5.Cu" "In6.Cu"
			"In7.Cu" "In8.Cu" "In9.Cu" "In10.Cu" "In11.Cu" "In12.Cu" "In13.Cu" "In14.Cu"
			"In15.Cu" "In16.Cu"
		)
		(hatch none 0.5)
		(connect_pads
			(clearance 0)
		)
		(min_thickness 0.25)
		(keepout
			(tracks not_allowed)
			(vias allowed)
			(pads allowed)
			(copperpour not_allowed)
			(footprints allowed)
		)
		(placement
			(enabled no)
			(sheetname "")
		)
		(fill
			(thermal_gap 0.5)
			(thermal_bridge_width 0.5)
			(island_removal_mode 0)
		)
		(polygon
			(pts
				(arc
					(start 52.19573 -18.75536)
					(mid 51.81473 -19.13636)
					(end 52.19573 -19.51736)
				)
				(arc
					(start 53.05933 -19.51736)
					(mid 53.44033 -19.13636)
					(end 53.05933 -18.75536)
				)
			)
		)
	)
	(zone
		(layers "F.Cu" "B.Cu" "In1.Cu" "In2.Cu" "In3.Cu" "In4.Cu" "In5.Cu" "In6.Cu"
			"In7.Cu" "In8.Cu" "In9.Cu" "In10.Cu" "In11.Cu" "In12.Cu" "In13.Cu" "In14.Cu"
			"In15.Cu" "In16.Cu"
		)
		(hatch none 0.5)
		(connect_pads
			(clearance 0)
		)
		(min_thickness 0.25)
		(keepout
			(tracks not_allowed)
			(vias allowed)
			(pads allowed)
			(copperpour not_allowed)
			(footprints allowed)
		)
		(placement
			(enabled no)
			(sheetname "")
		)
		(fill
			(thermal_gap 0.5)
			(thermal_bridge_width 0.5)
			(island_removal_mode 0)
		)
		(polygon
			(pts
				(arc
					(start 92.703142 -217.064336)
					(mid 92.045282 -217.064336)
					(end 92.703142 -217.064336)
				)
			)
		)
	)
	(zone
		(layers "F.Cu" "B.Cu" "In1.Cu" "In2.Cu" "In3.Cu" "In4.Cu" "In5.Cu" "In6.Cu"
			"In7.Cu" "In8.Cu" "In9.Cu" "In10.Cu" "In11.Cu" "In12.Cu" "In13.Cu" "In14.Cu"
			"In15.Cu" "In16.Cu"
		)
		(hatch none 0.5)
		(connect_pads
			(clearance 0)
		)
		(min_thickness 0.25)
		(keepout
			(tracks not_allowed)
			(vias allowed)
			(pads allowed)
			(copperpour not_allowed)
			(footprints allowed)
		)
		(placement
			(enabled no)
			(sheetname "")
		)
		(fill
			(thermal_gap 0.5)
			(thermal_bridge_width 0.5)
			(island_removal_mode 0)
		)
		(polygon
			(pts
				(arc
					(start 371.13845 -284.74924)
					(mid 371.066461 -284.677081)
					(end 370.968016 -284.650688)
				)
				(arc
					(start 370.968016 -284.650688)
					(mid 370.828822 -284.708344)
					(end 370.771166 -284.847538)
				)
				(arc
					(start 370.771166 -284.847538)
					(mid 370.777923 -284.898419)
					(end 370.797582 -284.945836)
				)
				(arc
					(start 371.267228 -285.759652)
					(mid 371.339217 -285.831811)
					(end 371.437662 -285.858204)
				)
				(arc
					(start 371.437662 -285.858204)
					(mid 371.576856 -285.800548)
					(end 371.634512 -285.661354)
				)
				(arc
					(start 371.634512 -285.661354)
					(mid 371.627755 -285.610473)
					(end 371.608096 -285.563056)
				)
			)
		)
	)
	(zone
		(layers "F.Cu" "B.Cu" "In1.Cu" "In2.Cu" "In3.Cu" "In4.Cu" "In5.Cu" "In6.Cu"
			"In7.Cu" "In8.Cu" "In9.Cu" "In10.Cu" "In11.Cu" "In12.Cu" "In13.Cu" "In14.Cu"
			"In15.Cu" "In16.Cu"
		)
		(hatch none 0.5)
		(connect_pads
			(clearance 0)
		)
		(min_thickness 0.25)
		(keepout
			(tracks not_allowed)
			(vias allowed)
			(pads allowed)
			(copperpour not_allowed)
			(footprints allowed)
		)
		(placement
			(enabled no)
			(sheetname "")
		)
		(fill
			(thermal_gap 0.5)
			(thermal_bridge_width 0.5)
			(island_removal_mode 0)
		)
		(polygon
			(pts
				(arc
					(start 356.260146 -275.08073)
					(mid 355.602286 -275.08073)
					(end 356.260146 -275.08073)
				)
			)
		)
	)
	(zone
		(layers "F.Cu" "B.Cu" "In1.Cu" "In2.Cu" "In3.Cu" "In4.Cu" "In5.Cu" "In6.Cu"
			"In7.Cu" "In8.Cu" "In9.Cu" "In10.Cu" "In11.Cu" "In12.Cu" "In13.Cu" "In14.Cu"
			"In15.Cu" "In16.Cu"
		)
		(hatch none 0.5)
		(connect_pads
			(clearance 0)
		)
		(min_thickness 0.25)
		(keepout
			(tracks not_allowed)
			(vias allowed)
			(pads allowed)
			(copperpour not_allowed)
			(footprints allowed)
		)
		(placement
			(enabled no)
			(sheetname "")
		)
		(fill
			(thermal_gap 0.5)
			(thermal_bridge_width 0.5)
			(island_removal_mode 0)
		)
		(polygon
			(pts
				(arc
					(start 351.090992 -279.150318)
					(mid 350.433132 -279.150318)
					(end 351.090992 -279.150318)
				)
			)
		)
	)
	(zone
		(layers "F.Cu" "B.Cu" "In1.Cu" "In2.Cu" "In3.Cu" "In4.Cu" "In5.Cu" "In6.Cu"
			"In7.Cu" "In8.Cu" "In9.Cu" "In10.Cu" "In11.Cu" "In12.Cu" "In13.Cu" "In14.Cu"
			"In15.Cu" "In16.Cu"
		)
		(hatch none 0.5)
		(connect_pads
			(clearance 0)
		)
		(min_thickness 0.25)
		(keepout
			(tracks not_allowed)
			(vias allowed)
			(pads allowed)
			(copperpour not_allowed)
			(footprints allowed)
		)
		(placement
			(enabled no)
			(sheetname "")
		)
		(fill
			(thermal_gap 0.5)
			(thermal_bridge_width 0.5)
			(island_removal_mode 0)
		)
		(polygon
			(pts
				(xy 468.100156 -315.71184) (xy 468.100156 -320.71183) (xy 467.795356 -320.40703) (xy 467.795356 -316.01664)
			)
		)
	)
	(zone
		(layers "F.Cu" "B.Cu" "In1.Cu" "In2.Cu" "In3.Cu" "In4.Cu" "In5.Cu" "In6.Cu"
			"In7.Cu" "In8.Cu" "In9.Cu" "In10.Cu" "In11.Cu" "In12.Cu" "In13.Cu" "In14.Cu"
			"In15.Cu" "In16.Cu"
		)
		(hatch none 0.5)
		(connect_pads
			(clearance 0)
		)
		(min_thickness 0.25)
		(keepout
			(tracks not_allowed)
			(vias allowed)
			(pads allowed)
			(copperpour not_allowed)
			(footprints allowed)
		)
		(placement
			(enabled no)
			(sheetname "")
		)
		(fill
			(thermal_gap 0.5)
			(thermal_bridge_width 0.5)
			(island_removal_mode 0)
		)
		(polygon
			(pts
				(arc
					(start 364.608364 -217.878406)
					(mid 363.950504 -217.878406)
					(end 364.608364 -217.878406)
				)
			)
		)
	)
	(zone
		(layers "F.Cu" "B.Cu" "In1.Cu" "In2.Cu" "In3.Cu" "In4.Cu" "In5.Cu" "In6.Cu"
			"In7.Cu" "In8.Cu" "In9.Cu" "In10.Cu" "In11.Cu" "In12.Cu" "In13.Cu" "In14.Cu"
			"In15.Cu" "In16.Cu"
		)
		(hatch none 0.5)
		(connect_pads
			(clearance 0)
		)
		(min_thickness 0.25)
		(keepout
			(tracks not_allowed)
			(vias allowed)
			(pads allowed)
			(copperpour not_allowed)
			(footprints allowed)
		)
		(placement
			(enabled no)
			(sheetname "")
		)
		(fill
			(thermal_gap 0.5)
			(thermal_bridge_width 0.5)
			(island_removal_mode 0)
		)
		(polygon
			(pts
				(arc
					(start 349.10141 -225.203258)
					(mid 348.44355 -225.203258)
					(end 349.10141 -225.203258)
				)
			)
		)
	)
	(zone
		(layers "F.Cu" "B.Cu" "In1.Cu" "In2.Cu" "In3.Cu" "In4.Cu" "In5.Cu" "In6.Cu"
			"In7.Cu" "In8.Cu" "In9.Cu" "In10.Cu" "In11.Cu" "In12.Cu" "In13.Cu" "In14.Cu"
			"In15.Cu" "In16.Cu"
		)
		(hatch none 0.5)
		(connect_pads
			(clearance 0)
		)
		(min_thickness 0.25)
		(keepout
			(tracks not_allowed)
			(vias allowed)
			(pads allowed)
			(copperpour not_allowed)
			(footprints allowed)
		)
		(placement
			(enabled no)
			(sheetname "")
		)
		(fill
			(thermal_gap 0.5)
			(thermal_bridge_width 0.5)
			(island_removal_mode 0)
		)
		(polygon
			(pts
				(arc
					(start 95.992696 -224.389442)
					(mid 95.334836 -224.389442)
					(end 95.992696 -224.389442)
				)
			)
		)
	)
	(zone
		(layers "F.Cu" "B.Cu" "In1.Cu" "In2.Cu" "In3.Cu" "In4.Cu" "In5.Cu" "In6.Cu"
			"In7.Cu" "In8.Cu" "In9.Cu" "In10.Cu" "In11.Cu" "In12.Cu" "In13.Cu" "In14.Cu"
			"In15.Cu" "In16.Cu"
		)
		(hatch none 0.5)
		(connect_pads
			(clearance 0)
		)
		(min_thickness 0.25)
		(keepout
			(tracks not_allowed)
			(vias allowed)
			(pads allowed)
			(copperpour not_allowed)
			(footprints allowed)
		)
		(placement
			(enabled no)
			(sheetname "")
		)
		(fill
			(thermal_gap 0.5)
			(thermal_bridge_width 0.5)
			(island_removal_mode 0)
		)
		(polygon
			(pts
				(arc
					(start 357.669338 -275.8948)
					(mid 357.011478 -275.8948)
					(end 357.669338 -275.8948)
				)
			)
		)
	)
	(zone
		(layers "F.Cu" "B.Cu" "In1.Cu" "In2.Cu" "In3.Cu" "In4.Cu" "In5.Cu" "In6.Cu"
			"In7.Cu" "In8.Cu" "In9.Cu" "In10.Cu" "In11.Cu" "In12.Cu" "In13.Cu" "In14.Cu"
			"In15.Cu" "In16.Cu"
		)
		(hatch none 0.5)
		(connect_pads
			(clearance 0)
		)
		(min_thickness 0.25)
		(keepout
			(tracks not_allowed)
			(vias allowed)
			(pads allowed)
			(copperpour not_allowed)
			(footprints allowed)
		)
		(placement
			(enabled no)
			(sheetname "")
		)
		(fill
			(thermal_gap 0.5)
			(thermal_bridge_width 0.5)
			(island_removal_mode 0)
		)
		(polygon
			(pts
				(arc
					(start 349.10141 -221.94774)
					(mid 348.44355 -221.94774)
					(end 349.10141 -221.94774)
				)
			)
		)
	)
	(zone
		(layers "F.Cu" "B.Cu" "In1.Cu" "In2.Cu" "In3.Cu" "In4.Cu" "In5.Cu" "In6.Cu"
			"In7.Cu" "In8.Cu" "In9.Cu" "In10.Cu" "In11.Cu" "In12.Cu" "In13.Cu" "In14.Cu"
			"In15.Cu" "In16.Cu"
		)
		(hatch none 0.5)
		(connect_pads
			(clearance 0)
		)
		(min_thickness 0.25)
		(keepout
			(tracks not_allowed)
			(vias allowed)
			(pads allowed)
			(copperpour not_allowed)
			(footprints allowed)
		)
		(placement
			(enabled no)
			(sheetname "")
		)
		(fill
			(thermal_gap 0.5)
			(thermal_bridge_width 0.5)
			(island_removal_mode 0)
		)
		(polygon
			(pts
				(arc
					(start 97.324164 -289.807142)
					(mid 97.982024 -289.807142)
					(end 97.324164 -289.807142)
				)
			)
		)
	)
	(zone
		(layers "F.Cu" "B.Cu" "In1.Cu" "In2.Cu" "In3.Cu" "In4.Cu" "In5.Cu" "In6.Cu"
			"In7.Cu" "In8.Cu" "In9.Cu" "In10.Cu" "In11.Cu" "In12.Cu" "In13.Cu" "In14.Cu"
			"In15.Cu" "In16.Cu"
		)
		(hatch none 0.5)
		(connect_pads
			(clearance 0)
		)
		(min_thickness 0.25)
		(keepout
			(tracks not_allowed)
			(vias allowed)
			(pads allowed)
			(copperpour not_allowed)
			(footprints allowed)
		)
		(placement
			(enabled no)
			(sheetname "")
		)
		(fill
			(thermal_gap 0.5)
			(thermal_bridge_width 0.5)
			(island_removal_mode 0)
		)
		(polygon
			(pts
				(arc
					(start 370.247164 -221.133924)
					(mid 369.589304 -221.133924)
					(end 370.247164 -221.133924)
				)
			)
		)
	)
	(zone
		(layers "F.Cu" "B.Cu" "In1.Cu" "In2.Cu" "In3.Cu" "In4.Cu" "In5.Cu" "In6.Cu"
			"In7.Cu" "In8.Cu" "In9.Cu" "In10.Cu" "In11.Cu" "In12.Cu" "In13.Cu" "In14.Cu"
			"In15.Cu" "In16.Cu"
		)
		(hatch none 0.5)
		(connect_pads
			(clearance 0)
		)
		(min_thickness 0.25)
		(keepout
			(tracks not_allowed)
			(vias allowed)
			(pads allowed)
			(copperpour not_allowed)
			(footprints allowed)
		)
		(placement
			(enabled no)
			(sheetname "")
		)
		(fill
			(thermal_gap 0.5)
			(thermal_bridge_width 0.5)
			(island_removal_mode 0)
		)
		(polygon
			(pts
				(arc
					(start 97.794318 -288.917126)
					(mid 98.452178 -288.917126)
					(end 97.794318 -288.917126)
				)
			)
		)
	)
	(zone
		(layers "F.Cu" "B.Cu" "In1.Cu" "In2.Cu" "In3.Cu" "In4.Cu" "In5.Cu" "In6.Cu"
			"In7.Cu" "In8.Cu" "In9.Cu" "In10.Cu" "In11.Cu" "In12.Cu" "In13.Cu" "In14.Cu"
			"In15.Cu" "In16.Cu"
		)
		(hatch none 0.5)
		(connect_pads
			(clearance 0)
		)
		(min_thickness 0.25)
		(keepout
			(tracks not_allowed)
			(vias allowed)
			(pads allowed)
			(copperpour not_allowed)
			(footprints allowed)
		)
		(placement
			(enabled no)
			(sheetname "")
		)
		(fill
			(thermal_gap 0.5)
			(thermal_bridge_width 0.5)
			(island_removal_mode 0)
		)
		(polygon
			(pts
				(arc
					(start 121.318782 -284.74924)
					(mid 121.246793 -284.677081)
					(end 121.148348 -284.650688)
				)
				(arc
					(start 121.148348 -284.650688)
					(mid 121.009154 -284.708344)
					(end 120.951498 -284.847538)
				)
				(arc
					(start 120.951498 -284.847538)
					(mid 120.958255 -284.898419)
					(end 120.977914 -284.945836)
				)
				(arc
					(start 121.44756 -285.759652)
					(mid 121.519549 -285.831811)
					(end 121.617994 -285.858204)
				)
				(arc
					(start 121.617994 -285.858204)
					(mid 121.757188 -285.800548)
					(end 121.814844 -285.661354)
				)
				(arc
					(start 121.814844 -285.661354)
					(mid 121.808087 -285.610473)
					(end 121.788428 -285.563056)
				)
			)
		)
	)
	(zone
		(layers "F.Cu" "B.Cu" "In1.Cu" "In2.Cu" "In3.Cu" "In4.Cu" "In5.Cu" "In6.Cu"
			"In7.Cu" "In8.Cu" "In9.Cu" "In10.Cu" "In11.Cu" "In12.Cu" "In13.Cu" "In14.Cu"
			"In15.Cu" "In16.Cu"
		)
		(hatch none 0.5)
		(connect_pads
			(clearance 0)
		)
		(min_thickness 0.25)
		(keepout
			(tracks not_allowed)
			(vias allowed)
			(pads allowed)
			(copperpour not_allowed)
			(footprints allowed)
		)
		(placement
			(enabled no)
			(sheetname "")
		)
		(fill
			(thermal_gap 0.5)
			(thermal_bridge_width 0.5)
			(island_removal_mode 0)
		)
		(polygon
			(pts
				(arc
					(start 95.522542 -218.692222)
					(mid 94.864682 -218.692222)
					(end 95.522542 -218.692222)
				)
			)
		)
	)
	(zone
		(layers "F.Cu" "B.Cu" "In1.Cu" "In2.Cu" "In3.Cu" "In4.Cu" "In5.Cu" "In6.Cu"
			"In7.Cu" "In8.Cu" "In9.Cu" "In10.Cu" "In11.Cu" "In12.Cu" "In13.Cu" "In14.Cu"
			"In15.Cu" "In16.Cu"
		)
		(hatch none 0.5)
		(connect_pads
			(clearance 0)
		)
		(min_thickness 0.25)
		(keepout
			(tracks not_allowed)
			(vias allowed)
			(pads allowed)
			(copperpour not_allowed)
			(footprints allowed)
		)
		(placement
			(enabled no)
			(sheetname "")
		)
		(fill
			(thermal_gap 0.5)
			(thermal_bridge_width 0.5)
			(island_removal_mode 0)
		)
		(polygon
			(pts
				(arc
					(start 94.974664 -282.405836)
					(mid 95.632524 -282.405836)
					(end 94.974664 -282.405836)
				)
			)
		)
	)
	(zone
		(layers "F.Cu" "B.Cu" "In1.Cu" "In2.Cu" "In3.Cu" "In4.Cu" "In5.Cu" "In6.Cu"
			"In7.Cu" "In8.Cu" "In9.Cu" "In10.Cu" "In11.Cu" "In12.Cu" "In13.Cu" "In14.Cu"
			"In15.Cu" "In16.Cu"
		)
		(hatch none 0.5)
		(connect_pads
			(clearance 0)
		)
		(min_thickness 0.25)
		(keepout
			(tracks not_allowed)
			(vias allowed)
			(pads allowed)
			(copperpour not_allowed)
			(footprints allowed)
		)
		(placement
			(enabled no)
			(sheetname "")
		)
		(fill
			(thermal_gap 0.5)
			(thermal_bridge_width 0.5)
			(island_removal_mode 0)
		)
		(polygon
			(pts
				(arc
					(start 350.510856 -214.622634)
					(mid 349.852996 -214.622634)
					(end 350.510856 -214.622634)
				)
			)
		)
	)
	(zone
		(layers "F.Cu" "B.Cu" "In1.Cu" "In2.Cu" "In3.Cu" "In4.Cu" "In5.Cu" "In6.Cu"
			"In7.Cu" "In8.Cu" "In9.Cu" "In10.Cu" "In11.Cu" "In12.Cu" "In13.Cu" "In14.Cu"
			"In15.Cu" "In16.Cu"
		)
		(hatch none 0.5)
		(connect_pads
			(clearance 0)
		)
		(min_thickness 0.25)
		(keepout
			(tracks not_allowed)
			(vias allowed)
			(pads allowed)
			(copperpour not_allowed)
			(footprints allowed)
		)
		(placement
			(enabled no)
			(sheetname "")
		)
		(fill
			(thermal_gap 0.5)
			(thermal_bridge_width 0.5)
			(island_removal_mode 0)
		)
		(polygon
			(pts
				(arc
					(start 104.372664 -282.405836)
					(mid 105.030524 -282.405836)
					(end 104.372664 -282.405836)
				)
			)
		)
	)
	(zone
		(layers "F.Cu" "B.Cu" "In1.Cu" "In2.Cu" "In3.Cu" "In4.Cu" "In5.Cu" "In6.Cu"
			"In7.Cu" "In8.Cu" "In9.Cu" "In10.Cu" "In11.Cu" "In12.Cu" "In13.Cu" "In14.Cu"
			"In15.Cu" "In16.Cu"
		)
		(hatch none 0.5)
		(connect_pads
			(clearance 0)
		)
		(min_thickness 0.25)
		(keepout
			(tracks not_allowed)
			(vias allowed)
			(pads allowed)
			(copperpour not_allowed)
			(footprints allowed)
		)
		(placement
			(enabled no)
			(sheetname "")
		)
		(fill
			(thermal_gap 0.5)
			(thermal_bridge_width 0.5)
			(island_removal_mode 0)
		)
		(polygon
			(pts
				(arc
					(start 119.409464 -285.661354)
					(mid 120.067324 -285.661354)
					(end 119.409464 -285.661354)
				)
			)
		)
	)
	(zone
		(layers "F.Cu" "B.Cu" "In1.Cu" "In2.Cu" "In3.Cu" "In4.Cu" "In5.Cu" "In6.Cu"
			"In7.Cu" "In8.Cu" "In9.Cu" "In10.Cu" "In11.Cu" "In12.Cu" "In13.Cu" "In14.Cu"
			"In15.Cu" "In16.Cu"
		)
		(hatch none 0.5)
		(connect_pads
			(clearance 0)
		)
		(min_thickness 0.25)
		(keepout
			(tracks not_allowed)
			(vias allowed)
			(pads allowed)
			(copperpour not_allowed)
			(footprints allowed)
		)
		(placement
			(enabled no)
			(sheetname "")
		)
		(fill
			(thermal_gap 0.5)
			(thermal_bridge_width 0.5)
			(island_removal_mode 0)
		)
		(polygon
			(pts
				(arc
					(start 90.353896 -221.133924)
					(mid 89.696036 -221.133924)
					(end 90.353896 -221.133924)
				)
			)
		)
	)
	(zone
		(layers "F.Cu" "B.Cu" "In1.Cu" "In2.Cu" "In3.Cu" "In4.Cu" "In5.Cu" "In6.Cu"
			"In7.Cu" "In8.Cu" "In9.Cu" "In10.Cu" "In11.Cu" "In12.Cu" "In13.Cu" "In14.Cu"
			"In15.Cu" "In16.Cu"
		)
		(hatch none 0.5)
		(connect_pads
			(clearance 0)
		)
		(min_thickness 0.25)
		(keepout
			(tracks not_allowed)
			(vias allowed)
			(pads allowed)
			(copperpour not_allowed)
			(footprints allowed)
		)
		(placement
			(enabled no)
			(sheetname "")
		)
		(fill
			(thermal_gap 0.5)
			(thermal_bridge_width 0.5)
			(island_removal_mode 0)
		)
		(polygon
			(pts
				(arc
					(start 385.097782 -206.024988)
					(mid 380.651766 -206.024988)
					(end 385.097782 -206.024988)
				)
			)
		)
	)
	(zone
		(layers "F.Cu" "B.Cu" "In1.Cu" "In2.Cu" "In3.Cu" "In4.Cu" "In5.Cu" "In6.Cu"
			"In7.Cu" "In8.Cu" "In9.Cu" "In10.Cu" "In11.Cu" "In12.Cu" "In13.Cu" "In14.Cu"
			"In15.Cu" "In16.Cu"
		)
		(hatch none 0.5)
		(connect_pads
			(clearance 0)
		)
		(min_thickness 0.25)
		(keepout
			(tracks not_allowed)
			(vias allowed)
			(pads allowed)
			(copperpour not_allowed)
			(footprints allowed)
		)
		(placement
			(enabled no)
			(sheetname "")
		)
		(fill
			(thermal_gap 0.5)
			(thermal_bridge_width 0.5)
			(island_removal_mode 0)
		)
		(polygon
			(pts
				(arc
					(start 91.403424 -281.59202)
					(mid 90.745564 -281.59202)
					(end 91.403424 -281.59202)
				)
			)
		)
	)
	(zone
		(layers "F.Cu" "B.Cu" "In1.Cu" "In2.Cu" "In3.Cu" "In4.Cu" "In5.Cu" "In6.Cu"
			"In7.Cu" "In8.Cu" "In9.Cu" "In10.Cu" "In11.Cu" "In12.Cu" "In13.Cu" "In14.Cu"
			"In15.Cu" "In16.Cu"
		)
		(hatch none 0.5)
		(connect_pads
			(clearance 0)
		)
		(min_thickness 0.25)
		(keepout
			(tracks not_allowed)
			(vias allowed)
			(pads allowed)
			(copperpour not_allowed)
			(footprints allowed)
		)
		(placement
			(enabled no)
			(sheetname "")
		)
		(fill
			(thermal_gap 0.5)
			(thermal_bridge_width 0.5)
			(island_removal_mode 0)
		)
		(polygon
			(pts
				(arc
					(start 353.330764 -224.389442)
					(mid 352.672904 -224.389442)
					(end 353.330764 -224.389442)
				)
			)
		)
	)
	(zone
		(layers "F.Cu" "B.Cu" "In1.Cu" "In2.Cu" "In3.Cu" "In4.Cu" "In5.Cu" "In6.Cu"
			"In7.Cu" "In8.Cu" "In9.Cu" "In10.Cu" "In11.Cu" "In12.Cu" "In13.Cu" "In14.Cu"
			"In15.Cu" "In16.Cu"
		)
		(hatch none 0.5)
		(connect_pads
			(clearance 0)
		)
		(min_thickness 0.25)
		(keepout
			(tracks not_allowed)
			(vias allowed)
			(pads allowed)
			(copperpour not_allowed)
			(footprints allowed)
		)
		(placement
			(enabled no)
			(sheetname "")
		)
		(fill
			(thermal_gap 0.5)
			(thermal_bridge_width 0.5)
			(island_removal_mode 0)
		)
		(polygon
			(pts
				(arc
					(start 374.89765 -284.74924)
					(mid 374.825661 -284.677081)
					(end 374.727216 -284.650688)
				)
				(arc
					(start 374.727216 -284.650688)
					(mid 374.588022 -284.708344)
					(end 374.530366 -284.847538)
				)
				(arc
					(start 374.530366 -284.847538)
					(mid 374.537123 -284.898419)
					(end 374.556782 -284.945836)
				)
				(arc
					(start 375.026428 -285.759652)
					(mid 375.098417 -285.831811)
					(end 375.196862 -285.858204)
				)
				(arc
					(start 375.196862 -285.858204)
					(mid 375.336056 -285.800548)
					(end 375.393712 -285.661354)
				)
				(arc
					(start 375.393712 -285.661354)
					(mid 375.386955 -285.610473)
					(end 375.367296 -285.563056)
				)
			)
		)
	)
	(zone
		(layers "F.Cu" "B.Cu" "In1.Cu" "In2.Cu" "In3.Cu" "In4.Cu" "In5.Cu" "In6.Cu"
			"In7.Cu" "In8.Cu" "In9.Cu" "In10.Cu" "In11.Cu" "In12.Cu" "In13.Cu" "In14.Cu"
			"In15.Cu" "In16.Cu"
		)
		(hatch none 0.5)
		(connect_pads
			(clearance 0)
		)
		(min_thickness 0.25)
		(keepout
			(tracks not_allowed)
			(vias allowed)
			(pads allowed)
			(copperpour not_allowed)
			(footprints allowed)
		)
		(placement
			(enabled no)
			(sheetname "")
		)
		(fill
			(thermal_gap 0.5)
			(thermal_bridge_width 0.5)
			(island_removal_mode 0)
		)
		(polygon
			(pts
				(arc
					(start 96.303846 -223.67367)
					(mid 96.32353 -223.62626)
					(end 96.330262 -223.575372)
				)
				(arc
					(start 96.330262 -223.575372)
					(mid 96.272606 -223.436178)
					(end 96.133412 -223.378522)
				)
				(arc
					(start 96.133412 -223.378522)
					(mid 96.034981 -223.404938)
					(end 95.962978 -223.477074)
				)
				(arc
					(start 95.493332 -224.291144)
					(mid 95.473648 -224.338554)
					(end 95.466916 -224.389442)
				)
				(arc
					(start 95.466916 -224.389442)
					(mid 95.524572 -224.528636)
					(end 95.663766 -224.586292)
				)
				(arc
					(start 95.663766 -224.586292)
					(mid 95.762197 -224.559876)
					(end 95.8342 -224.48774)
				)
			)
		)
	)
	(zone
		(layers "F.Cu" "B.Cu" "In1.Cu" "In2.Cu" "In3.Cu" "In4.Cu" "In5.Cu" "In6.Cu"
			"In7.Cu" "In8.Cu" "In9.Cu" "In10.Cu" "In11.Cu" "In12.Cu" "In13.Cu" "In14.Cu"
			"In15.Cu" "In16.Cu"
		)
		(hatch none 0.5)
		(connect_pads
			(clearance 0)
		)
		(min_thickness 0.25)
		(keepout
			(tracks not_allowed)
			(vias allowed)
			(pads allowed)
			(copperpour not_allowed)
			(footprints allowed)
		)
		(placement
			(enabled no)
			(sheetname "")
		)
		(fill
			(thermal_gap 0.5)
			(thermal_bridge_width 0.5)
			(island_removal_mode 0)
		)
		(polygon
			(pts
				(arc
					(start 348.271592 -282.405836)
					(mid 347.613732 -282.405836)
					(end 348.271592 -282.405836)
				)
			)
		)
	)
	(zone
		(layers "F.Cu" "B.Cu" "In1.Cu" "In2.Cu" "In3.Cu" "In4.Cu" "In5.Cu" "In6.Cu"
			"In7.Cu" "In8.Cu" "In9.Cu" "In10.Cu" "In11.Cu" "In12.Cu" "In13.Cu" "In14.Cu"
			"In15.Cu" "In16.Cu"
		)
		(hatch none 0.5)
		(connect_pads
			(clearance 0)
		)
		(min_thickness 0.25)
		(keepout
			(tracks not_allowed)
			(vias allowed)
			(pads allowed)
			(copperpour not_allowed)
			(footprints allowed)
		)
		(placement
			(enabled no)
			(sheetname "")
		)
		(fill
			(thermal_gap 0.5)
			(thermal_bridge_width 0.5)
			(island_removal_mode 0)
		)
		(polygon
			(pts
				(arc
					(start 105.860342 -223.575626)
					(mid 105.202482 -223.575626)
					(end 105.860342 -223.575626)
				)
			)
		)
	)
	(zone
		(layers "F.Cu" "B.Cu" "In1.Cu" "In2.Cu" "In3.Cu" "In4.Cu" "In5.Cu" "In6.Cu"
			"In7.Cu" "In8.Cu" "In9.Cu" "In10.Cu" "In11.Cu" "In12.Cu" "In13.Cu" "In14.Cu"
			"In15.Cu" "In16.Cu"
		)
		(hatch none 0.5)
		(connect_pads
			(clearance 0)
		)
		(min_thickness 0.25)
		(keepout
			(tracks not_allowed)
			(vias allowed)
			(pads allowed)
			(copperpour not_allowed)
			(footprints allowed)
		)
		(placement
			(enabled no)
			(sheetname "")
		)
		(fill
			(thermal_gap 0.5)
			(thermal_bridge_width 0.5)
			(island_removal_mode 0)
		)
		(polygon
			(pts
				(arc
					(start 123.246896 -217.878406)
					(mid 122.589036 -217.878406)
					(end 123.246896 -217.878406)
				)
			)
		)
	)
	(zone
		(layers "F.Cu" "B.Cu" "In1.Cu" "In2.Cu" "In3.Cu" "In4.Cu" "In5.Cu" "In6.Cu"
			"In7.Cu" "In8.Cu" "In9.Cu" "In10.Cu" "In11.Cu" "In12.Cu" "In13.Cu" "In14.Cu"
			"In15.Cu" "In16.Cu"
		)
		(hatch none 0.5)
		(connect_pads
			(clearance 0)
		)
		(min_thickness 0.25)
		(keepout
			(tracks not_allowed)
			(vias allowed)
			(pads allowed)
			(copperpour not_allowed)
			(footprints allowed)
		)
		(placement
			(enabled no)
			(sheetname "")
		)
		(fill
			(thermal_gap 0.5)
			(thermal_bridge_width 0.5)
			(island_removal_mode 0)
		)
		(polygon
			(pts
				(arc
					(start 379.645164 -217.878406)
					(mid 378.987304 -217.878406)
					(end 379.645164 -217.878406)
				)
			)
		)
	)
	(zone
		(layers "F.Cu" "B.Cu" "In1.Cu" "In2.Cu" "In3.Cu" "In4.Cu" "In5.Cu" "In6.Cu"
			"In7.Cu" "In8.Cu" "In9.Cu" "In10.Cu" "In11.Cu" "In12.Cu" "In13.Cu" "In14.Cu"
			"In15.Cu" "In16.Cu"
		)
		(hatch none 0.5)
		(connect_pads
			(clearance 0)
		)
		(min_thickness 0.25)
		(keepout
			(tracks not_allowed)
			(vias allowed)
			(pads allowed)
			(copperpour not_allowed)
			(footprints allowed)
		)
		(placement
			(enabled no)
			(sheetname "")
		)
		(fill
			(thermal_gap 0.5)
			(thermal_bridge_width 0.5)
			(island_removal_mode 0)
		)
		(polygon
			(pts
				(arc
					(start 109.149388 -214.622634)
					(mid 108.491528 -214.622634)
					(end 109.149388 -214.622634)
				)
			)
		)
	)
	(zone
		(layers "F.Cu" "B.Cu" "In1.Cu" "In2.Cu" "In3.Cu" "In4.Cu" "In5.Cu" "In6.Cu"
			"In7.Cu" "In8.Cu" "In9.Cu" "In10.Cu" "In11.Cu" "In12.Cu" "In13.Cu" "In14.Cu"
			"In15.Cu" "In16.Cu"
		)
		(hatch none 0.5)
		(connect_pads
			(clearance 0)
		)
		(min_thickness 0.25)
		(keepout
			(tracks not_allowed)
			(vias allowed)
			(pads allowed)
			(copperpour not_allowed)
			(footprints allowed)
		)
		(placement
			(enabled no)
			(sheetname "")
		)
		(fill
			(thermal_gap 0.5)
			(thermal_bridge_width 0.5)
			(island_removal_mode 0)
		)
		(polygon
			(pts
				(arc
					(start 134.524496 -221.133924)
					(mid 133.866636 -221.133924)
					(end 134.524496 -221.133924)
				)
			)
		)
	)
	(zone
		(layers "F.Cu" "B.Cu" "In1.Cu" "In2.Cu" "In3.Cu" "In4.Cu" "In5.Cu" "In6.Cu"
			"In7.Cu" "In8.Cu" "In9.Cu" "In10.Cu" "In11.Cu" "In12.Cu" "In13.Cu" "In14.Cu"
			"In15.Cu" "In16.Cu"
		)
		(hatch none 0.5)
		(connect_pads
			(clearance 0)
		)
		(min_thickness 0.25)
		(keepout
			(tracks not_allowed)
			(vias allowed)
			(pads allowed)
			(copperpour not_allowed)
			(footprints allowed)
		)
		(placement
			(enabled no)
			(sheetname "")
		)
		(fill
			(thermal_gap 0.5)
			(thermal_bridge_width 0.5)
			(island_removal_mode 0)
		)
		(polygon
			(pts
				(arc
					(start 129.355342 -225.203258)
					(mid 128.697482 -225.203258)
					(end 129.355342 -225.203258)
				)
			)
		)
	)
	(zone
		(layers "F.Cu" "B.Cu" "In1.Cu" "In2.Cu" "In3.Cu" "In4.Cu" "In5.Cu" "In6.Cu"
			"In7.Cu" "In8.Cu" "In9.Cu" "In10.Cu" "In11.Cu" "In12.Cu" "In13.Cu" "In14.Cu"
			"In15.Cu" "In16.Cu"
		)
		(hatch none 0.5)
		(connect_pads
			(clearance 0)
		)
		(min_thickness 0.25)
		(keepout
			(tracks not_allowed)
			(vias allowed)
			(pads allowed)
			(copperpour not_allowed)
			(footprints allowed)
		)
		(placement
			(enabled no)
			(sheetname "")
		)
		(fill
			(thermal_gap 0.5)
			(thermal_bridge_width 0.5)
			(island_removal_mode 0)
		)
		(polygon
			(pts
				(arc
					(start 311.452768 -409.649168)
					(mid 311.071768 -410.030168)
					(end 311.452768 -410.411168)
				)
				(arc
					(start 312.316368 -410.411168)
					(mid 312.697368 -410.030168)
					(end 312.316368 -409.649168)
				)
			)
		)
	)
	(zone
		(layers "F.Cu" "B.Cu" "In1.Cu" "In2.Cu" "In3.Cu" "In4.Cu" "In5.Cu" "In6.Cu"
			"In7.Cu" "In8.Cu" "In9.Cu" "In10.Cu" "In11.Cu" "In12.Cu" "In13.Cu" "In14.Cu"
			"In15.Cu" "In16.Cu"
		)
		(hatch none 0.5)
		(connect_pads
			(clearance 0)
		)
		(min_thickness 0.25)
		(keepout
			(tracks not_allowed)
			(vias allowed)
			(pads allowed)
			(copperpour not_allowed)
			(footprints allowed)
		)
		(placement
			(enabled no)
			(sheetname "")
		)
		(fill
			(thermal_gap 0.5)
			(thermal_bridge_width 0.5)
			(island_removal_mode 0)
		)
		(polygon
			(pts
				(arc
					(start 104.53116 -275.796502)
					(mid 104.511476 -275.843912)
					(end 104.504744 -275.8948)
				)
				(arc
					(start 104.504744 -275.8948)
					(mid 104.5624 -276.033994)
					(end 104.701594 -276.09165)
				)
				(arc
					(start 104.701594 -276.09165)
					(mid 104.800025 -276.065234)
					(end 104.872028 -275.993098)
				)
				(arc
					(start 105.341928 -275.179028)
					(mid 105.361612 -275.131618)
					(end 105.368344 -275.08073)
				)
				(arc
					(start 105.368344 -275.08073)
					(mid 105.310688 -274.941536)
					(end 105.171494 -274.88388)
				)
				(arc
					(start 105.171494 -274.88388)
					(mid 105.073063 -274.910296)
					(end 105.00106 -274.982432)
				)
			)
		)
	)
	(zone
		(layers "F.Cu" "B.Cu" "In1.Cu" "In2.Cu" "In3.Cu" "In4.Cu" "In5.Cu" "In6.Cu"
			"In7.Cu" "In8.Cu" "In9.Cu" "In10.Cu" "In11.Cu" "In12.Cu" "In13.Cu" "In14.Cu"
			"In15.Cu" "In16.Cu"
		)
		(hatch none 0.5)
		(connect_pads
			(clearance 0)
		)
		(min_thickness 0.25)
		(keepout
			(tracks not_allowed)
			(vias allowed)
			(pads allowed)
			(copperpour not_allowed)
			(footprints allowed)
		)
		(placement
			(enabled no)
			(sheetname "")
		)
		(fill
			(thermal_gap 0.5)
			(thermal_bridge_width 0.5)
			(island_removal_mode 0)
		)
		(polygon
			(pts
				(arc
					(start 343.932764 -217.878406)
					(mid 343.274904 -217.878406)
					(end 343.932764 -217.878406)
				)
			)
		)
	)
	(zone
		(layers "F.Cu" "B.Cu" "In1.Cu" "In2.Cu" "In3.Cu" "In4.Cu" "In5.Cu" "In6.Cu"
			"In7.Cu" "In8.Cu" "In9.Cu" "In10.Cu" "In11.Cu" "In12.Cu" "In13.Cu" "In14.Cu"
			"In15.Cu" "In16.Cu"
		)
		(hatch none 0.5)
		(connect_pads
			(clearance 0)
		)
		(min_thickness 0.25)
		(keepout
			(tracks not_allowed)
			(vias allowed)
			(pads allowed)
			(copperpour not_allowed)
			(footprints allowed)
		)
		(placement
			(enabled no)
			(sheetname "")
		)
		(fill
			(thermal_gap 0.5)
			(thermal_bridge_width 0.5)
			(island_removal_mode 0)
		)
		(polygon
			(pts
				(arc
					(start 96.102678 -281.59202)
					(mid 95.444818 -281.59202)
					(end 96.102678 -281.59202)
				)
			)
		)
	)
	(zone
		(layers "F.Cu" "B.Cu" "In1.Cu" "In2.Cu" "In3.Cu" "In4.Cu" "In5.Cu" "In6.Cu"
			"In7.Cu" "In8.Cu" "In9.Cu" "In10.Cu" "In11.Cu" "In12.Cu" "In13.Cu" "In14.Cu"
			"In15.Cu" "In16.Cu"
		)
		(hatch none 0.5)
		(connect_pads
			(clearance 0)
		)
		(min_thickness 0.25)
		(keepout
			(tracks not_allowed)
			(vias allowed)
			(pads allowed)
			(copperpour not_allowed)
			(footprints allowed)
		)
		(placement
			(enabled no)
			(sheetname "")
		)
		(fill
			(thermal_gap 0.5)
			(thermal_bridge_width 0.5)
			(island_removal_mode 0)
		)
		(polygon
			(pts
				(arc
					(start 351.561146 -286.475424)
					(mid 350.903286 -286.475424)
					(end 351.561146 -286.475424)
				)
			)
		)
	)
	(zone
		(layers "F.Cu" "B.Cu" "In1.Cu" "In2.Cu" "In3.Cu" "In4.Cu" "In5.Cu" "In6.Cu"
			"In7.Cu" "In8.Cu" "In9.Cu" "In10.Cu" "In11.Cu" "In12.Cu" "In13.Cu" "In14.Cu"
			"In15.Cu" "In16.Cu"
		)
		(hatch none 0.5)
		(connect_pads
			(clearance 0)
		)
		(min_thickness 0.25)
		(keepout
			(tracks not_allowed)
			(vias allowed)
			(pads allowed)
			(copperpour not_allowed)
			(footprints allowed)
		)
		(placement
			(enabled no)
			(sheetname "")
		)
		(fill
			(thermal_gap 0.5)
			(thermal_bridge_width 0.5)
			(island_removal_mode 0)
		)
		(polygon
			(pts
				(arc
					(start 107.270296 -217.878406)
					(mid 106.612436 -217.878406)
					(end 107.270296 -217.878406)
				)
			)
		)
	)
	(zone
		(layers "F.Cu" "B.Cu" "In1.Cu" "In2.Cu" "In3.Cu" "In4.Cu" "In5.Cu" "In6.Cu"
			"In7.Cu" "In8.Cu" "In9.Cu" "In10.Cu" "In11.Cu" "In12.Cu" "In13.Cu" "In14.Cu"
			"In15.Cu" "In16.Cu"
		)
		(hatch none 0.5)
		(connect_pads
			(clearance 0)
		)
		(min_thickness 0.25)
		(keepout
			(tracks not_allowed)
			(vias allowed)
			(pads allowed)
			(copperpour not_allowed)
			(footprints allowed)
		)
		(placement
			(enabled no)
			(sheetname "")
		)
		(fill
			(thermal_gap 0.5)
			(thermal_bridge_width 0.5)
			(island_removal_mode 0)
		)
		(polygon
			(pts
				(arc
					(start 106.722418 -276.708616)
					(mid 107.380278 -276.708616)
					(end 106.722418 -276.708616)
				)
			)
		)
	)
	(zone
		(layers "F.Cu" "B.Cu" "In1.Cu" "In2.Cu" "In3.Cu" "In4.Cu" "In5.Cu" "In6.Cu"
			"In7.Cu" "In8.Cu" "In9.Cu" "In10.Cu" "In11.Cu" "In12.Cu" "In13.Cu" "In14.Cu"
			"In15.Cu" "In16.Cu"
		)
		(hatch none 0.5)
		(connect_pads
			(clearance 0)
		)
		(min_thickness 0.25)
		(keepout
			(tracks not_allowed)
			(vias allowed)
			(pads allowed)
			(copperpour not_allowed)
			(footprints allowed)
		)
		(placement
			(enabled no)
			(sheetname "")
		)
		(fill
			(thermal_gap 0.5)
			(thermal_bridge_width 0.5)
			(island_removal_mode 0)
		)
		(polygon
			(pts
				(arc
					(start 103.621078 -286.475424)
					(mid 102.963218 -286.475424)
					(end 103.621078 -286.475424)
				)
			)
		)
	)
	(zone
		(layers "F.Cu" "B.Cu" "In1.Cu" "In2.Cu" "In3.Cu" "In4.Cu" "In5.Cu" "In6.Cu"
			"In7.Cu" "In8.Cu" "In9.Cu" "In10.Cu" "In11.Cu" "In12.Cu" "In13.Cu" "In14.Cu"
			"In15.Cu" "In16.Cu"
		)
		(hatch none 0.5)
		(connect_pads
			(clearance 0)
		)
		(min_thickness 0.25)
		(keepout
			(tracks not_allowed)
			(vias allowed)
			(pads allowed)
			(copperpour not_allowed)
			(footprints allowed)
		)
		(placement
			(enabled no)
			(sheetname "")
		)
		(fill
			(thermal_gap 0.5)
			(thermal_bridge_width 0.5)
			(island_removal_mode 0)
		)
		(polygon
			(pts
				(arc
					(start 344.872564 -221.133924)
					(mid 344.214704 -221.133924)
					(end 344.872564 -221.133924)
				)
			)
		)
	)
	(zone
		(layers "F.Cu" "B.Cu" "In1.Cu" "In2.Cu" "In3.Cu" "In4.Cu" "In5.Cu" "In6.Cu"
			"In7.Cu" "In8.Cu" "In9.Cu" "In10.Cu" "In11.Cu" "In12.Cu" "In13.Cu" "In14.Cu"
			"In15.Cu" "In16.Cu"
		)
		(hatch none 0.5)
		(connect_pads
			(clearance 0)
		)
		(min_thickness 0.25)
		(keepout
			(tracks not_allowed)
			(vias allowed)
			(pads allowed)
			(copperpour not_allowed)
			(footprints allowed)
		)
		(placement
			(enabled no)
			(sheetname "")
		)
		(fill
			(thermal_gap 0.5)
			(thermal_bridge_width 0.5)
			(island_removal_mode 0)
		)
		(polygon
			(pts
				(arc
					(start 49.326038 -409.649168)
					(mid 48.945038 -410.030168)
					(end 49.326038 -410.411168)
				)
				(arc
					(start 50.189638 -410.411168)
					(mid 50.570638 -410.030168)
					(end 50.189638 -409.649168)
				)
			)
		)
	)
	(zone
		(layers "F.Cu" "B.Cu" "In1.Cu" "In2.Cu" "In3.Cu" "In4.Cu" "In5.Cu" "In6.Cu"
			"In7.Cu" "In8.Cu" "In9.Cu" "In10.Cu" "In11.Cu" "In12.Cu" "In13.Cu" "In14.Cu"
			"In15.Cu" "In16.Cu"
		)
		(hatch none 0.5)
		(connect_pads
			(clearance 0)
		)
		(min_thickness 0.25)
		(keepout
			(tracks not_allowed)
			(vias allowed)
			(pads allowed)
			(copperpour not_allowed)
			(footprints allowed)
		)
		(placement
			(enabled no)
			(sheetname "")
		)
		(fill
			(thermal_gap 0.5)
			(thermal_bridge_width 0.5)
			(island_removal_mode 0)
		)
		(polygon
			(pts
				(arc
					(start 386.73913 -403.502876)
					(mid 386.35813 -403.883876)
					(end 386.73913 -404.264876)
				)
				(arc
					(start 387.60273 -404.264876)
					(mid 387.98373 -403.883876)
					(end 387.60273 -403.502876)
				)
			)
		)
	)
	(zone
		(layers "F.Cu" "B.Cu" "In1.Cu" "In2.Cu" "In3.Cu" "In4.Cu" "In5.Cu" "In6.Cu"
			"In7.Cu" "In8.Cu" "In9.Cu" "In10.Cu" "In11.Cu" "In12.Cu" "In13.Cu" "In14.Cu"
			"In15.Cu" "In16.Cu"
		)
		(hatch none 0.5)
		(connect_pads
			(clearance 0)
		)
		(min_thickness 0.25)
		(keepout
			(tracks not_allowed)
			(vias allowed)
			(pads allowed)
			(copperpour not_allowed)
			(footprints allowed)
		)
		(placement
			(enabled no)
			(sheetname "")
		)
		(fill
			(thermal_gap 0.5)
			(thermal_bridge_width 0.5)
			(island_removal_mode 0)
		)
		(polygon
			(pts
				(arc
					(start 115.100354 -220.22181)
					(mid 115.028365 -220.149651)
					(end 114.92992 -220.123258)
				)
				(arc
					(start 114.92992 -220.123258)
					(mid 114.790726 -220.180914)
					(end 114.73307 -220.320108)
				)
				(arc
					(start 114.73307 -220.320108)
					(mid 114.739827 -220.370989)
					(end 114.759486 -220.418406)
				)
				(arc
					(start 115.229132 -221.232222)
					(mid 115.301121 -221.304381)
					(end 115.399566 -221.330774)
				)
				(arc
					(start 115.399566 -221.330774)
					(mid 115.53876 -221.273118)
					(end 115.596416 -221.133924)
				)
				(arc
					(start 115.596416 -221.133924)
					(mid 115.589659 -221.083043)
					(end 115.57 -221.035626)
				)
			)
		)
	)
	(zone
		(layers "F.Cu" "B.Cu" "In1.Cu" "In2.Cu" "In3.Cu" "In4.Cu" "In5.Cu" "In6.Cu"
			"In7.Cu" "In8.Cu" "In9.Cu" "In10.Cu" "In11.Cu" "In12.Cu" "In13.Cu" "In14.Cu"
			"In15.Cu" "In16.Cu"
		)
		(hatch none 0.5)
		(connect_pads
			(clearance 0)
		)
		(min_thickness 0.25)
		(keepout
			(tracks not_allowed)
			(vias allowed)
			(pads allowed)
			(copperpour not_allowed)
			(footprints allowed)
		)
		(placement
			(enabled no)
			(sheetname "")
		)
		(fill
			(thermal_gap 0.5)
			(thermal_bridge_width 0.5)
			(island_removal_mode 0)
		)
		(polygon
			(pts
				(arc
					(start 353.874324 -173.026832)
					(mid 354.233534 -172.878042)
					(end 354.382324 -172.518832)
				)
				(arc
					(start 354.382324 -172.518832)
					(mid 354.314267 -172.264835)
					(end 354.128324 -172.078904)
				)
				(arc
					(start 353.204272 -171.54525)
					(mid 353.081978 -171.494713)
					(end 352.95078 -171.477432)
				)
				(arc
					(start 352.950272 -171.477432)
					(mid 352.591062 -171.626222)
					(end 352.442272 -171.985432)
				)
				(arc
					(start 352.442272 -171.985432)
					(mid 352.510329 -172.239429)
					(end 352.696272 -172.42536)
				)
				(arc
					(start 353.620324 -172.959014)
					(mid 353.742618 -173.009551)
					(end 353.873816 -173.026832)
				)
			)
		)
	)
	(zone
		(layers "F.Cu" "B.Cu" "In1.Cu" "In2.Cu" "In3.Cu" "In4.Cu" "In5.Cu" "In6.Cu"
			"In7.Cu" "In8.Cu" "In9.Cu" "In10.Cu" "In11.Cu" "In12.Cu" "In13.Cu" "In14.Cu"
			"In15.Cu" "In16.Cu"
		)
		(hatch none 0.5)
		(connect_pads
			(clearance 0)
		)
		(min_thickness 0.25)
		(keepout
			(tracks not_allowed)
			(vias allowed)
			(pads allowed)
			(copperpour not_allowed)
			(footprints allowed)
		)
		(placement
			(enabled no)
			(sheetname "")
		)
		(fill
			(thermal_gap 0.5)
			(thermal_bridge_width 0.5)
			(island_removal_mode 0)
		)
		(polygon
			(pts
				(arc
					(start 423.8752 -17.220438)
					(mid 423.4942 -17.601438)
					(end 423.8752 -17.982438)
				)
				(arc
					(start 424.7388 -17.982438)
					(mid 425.1198 -17.601438)
					(end 424.7388 -17.220438)
				)
			)
		)
	)
	(zone
		(layers "F.Cu" "B.Cu" "In1.Cu" "In2.Cu" "In3.Cu" "In4.Cu" "In5.Cu" "In6.Cu"
			"In7.Cu" "In8.Cu" "In9.Cu" "In10.Cu" "In11.Cu" "In12.Cu" "In13.Cu" "In14.Cu"
			"In15.Cu" "In16.Cu"
		)
		(hatch none 0.5)
		(connect_pads
			(clearance 0)
		)
		(min_thickness 0.25)
		(keepout
			(tracks not_allowed)
			(vias allowed)
			(pads allowed)
			(copperpour not_allowed)
			(footprints allowed)
		)
		(placement
			(enabled no)
			(sheetname "")
		)
		(fill
			(thermal_gap 0.5)
			(thermal_bridge_width 0.5)
			(island_removal_mode 0)
		)
		(polygon
			(pts
				(arc
					(start 374.116346 -286.475424)
					(mid 373.458486 -286.475424)
					(end 374.116346 -286.475424)
				)
			)
		)
	)
	(zone
		(layers "F.Cu" "B.Cu" "In1.Cu" "In2.Cu" "In3.Cu" "In4.Cu" "In5.Cu" "In6.Cu"
			"In7.Cu" "In8.Cu" "In9.Cu" "In10.Cu" "In11.Cu" "In12.Cu" "In13.Cu" "In14.Cu"
			"In15.Cu" "In16.Cu"
		)
		(hatch none 0.5)
		(connect_pads
			(clearance 0)
		)
		(min_thickness 0.25)
		(keepout
			(tracks not_allowed)
			(vias allowed)
			(pads allowed)
			(copperpour not_allowed)
			(footprints allowed)
		)
		(placement
			(enabled no)
			(sheetname "")
		)
		(fill
			(thermal_gap 0.5)
			(thermal_bridge_width 0.5)
			(island_removal_mode 0)
		)
		(polygon
			(pts
				(arc
					(start 336.524092 -283.219906)
					(mid 335.866232 -283.219906)
					(end 336.524092 -283.219906)
				)
			)
		)
	)
	(zone
		(layers "F.Cu" "B.Cu" "In1.Cu" "In2.Cu" "In3.Cu" "In4.Cu" "In5.Cu" "In6.Cu"
			"In7.Cu" "In8.Cu" "In9.Cu" "In10.Cu" "In11.Cu" "In12.Cu" "In13.Cu" "In14.Cu"
			"In15.Cu" "In16.Cu"
		)
		(hatch none 0.5)
		(connect_pads
			(clearance 0)
		)
		(min_thickness 0.25)
		(keepout
			(tracks not_allowed)
			(vias allowed)
			(pads allowed)
			(copperpour not_allowed)
			(footprints allowed)
		)
		(placement
			(enabled no)
			(sheetname "")
		)
		(fill
			(thermal_gap 0.5)
			(thermal_bridge_width 0.5)
			(island_removal_mode 0)
		)
		(polygon
			(pts
				(arc
					(start 96.854264 -282.405836)
					(mid 97.512124 -282.405836)
					(end 96.854264 -282.405836)
				)
			)
		)
	)
	(zone
		(layers "F.Cu" "B.Cu" "In1.Cu" "In2.Cu" "In3.Cu" "In4.Cu" "In5.Cu" "In6.Cu"
			"In7.Cu" "In8.Cu" "In9.Cu" "In10.Cu" "In11.Cu" "In12.Cu" "In13.Cu" "In14.Cu"
			"In15.Cu" "In16.Cu"
		)
		(hatch none 0.5)
		(connect_pads
			(clearance 0)
		)
		(min_thickness 0.25)
		(keepout
			(tracks not_allowed)
			(vias allowed)
			(pads allowed)
			(copperpour not_allowed)
			(footprints allowed)
		)
		(placement
			(enabled no)
			(sheetname "")
		)
		(fill
			(thermal_gap 0.5)
			(thermal_bridge_width 0.5)
			(island_removal_mode 0)
		)
		(polygon
			(pts
				(arc
					(start 118.547896 -221.133924)
					(mid 117.890036 -221.133924)
					(end 118.547896 -221.133924)
				)
			)
		)
	)
	(zone
		(layers "F.Cu" "B.Cu" "In1.Cu" "In2.Cu" "In3.Cu" "In4.Cu" "In5.Cu" "In6.Cu"
			"In7.Cu" "In8.Cu" "In9.Cu" "In10.Cu" "In11.Cu" "In12.Cu" "In13.Cu" "In14.Cu"
			"In15.Cu" "In16.Cu"
		)
		(hatch none 0.5)
		(connect_pads
			(clearance 0)
		)
		(min_thickness 0.25)
		(keepout
			(tracks not_allowed)
			(vias allowed)
			(pads allowed)
			(copperpour not_allowed)
			(footprints allowed)
		)
		(placement
			(enabled no)
			(sheetname "")
		)
		(fill
			(thermal_gap 0.5)
			(thermal_bridge_width 0.5)
			(island_removal_mode 0)
		)
		(polygon
			(pts
				(arc
					(start 374.318022 -216.966292)
					(mid 374.246033 -216.894133)
					(end 374.147588 -216.86774)
				)
				(arc
					(start 374.147588 -216.86774)
					(mid 374.008394 -216.925396)
					(end 373.950738 -217.06459)
				)
				(arc
					(start 373.950738 -217.06459)
					(mid 373.957495 -217.115471)
					(end 373.977154 -217.162888)
				)
				(arc
					(start 374.4468 -217.976704)
					(mid 374.518789 -218.048863)
					(end 374.617234 -218.075256)
				)
				(arc
					(start 374.617234 -218.075256)
					(mid 374.756428 -218.0176)
					(end 374.814084 -217.878406)
				)
				(arc
					(start 374.814084 -217.878406)
					(mid 374.807327 -217.827525)
					(end 374.787668 -217.780108)
				)
			)
		)
	)
	(zone
		(layers "F.Cu" "B.Cu" "In1.Cu" "In2.Cu" "In3.Cu" "In4.Cu" "In5.Cu" "In6.Cu"
			"In7.Cu" "In8.Cu" "In9.Cu" "In10.Cu" "In11.Cu" "In12.Cu" "In13.Cu" "In14.Cu"
			"In15.Cu" "In16.Cu"
		)
		(hatch none 0.5)
		(connect_pads
			(clearance 0)
		)
		(min_thickness 0.25)
		(keepout
			(tracks not_allowed)
			(vias allowed)
			(pads allowed)
			(copperpour not_allowed)
			(footprints allowed)
		)
		(placement
			(enabled no)
			(sheetname "")
		)
		(fill
			(thermal_gap 0.5)
			(thermal_bridge_width 0.5)
			(island_removal_mode 0)
		)
		(polygon
			(pts
				(arc
					(start 98.183446 -223.67367)
					(mid 98.20313 -223.62626)
					(end 98.209862 -223.575372)
				)
				(arc
					(start 98.209862 -223.575372)
					(mid 98.152206 -223.436178)
					(end 98.013012 -223.378522)
				)
				(arc
					(start 98.013012 -223.378522)
					(mid 97.914581 -223.404938)
					(end 97.842578 -223.477074)
				)
				(arc
					(start 97.372932 -224.291144)
					(mid 97.353248 -224.338554)
					(end 97.346516 -224.389442)
				)
				(arc
					(start 97.346516 -224.389442)
					(mid 97.404172 -224.528636)
					(end 97.543366 -224.586292)
				)
				(arc
					(start 97.543366 -224.586292)
					(mid 97.641797 -224.559876)
					(end 97.7138 -224.48774)
				)
			)
		)
	)
	(zone
		(layers "F.Cu" "B.Cu" "In1.Cu" "In2.Cu" "In3.Cu" "In4.Cu" "In5.Cu" "In6.Cu"
			"In7.Cu" "In8.Cu" "In9.Cu" "In10.Cu" "In11.Cu" "In12.Cu" "In13.Cu" "In14.Cu"
			"In15.Cu" "In16.Cu"
		)
		(hatch none 0.5)
		(connect_pads
			(clearance 0)
		)
		(min_thickness 0.25)
		(keepout
			(tracks not_allowed)
			(vias allowed)
			(pads allowed)
			(copperpour not_allowed)
			(footprints allowed)
		)
		(placement
			(enabled no)
			(sheetname "")
		)
		(fill
			(thermal_gap 0.5)
			(thermal_bridge_width 0.5)
			(island_removal_mode 0)
		)
		(polygon
			(pts
				(arc
					(start 305.326288 -406.62352)
					(mid 304.945288 -407.00452)
					(end 305.326288 -407.38552)
				)
				(arc
					(start 306.189888 -407.38552)
					(mid 306.570888 -407.00452)
					(end 306.189888 -406.62352)
				)
			)
		)
	)
	(zone
		(layers "F.Cu" "B.Cu" "In1.Cu" "In2.Cu" "In3.Cu" "In4.Cu" "In5.Cu" "In6.Cu"
			"In7.Cu" "In8.Cu" "In9.Cu" "In10.Cu" "In11.Cu" "In12.Cu" "In13.Cu" "In14.Cu"
			"In15.Cu" "In16.Cu"
		)
		(hatch none 0.5)
		(connect_pads
			(clearance 0)
		)
		(min_thickness 0.25)
		(keepout
			(tracks not_allowed)
			(vias allowed)
			(pads allowed)
			(copperpour not_allowed)
			(footprints allowed)
		)
		(placement
			(enabled no)
			(sheetname "")
		)
		(fill
			(thermal_gap 0.5)
			(thermal_bridge_width 0.5)
			(island_removal_mode 0)
		)
		(polygon
			(pts
				(arc
					(start 345.148408 -409.649168)
					(mid 344.767408 -410.030168)
					(end 345.148408 -410.411168)
				)
				(arc
					(start 346.012008 -410.411168)
					(mid 346.393008 -410.030168)
					(end 346.012008 -409.649168)
				)
			)
		)
	)
	(zone
		(layers "F.Cu" "B.Cu" "In1.Cu" "In2.Cu" "In3.Cu" "In4.Cu" "In5.Cu" "In6.Cu"
			"In7.Cu" "In8.Cu" "In9.Cu" "In10.Cu" "In11.Cu" "In12.Cu" "In13.Cu" "In14.Cu"
			"In15.Cu" "In16.Cu"
		)
		(hatch none 0.5)
		(connect_pads
			(clearance 0)
		)
		(min_thickness 0.25)
		(keepout
			(tracks not_allowed)
			(vias allowed)
			(pads allowed)
			(copperpour not_allowed)
			(footprints allowed)
		)
		(placement
			(enabled no)
			(sheetname "")
		)
		(fill
			(thermal_gap 0.5)
			(thermal_bridge_width 0.5)
			(island_removal_mode 0)
		)
		(polygon
			(pts
				(arc
					(start 93.283278 -288.103056)
					(mid 92.625418 -288.103056)
					(end 93.283278 -288.103056)
				)
			)
		)
	)
	(zone
		(layers "F.Cu" "B.Cu" "In1.Cu" "In2.Cu" "In3.Cu" "In4.Cu" "In5.Cu" "In6.Cu"
			"In7.Cu" "In8.Cu" "In9.Cu" "In10.Cu" "In11.Cu" "In12.Cu" "In13.Cu" "In14.Cu"
			"In15.Cu" "In16.Cu"
		)
		(hatch none 0.5)
		(connect_pads
			(clearance 0)
		)
		(min_thickness 0.25)
		(keepout
			(tracks not_allowed)
			(vias allowed)
			(pads allowed)
			(copperpour not_allowed)
			(footprints allowed)
		)
		(placement
			(enabled no)
			(sheetname "")
		)
		(fill
			(thermal_gap 0.5)
			(thermal_bridge_width 0.5)
			(island_removal_mode 0)
		)
		(polygon
			(pts
				(arc
					(start 369.614704 -179.067968)
					(mid 369.763494 -179.427178)
					(end 370.122704 -179.575968)
				)
				(arc
					(start 370.123212 -179.575968)
					(mid 370.254421 -179.558731)
					(end 370.376704 -179.50815)
				)
				(arc
					(start 371.300756 -178.974496)
					(mid 371.486689 -178.78856)
					(end 371.554756 -178.534568)
				)
				(arc
					(start 371.554756 -178.534568)
					(mid 371.405966 -178.175358)
					(end 371.046756 -178.026568)
				)
				(arc
					(start 371.046248 -178.026568)
					(mid 370.915039 -178.043805)
					(end 370.792756 -178.094386)
				)
				(arc
					(start 369.868704 -178.62804)
					(mid 369.682771 -178.813976)
					(end 369.614704 -179.067968)
				)
			)
		)
	)
	(zone
		(layers "F.Cu" "B.Cu" "In1.Cu" "In2.Cu" "In3.Cu" "In4.Cu" "In5.Cu" "In6.Cu"
			"In7.Cu" "In8.Cu" "In9.Cu" "In10.Cu" "In11.Cu" "In12.Cu" "In13.Cu" "In14.Cu"
			"In15.Cu" "In16.Cu"
		)
		(hatch none 0.5)
		(connect_pads
			(clearance 0)
		)
		(min_thickness 0.25)
		(keepout
			(tracks not_allowed)
			(vias allowed)
			(pads allowed)
			(copperpour not_allowed)
			(footprints allowed)
		)
		(placement
			(enabled no)
			(sheetname "")
		)
		(fill
			(thermal_gap 0.5)
			(thermal_bridge_width 0.5)
			(island_removal_mode 0)
		)
		(polygon
			(pts
				(arc
					(start 338.873846 -285.661354)
					(mid 338.215986 -285.661354)
					(end 338.873846 -285.661354)
				)
			)
		)
	)
	(zone
		(layers "F.Cu" "B.Cu" "In1.Cu" "In2.Cu" "In3.Cu" "In4.Cu" "In5.Cu" "In6.Cu"
			"In7.Cu" "In8.Cu" "In9.Cu" "In10.Cu" "In11.Cu" "In12.Cu" "In13.Cu" "In14.Cu"
			"In15.Cu" "In16.Cu"
		)
		(hatch none 0.5)
		(connect_pads
			(clearance 0)
		)
		(min_thickness 0.25)
		(keepout
			(tracks not_allowed)
			(vias allowed)
			(pads allowed)
			(copperpour not_allowed)
			(footprints allowed)
		)
		(placement
			(enabled no)
			(sheetname "")
		)
		(fill
			(thermal_gap 0.5)
			(thermal_bridge_width 0.5)
			(island_removal_mode 0)
		)
		(polygon
			(pts
				(arc
					(start 124.108718 -288.917126)
					(mid 124.766578 -288.917126)
					(end 124.108718 -288.917126)
				)
			)
		)
	)
	(zone
		(layers "F.Cu" "B.Cu" "In1.Cu" "In2.Cu" "In3.Cu" "In4.Cu" "In5.Cu" "In6.Cu"
			"In7.Cu" "In8.Cu" "In9.Cu" "In10.Cu" "In11.Cu" "In12.Cu" "In13.Cu" "In14.Cu"
			"In15.Cu" "In16.Cu"
		)
		(hatch none 0.5)
		(connect_pads
			(clearance 0)
		)
		(min_thickness 0.25)
		(keepout
			(tracks not_allowed)
			(vias allowed)
			(pads allowed)
			(copperpour not_allowed)
			(footprints allowed)
		)
		(placement
			(enabled no)
			(sheetname "")
		)
		(fill
			(thermal_gap 0.5)
			(thermal_bridge_width 0.5)
			(island_removal_mode 0)
		)
		(polygon
			(pts
				(arc
					(start 116.97208 -213.646766)
					(mid 116.904372 -213.574915)
					(end 116.809266 -213.548468)
				)
				(arc
					(start 116.809266 -213.548468)
					(mid 116.679052 -213.602404)
					(end 116.625116 -213.732618)
				)
				(arc
					(start 116.625116 -213.732618)
					(mid 116.630567 -213.776839)
					(end 116.646452 -213.81847)
				)
				(arc
					(start 117.115844 -214.708486)
					(mid 117.183552 -214.780337)
					(end 117.278658 -214.806784)
				)
				(arc
					(start 117.278658 -214.806784)
					(mid 117.408872 -214.752848)
					(end 117.462808 -214.622634)
				)
				(arc
					(start 117.462808 -214.622634)
					(mid 117.457357 -214.578413)
					(end 117.441472 -214.536782)
				)
			)
		)
	)
	(zone
		(layers "F.Cu" "B.Cu" "In1.Cu" "In2.Cu" "In3.Cu" "In4.Cu" "In5.Cu" "In6.Cu"
			"In7.Cu" "In8.Cu" "In9.Cu" "In10.Cu" "In11.Cu" "In12.Cu" "In13.Cu" "In14.Cu"
			"In15.Cu" "In16.Cu"
		)
		(hatch none 0.5)
		(connect_pads
			(clearance 0)
		)
		(min_thickness 0.25)
		(keepout
			(tracks not_allowed)
			(vias allowed)
			(pads allowed)
			(copperpour not_allowed)
			(footprints allowed)
		)
		(placement
			(enabled no)
			(sheetname "")
		)
		(fill
			(thermal_gap 0.5)
			(thermal_bridge_width 0.5)
			(island_removal_mode 0)
		)
		(polygon
			(pts
				(arc
					(start 325.41083 -64.940434)
					(mid 325.79183 -65.321434)
					(end 326.17283 -64.940434)
				)
				(arc
					(start 326.17283 -64.076834)
					(mid 325.79183 -63.695834)
					(end 325.41083 -64.076834)
				)
			)
		)
	)
	(zone
		(layers "F.Cu" "B.Cu" "In1.Cu" "In2.Cu" "In3.Cu" "In4.Cu" "In5.Cu" "In6.Cu"
			"In7.Cu" "In8.Cu" "In9.Cu" "In10.Cu" "In11.Cu" "In12.Cu" "In13.Cu" "In14.Cu"
			"In15.Cu" "In16.Cu"
		)
		(hatch none 0.5)
		(connect_pads
			(clearance 0)
		)
		(min_thickness 0.25)
		(keepout
			(tracks not_allowed)
			(vias allowed)
			(pads allowed)
			(copperpour not_allowed)
			(footprints allowed)
		)
		(placement
			(enabled no)
			(sheetname "")
		)
		(fill
			(thermal_gap 0.5)
			(thermal_bridge_width 0.5)
			(island_removal_mode 0)
		)
		(polygon
			(pts
				(arc
					(start 130.875278 -284.847538)
					(mid 130.217418 -284.847538)
					(end 130.875278 -284.847538)
				)
			)
		)
	)
	(zone
		(layers "F.Cu" "B.Cu" "In1.Cu" "In2.Cu" "In3.Cu" "In4.Cu" "In5.Cu" "In6.Cu"
			"In7.Cu" "In8.Cu" "In9.Cu" "In10.Cu" "In11.Cu" "In12.Cu" "In13.Cu" "In14.Cu"
			"In15.Cu" "In16.Cu"
		)
		(hatch none 0.5)
		(connect_pads
			(clearance 0)
		)
		(min_thickness 0.25)
		(keepout
			(tracks not_allowed)
			(vias allowed)
			(pads allowed)
			(copperpour not_allowed)
			(footprints allowed)
		)
		(placement
			(enabled no)
			(sheetname "")
		)
		(fill
			(thermal_gap 0.5)
			(thermal_bridge_width 0.5)
			(island_removal_mode 0)
		)
		(polygon
			(pts
				(arc
					(start 348.741746 -288.103056)
					(mid 348.083886 -288.103056)
					(end 348.741746 -288.103056)
				)
			)
		)
	)
	(zone
		(layers "F.Cu" "B.Cu" "In1.Cu" "In2.Cu" "In3.Cu" "In4.Cu" "In5.Cu" "In6.Cu"
			"In7.Cu" "In8.Cu" "In9.Cu" "In10.Cu" "In11.Cu" "In12.Cu" "In13.Cu" "In14.Cu"
			"In15.Cu" "In16.Cu"
		)
		(hatch none 0.5)
		(connect_pads
			(clearance 0)
		)
		(min_thickness 0.25)
		(keepout
			(tracks not_allowed)
			(vias allowed)
			(pads allowed)
			(copperpour not_allowed)
			(footprints allowed)
		)
		(placement
			(enabled no)
			(sheetname "")
		)
		(fill
			(thermal_gap 0.5)
			(thermal_bridge_width 0.5)
			(island_removal_mode 0)
		)
		(polygon
			(pts
				(arc
					(start 131.627118 -288.917126)
					(mid 132.284978 -288.917126)
					(end 131.627118 -288.917126)
				)
			)
		)
	)
	(zone
		(layers "F.Cu" "B.Cu" "In1.Cu" "In2.Cu" "In3.Cu" "In4.Cu" "In5.Cu" "In6.Cu"
			"In7.Cu" "In8.Cu" "In9.Cu" "In10.Cu" "In11.Cu" "In12.Cu" "In13.Cu" "In14.Cu"
			"In15.Cu" "In16.Cu"
		)
		(hatch none 0.5)
		(connect_pads
			(clearance 0)
		)
		(min_thickness 0.25)
		(keepout
			(tracks not_allowed)
			(vias allowed)
			(pads allowed)
			(copperpour not_allowed)
			(footprints allowed)
		)
		(placement
			(enabled no)
			(sheetname "")
		)
		(fill
			(thermal_gap 0.5)
			(thermal_bridge_width 0.5)
			(island_removal_mode 0)
		)
		(polygon
			(pts
				(arc
					(start 351.762314 -217.162634)
					(mid 351.781998 -217.115224)
					(end 351.78873 -217.064336)
				)
				(arc
					(start 351.78873 -217.064336)
					(mid 351.731074 -216.925142)
					(end 351.59188 -216.867486)
				)
				(arc
					(start 351.59188 -216.867486)
					(mid 351.493449 -216.893902)
					(end 351.421446 -216.966038)
				)
				(arc
					(start 350.9518 -217.780108)
					(mid 350.932116 -217.827518)
					(end 350.925384 -217.878406)
				)
				(arc
					(start 350.925384 -217.878406)
					(mid 350.98304 -218.0176)
					(end 351.122234 -218.075256)
				)
				(arc
					(start 351.122234 -218.075256)
					(mid 351.220665 -218.04884)
					(end 351.292668 -217.976704)
				)
			)
		)
	)
	(zone
		(layers "F.Cu" "B.Cu" "In1.Cu" "In2.Cu" "In3.Cu" "In4.Cu" "In5.Cu" "In6.Cu"
			"In7.Cu" "In8.Cu" "In9.Cu" "In10.Cu" "In11.Cu" "In12.Cu" "In13.Cu" "In14.Cu"
			"In15.Cu" "In16.Cu"
		)
		(hatch none 0.5)
		(connect_pads
			(clearance 0)
		)
		(min_thickness 0.25)
		(keepout
			(tracks not_allowed)
			(vias allowed)
			(pads allowed)
			(copperpour not_allowed)
			(footprints allowed)
		)
		(placement
			(enabled no)
			(sheetname "")
		)
		(fill
			(thermal_gap 0.5)
			(thermal_bridge_width 0.5)
			(island_removal_mode 0)
		)
		(polygon
			(pts
				(arc
					(start 130.690874 -406.62352)
					(mid 130.309874 -407.00452)
					(end 130.690874 -407.38552)
				)
				(arc
					(start 131.554474 -407.38552)
					(mid 131.935474 -407.00452)
					(end 131.554474 -406.62352)
				)
			)
		)
	)
	(zone
		(layers "F.Cu" "B.Cu" "In1.Cu" "In2.Cu" "In3.Cu" "In4.Cu" "In5.Cu" "In6.Cu"
			"In7.Cu" "In8.Cu" "In9.Cu" "In10.Cu" "In11.Cu" "In12.Cu" "In13.Cu" "In14.Cu"
			"In15.Cu" "In16.Cu"
		)
		(hatch none 0.5)
		(connect_pads
			(clearance 0)
		)
		(min_thickness 0.25)
		(keepout
			(tracks not_allowed)
			(vias allowed)
			(pads allowed)
			(copperpour not_allowed)
			(footprints allowed)
		)
		(placement
			(enabled no)
			(sheetname "")
		)
		(fill
			(thermal_gap 0.5)
			(thermal_bridge_width 0.5)
			(island_removal_mode 0)
		)
		(polygon
			(pts
				(arc
					(start 341.58301 -221.94774)
					(mid 340.92515 -221.94774)
					(end 341.58301 -221.94774)
				)
			)
		)
	)
	(zone
		(layers "F.Cu" "B.Cu" "In1.Cu" "In2.Cu" "In3.Cu" "In4.Cu" "In5.Cu" "In6.Cu"
			"In7.Cu" "In8.Cu" "In9.Cu" "In10.Cu" "In11.Cu" "In12.Cu" "In13.Cu" "In14.Cu"
			"In15.Cu" "In16.Cu"
		)
		(hatch none 0.5)
		(connect_pads
			(clearance 0)
		)
		(min_thickness 0.25)
		(keepout
			(tracks not_allowed)
			(vias allowed)
			(pads allowed)
			(copperpour not_allowed)
			(footprints allowed)
		)
		(placement
			(enabled no)
			(sheetname "")
		)
		(fill
			(thermal_gap 0.5)
			(thermal_bridge_width 0.5)
			(island_removal_mode 0)
		)
		(polygon
			(pts
				(arc
					(start 130.136646 -223.67367)
					(mid 130.15633 -223.62626)
					(end 130.163062 -223.575372)
				)
				(arc
					(start 130.163062 -223.575372)
					(mid 130.105406 -223.436178)
					(end 129.966212 -223.378522)
				)
				(arc
					(start 129.966212 -223.378522)
					(mid 129.867781 -223.404938)
					(end 129.795778 -223.477074)
				)
				(arc
					(start 129.326132 -224.291144)
					(mid 129.306448 -224.338554)
					(end 129.299716 -224.389442)
				)
				(arc
					(start 129.299716 -224.389442)
					(mid 129.357372 -224.528636)
					(end 129.496566 -224.586292)
				)
				(arc
					(start 129.496566 -224.586292)
					(mid 129.594997 -224.559876)
					(end 129.667 -224.48774)
				)
			)
		)
	)
	(zone
		(layers "F.Cu" "B.Cu" "In1.Cu" "In2.Cu" "In3.Cu" "In4.Cu" "In5.Cu" "In6.Cu"
			"In7.Cu" "In8.Cu" "In9.Cu" "In10.Cu" "In11.Cu" "In12.Cu" "In13.Cu" "In14.Cu"
			"In15.Cu" "In16.Cu"
		)
		(hatch none 0.5)
		(connect_pads
			(clearance 0)
		)
		(min_thickness 0.25)
		(keepout
			(tracks not_allowed)
			(vias allowed)
			(pads allowed)
			(copperpour not_allowed)
			(footprints allowed)
		)
		(placement
			(enabled no)
			(sheetname "")
		)
		(fill
			(thermal_gap 0.5)
			(thermal_bridge_width 0.5)
			(island_removal_mode 0)
		)
		(polygon
			(pts
				(arc
					(start 32.297878 -17.23136)
					(mid 31.916878 -17.61236)
					(end 32.297878 -17.99336)
				)
				(arc
					(start 33.161478 -17.99336)
					(mid 33.542478 -17.61236)
					(end 33.161478 -17.23136)
				)
			)
		)
	)
	(zone
		(layers "F.Cu" "B.Cu" "In1.Cu" "In2.Cu" "In3.Cu" "In4.Cu" "In5.Cu" "In6.Cu"
			"In7.Cu" "In8.Cu" "In9.Cu" "In10.Cu" "In11.Cu" "In12.Cu" "In13.Cu" "In14.Cu"
			"In15.Cu" "In16.Cu"
		)
		(hatch none 0.5)
		(connect_pads
			(clearance 0)
		)
		(min_thickness 0.25)
		(keepout
			(tracks not_allowed)
			(vias allowed)
			(pads allowed)
			(copperpour not_allowed)
			(footprints allowed)
		)
		(placement
			(enabled no)
			(sheetname "")
		)
		(fill
			(thermal_gap 0.5)
			(thermal_bridge_width 0.5)
			(island_removal_mode 0)
		)
		(polygon
			(pts
				(arc
					(start 125.878082 -220.319854)
					(mid 126.535942 -220.319854)
					(end 125.878082 -220.319854)
				)
			)
		)
	)
	(zone
		(layers "F.Cu" "B.Cu" "In1.Cu" "In2.Cu" "In3.Cu" "In4.Cu" "In5.Cu" "In6.Cu"
			"In7.Cu" "In8.Cu" "In9.Cu" "In10.Cu" "In11.Cu" "In12.Cu" "In13.Cu" "In14.Cu"
			"In15.Cu" "In16.Cu"
		)
		(hatch none 0.5)
		(connect_pads
			(clearance 0)
		)
		(min_thickness 0.25)
		(keepout
			(tracks not_allowed)
			(vias allowed)
			(pads allowed)
			(copperpour not_allowed)
			(footprints allowed)
		)
		(placement
			(enabled no)
			(sheetname "")
		)
		(fill
			(thermal_gap 0.5)
			(thermal_bridge_width 0.5)
			(island_removal_mode 0)
		)
		(polygon
			(pts
				(arc
					(start 398.99209 -400.477228)
					(mid 398.61109 -400.858228)
					(end 398.99209 -401.239228)
				)
				(arc
					(start 399.85569 -401.239228)
					(mid 400.23669 -400.858228)
					(end 399.85569 -400.477228)
				)
			)
		)
	)
	(zone
		(layers "F.Cu" "B.Cu" "In1.Cu" "In2.Cu" "In3.Cu" "In4.Cu" "In5.Cu" "In6.Cu"
			"In7.Cu" "In8.Cu" "In9.Cu" "In10.Cu" "In11.Cu" "In12.Cu" "In13.Cu" "In14.Cu"
			"In15.Cu" "In16.Cu"
		)
		(hatch none 0.5)
		(connect_pads
			(clearance 0)
		)
		(min_thickness 0.25)
		(keepout
			(tracks not_allowed)
			(vias allowed)
			(pads allowed)
			(copperpour not_allowed)
			(footprints allowed)
		)
		(placement
			(enabled no)
			(sheetname "")
		)
		(fill
			(thermal_gap 0.5)
			(thermal_bridge_width 0.5)
			(island_removal_mode 0)
		)
		(polygon
			(pts
				(arc
					(start 375.83237 -406.62352)
					(mid 375.45137 -407.00452)
					(end 375.83237 -407.38552)
				)
				(arc
					(start 376.69597 -407.38552)
					(mid 377.07697 -407.00452)
					(end 376.69597 -406.62352)
				)
			)
		)
	)
	(zone
		(layers "F.Cu" "B.Cu" "In1.Cu" "In2.Cu" "In3.Cu" "In4.Cu" "In5.Cu" "In6.Cu"
			"In7.Cu" "In8.Cu" "In9.Cu" "In10.Cu" "In11.Cu" "In12.Cu" "In13.Cu" "In14.Cu"
			"In15.Cu" "In16.Cu"
		)
		(hatch none 0.5)
		(connect_pads
			(clearance 0)
		)
		(min_thickness 0.25)
		(keepout
			(tracks not_allowed)
			(vias allowed)
			(pads allowed)
			(copperpour not_allowed)
			(footprints allowed)
		)
		(placement
			(enabled no)
			(sheetname "")
		)
		(fill
			(thermal_gap 0.5)
			(thermal_bridge_width 0.5)
			(island_removal_mode 0)
		)
		(polygon
			(pts
				(arc
					(start 127.116078 -284.847538)
					(mid 126.458218 -284.847538)
					(end 127.116078 -284.847538)
				)
			)
		)
	)
	(zone
		(layers "F.Cu" "B.Cu" "In1.Cu" "In2.Cu" "In3.Cu" "In4.Cu" "In5.Cu" "In6.Cu"
			"In7.Cu" "In8.Cu" "In9.Cu" "In10.Cu" "In11.Cu" "In12.Cu" "In13.Cu" "In14.Cu"
			"In15.Cu" "In16.Cu"
		)
		(hatch none 0.5)
		(connect_pads
			(clearance 0)
		)
		(min_thickness 0.25)
		(keepout
			(tracks not_allowed)
			(vias allowed)
			(pads allowed)
			(copperpour not_allowed)
			(footprints allowed)
		)
		(placement
			(enabled no)
			(sheetname "")
		)
		(fill
			(thermal_gap 0.5)
			(thermal_bridge_width 0.5)
			(island_removal_mode 0)
		)
		(polygon
			(pts
				(arc
					(start 129.666492 -221.231968)
					(mid 129.686176 -221.184558)
					(end 129.692908 -221.13367)
				)
				(arc
					(start 129.692908 -221.13367)
					(mid 129.635252 -220.994476)
					(end 129.496058 -220.93682)
				)
				(arc
					(start 129.496058 -220.93682)
					(mid 129.397627 -220.963236)
					(end 129.325624 -221.035372)
				)
				(arc
					(start 128.855978 -221.849442)
					(mid 128.836294 -221.896852)
					(end 128.829562 -221.94774)
				)
				(arc
					(start 128.829562 -221.94774)
					(mid 128.887218 -222.086934)
					(end 129.026412 -222.14459)
				)
				(arc
					(start 129.026412 -222.14459)
					(mid 129.124843 -222.118174)
					(end 129.196846 -222.046038)
				)
			)
		)
	)
	(zone
		(layers "F.Cu" "B.Cu" "In1.Cu" "In2.Cu" "In3.Cu" "In4.Cu" "In5.Cu" "In6.Cu"
			"In7.Cu" "In8.Cu" "In9.Cu" "In10.Cu" "In11.Cu" "In12.Cu" "In13.Cu" "In14.Cu"
			"In15.Cu" "In16.Cu"
		)
		(hatch none 0.5)
		(connect_pads
			(clearance 0)
		)
		(min_thickness 0.25)
		(keepout
			(tracks not_allowed)
			(vias allowed)
			(pads allowed)
			(copperpour not_allowed)
			(footprints allowed)
		)
		(placement
			(enabled no)
			(sheetname "")
		)
		(fill
			(thermal_gap 0.5)
			(thermal_bridge_width 0.5)
			(island_removal_mode 0)
		)
		(polygon
			(pts
				(xy 711.622148 -388.695946) (xy 706.622158 -388.695946) (xy 706.926958 -388.391146) (xy 711.317348 -388.391146)
			)
		)
	)
	(zone
		(layers "F.Cu" "B.Cu" "In1.Cu" "In2.Cu" "In3.Cu" "In4.Cu" "In5.Cu" "In6.Cu"
			"In7.Cu" "In8.Cu" "In9.Cu" "In10.Cu" "In11.Cu" "In12.Cu" "In13.Cu" "In14.Cu"
			"In15.Cu" "In16.Cu"
		)
		(hatch none 0.5)
		(connect_pads
			(clearance 0)
		)
		(min_thickness 0.25)
		(keepout
			(tracks not_allowed)
			(vias allowed)
			(pads allowed)
			(copperpour not_allowed)
			(footprints allowed)
		)
		(placement
			(enabled no)
			(sheetname "")
		)
		(fill
			(thermal_gap 0.5)
			(thermal_bridge_width 0.5)
			(island_removal_mode 0)
		)
		(polygon
			(pts
				(arc
					(start 351.701862 -282.208986)
					(mid 351.505012 -282.405836)
					(end 351.701862 -282.602686)
				)
				(arc
					(start 352.641662 -282.602686)
					(mid 352.838512 -282.405836)
					(end 352.641662 -282.208986)
				)
			)
		)
	)
	(zone
		(layers "F.Cu" "B.Cu" "In1.Cu" "In2.Cu" "In3.Cu" "In4.Cu" "In5.Cu" "In6.Cu"
			"In7.Cu" "In8.Cu" "In9.Cu" "In10.Cu" "In11.Cu" "In12.Cu" "In13.Cu" "In14.Cu"
			"In15.Cu" "In16.Cu"
		)
		(hatch none 0.5)
		(connect_pads
			(clearance 0)
		)
		(min_thickness 0.25)
		(keepout
			(tracks not_allowed)
			(vias allowed)
			(pads allowed)
			(copperpour not_allowed)
			(footprints allowed)
		)
		(placement
			(enabled no)
			(sheetname "")
		)
		(fill
			(thermal_gap 0.5)
			(thermal_bridge_width 0.5)
			(island_removal_mode 0)
		)
		(polygon
			(pts
				(arc
					(start 378.186696 -285.759652)
					(mid 378.20638 -285.712242)
					(end 378.213112 -285.661354)
				)
				(arc
					(start 378.213112 -285.661354)
					(mid 378.155456 -285.52216)
					(end 378.016262 -285.464504)
				)
				(arc
					(start 378.016262 -285.464504)
					(mid 377.917831 -285.49092)
					(end 377.845828 -285.563056)
				)
				(arc
					(start 377.376182 -286.377126)
					(mid 377.356498 -286.424536)
					(end 377.349766 -286.475424)
				)
				(arc
					(start 377.349766 -286.475424)
					(mid 377.407422 -286.614618)
					(end 377.546616 -286.672274)
				)
				(arc
					(start 377.546616 -286.672274)
					(mid 377.645047 -286.645858)
					(end 377.71705 -286.573722)
				)
			)
		)
	)
	(zone
		(layers "F.Cu" "B.Cu" "In1.Cu" "In2.Cu" "In3.Cu" "In4.Cu" "In5.Cu" "In6.Cu"
			"In7.Cu" "In8.Cu" "In9.Cu" "In10.Cu" "In11.Cu" "In12.Cu" "In13.Cu" "In14.Cu"
			"In15.Cu" "In16.Cu"
		)
		(hatch none 0.5)
		(connect_pads
			(clearance 0)
		)
		(min_thickness 0.25)
		(keepout
			(tracks not_allowed)
			(vias allowed)
			(pads allowed)
			(copperpour not_allowed)
			(footprints allowed)
		)
		(placement
			(enabled no)
			(sheetname "")
		)
		(fill
			(thermal_gap 0.5)
			(thermal_bridge_width 0.5)
			(island_removal_mode 0)
		)
		(polygon
			(pts
				(arc
					(start 121.477278 -288.103056)
					(mid 120.819418 -288.103056)
					(end 121.477278 -288.103056)
				)
			)
		)
	)
	(zone
		(layers "F.Cu" "B.Cu" "In1.Cu" "In2.Cu" "In3.Cu" "In4.Cu" "In5.Cu" "In6.Cu"
			"In7.Cu" "In8.Cu" "In9.Cu" "In10.Cu" "In11.Cu" "In12.Cu" "In13.Cu" "In14.Cu"
			"In15.Cu" "In16.Cu"
		)
		(hatch none 0.5)
		(connect_pads
			(clearance 0)
		)
		(min_thickness 0.25)
		(keepout
			(tracks not_allowed)
			(vias allowed)
			(pads allowed)
			(copperpour not_allowed)
			(footprints allowed)
		)
		(placement
			(enabled no)
			(sheetname "")
		)
		(fill
			(thermal_gap 0.5)
			(thermal_bridge_width 0.5)
			(island_removal_mode 0)
		)
		(polygon
			(pts
				(arc
					(start 338.13496 -214.720932)
					(mid 338.154644 -214.673522)
					(end 338.161376 -214.622634)
				)
				(arc
					(start 338.161376 -214.622634)
					(mid 338.10372 -214.48344)
					(end 337.964526 -214.425784)
				)
				(arc
					(start 337.964526 -214.425784)
					(mid 337.866095 -214.4522)
					(end 337.794092 -214.524336)
				)
				(arc
					(start 337.324446 -215.338406)
					(mid 337.304762 -215.385816)
					(end 337.29803 -215.436704)
				)
				(arc
					(start 337.29803 -215.436704)
					(mid 337.355686 -215.575898)
					(end 337.49488 -215.633554)
				)
				(arc
					(start 337.49488 -215.633554)
					(mid 337.593311 -215.607138)
					(end 337.665314 -215.535002)
				)
			)
		)
	)
	(zone
		(layers "F.Cu" "B.Cu" "In1.Cu" "In2.Cu" "In3.Cu" "In4.Cu" "In5.Cu" "In6.Cu"
			"In7.Cu" "In8.Cu" "In9.Cu" "In10.Cu" "In11.Cu" "In12.Cu" "In13.Cu" "In14.Cu"
			"In15.Cu" "In16.Cu"
		)
		(hatch none 0.5)
		(connect_pads
			(clearance 0)
		)
		(min_thickness 0.25)
		(keepout
			(tracks not_allowed)
			(vias allowed)
			(pads allowed)
			(copperpour not_allowed)
			(footprints allowed)
		)
		(placement
			(enabled no)
			(sheetname "")
		)
		(fill
			(thermal_gap 0.5)
			(thermal_bridge_width 0.5)
			(island_removal_mode 0)
		)
		(polygon
			(pts
				(arc
					(start 69.422518 -400.477228)
					(mid 69.041518 -400.858228)
					(end 69.422518 -401.239228)
				)
				(arc
					(start 70.286118 -401.239228)
					(mid 70.667118 -400.858228)
					(end 70.286118 -400.477228)
				)
			)
		)
	)
	(zone
		(layers "F.Cu" "B.Cu" "In1.Cu" "In2.Cu" "In3.Cu" "In4.Cu" "In5.Cu" "In6.Cu"
			"In7.Cu" "In8.Cu" "In9.Cu" "In10.Cu" "In11.Cu" "In12.Cu" "In13.Cu" "In14.Cu"
			"In15.Cu" "In16.Cu"
		)
		(hatch none 0.5)
		(connect_pads
			(clearance 0)
		)
		(min_thickness 0.25)
		(keepout
			(tracks not_allowed)
			(vias allowed)
			(pads allowed)
			(copperpour not_allowed)
			(footprints allowed)
		)
		(placement
			(enabled no)
			(sheetname "")
		)
		(fill
			(thermal_gap 0.5)
			(thermal_bridge_width 0.5)
			(island_removal_mode 0)
		)
		(polygon
			(pts
				(arc
					(start 106.252264 -280.778204)
					(mid 106.910124 -280.778204)
					(end 106.252264 -280.778204)
				)
			)
		)
	)
	(zone
		(layers "F.Cu" "B.Cu" "In1.Cu" "In2.Cu" "In3.Cu" "In4.Cu" "In5.Cu" "In6.Cu"
			"In7.Cu" "In8.Cu" "In9.Cu" "In10.Cu" "In11.Cu" "In12.Cu" "In13.Cu" "In14.Cu"
			"In15.Cu" "In16.Cu"
		)
		(hatch none 0.5)
		(connect_pads
			(clearance 0)
		)
		(min_thickness 0.25)
		(keepout
			(tracks not_allowed)
			(vias allowed)
			(pads allowed)
			(copperpour not_allowed)
			(footprints allowed)
		)
		(placement
			(enabled no)
			(sheetname "")
		)
		(fill
			(thermal_gap 0.5)
			(thermal_bridge_width 0.5)
			(island_removal_mode 0)
		)
		(polygon
			(pts
				(arc
					(start 111.340646 -217.162634)
					(mid 111.36033 -217.115224)
					(end 111.367062 -217.064336)
				)
				(arc
					(start 111.367062 -217.064336)
					(mid 111.309406 -216.925142)
					(end 111.170212 -216.867486)
				)
				(arc
					(start 111.170212 -216.867486)
					(mid 111.071781 -216.893902)
					(end 110.999778 -216.966038)
				)
				(arc
					(start 110.530132 -217.780108)
					(mid 110.510448 -217.827518)
					(end 110.503716 -217.878406)
				)
				(arc
					(start 110.503716 -217.878406)
					(mid 110.561372 -218.0176)
					(end 110.700566 -218.075256)
				)
				(arc
					(start 110.700566 -218.075256)
					(mid 110.798997 -218.04884)
					(end 110.871 -217.976704)
				)
			)
		)
	)
	(zone
		(layers "F.Cu" "B.Cu" "In1.Cu" "In2.Cu" "In3.Cu" "In4.Cu" "In5.Cu" "In6.Cu"
			"In7.Cu" "In8.Cu" "In9.Cu" "In10.Cu" "In11.Cu" "In12.Cu" "In13.Cu" "In14.Cu"
			"In15.Cu" "In16.Cu"
		)
		(hatch none 0.5)
		(connect_pads
			(clearance 0)
		)
		(min_thickness 0.25)
		(keepout
			(tracks not_allowed)
			(vias allowed)
			(pads allowed)
			(copperpour not_allowed)
			(footprints allowed)
		)
		(placement
			(enabled no)
			(sheetname "")
		)
		(fill
			(thermal_gap 0.5)
			(thermal_bridge_width 0.5)
			(island_removal_mode 0)
		)
		(polygon
			(pts
				(arc
					(start 307.043328 -400.477228)
					(mid 306.662328 -400.858228)
					(end 307.043328 -401.239228)
				)
				(arc
					(start 307.906928 -401.239228)
					(mid 308.287928 -400.858228)
					(end 307.906928 -400.477228)
				)
			)
		)
	)
	(zone
		(layers "F.Cu" "B.Cu" "In1.Cu" "In2.Cu" "In3.Cu" "In4.Cu" "In5.Cu" "In6.Cu"
			"In7.Cu" "In8.Cu" "In9.Cu" "In10.Cu" "In11.Cu" "In12.Cu" "In13.Cu" "In14.Cu"
			"In15.Cu" "In16.Cu"
		)
		(hatch none 0.5)
		(connect_pads
			(clearance 0)
		)
		(min_thickness 0.25)
		(keepout
			(tracks not_allowed)
			(vias allowed)
			(pads allowed)
			(copperpour not_allowed)
			(footprints allowed)
		)
		(placement
			(enabled no)
			(sheetname "")
		)
		(fill
			(thermal_gap 0.5)
			(thermal_bridge_width 0.5)
			(island_removal_mode 0)
		)
		(polygon
			(pts
				(arc
					(start 95.833692 -214.720932)
					(mid 95.853376 -214.673522)
					(end 95.860108 -214.622634)
				)
				(arc
					(start 95.860108 -214.622634)
					(mid 95.802452 -214.48344)
					(end 95.663258 -214.425784)
				)
				(arc
					(start 95.663258 -214.425784)
					(mid 95.564827 -214.4522)
					(end 95.492824 -214.524336)
				)
				(arc
					(start 95.023178 -215.338406)
					(mid 95.003494 -215.385816)
					(end 94.996762 -215.436704)
				)
				(arc
					(start 94.996762 -215.436704)
					(mid 95.054418 -215.575898)
					(end 95.193612 -215.633554)
				)
				(arc
					(start 95.193612 -215.633554)
					(mid 95.292043 -215.607138)
					(end 95.364046 -215.535002)
				)
			)
		)
	)
	(zone
		(layers "F.Cu" "B.Cu" "In1.Cu" "In2.Cu" "In3.Cu" "In4.Cu" "In5.Cu" "In6.Cu"
			"In7.Cu" "In8.Cu" "In9.Cu" "In10.Cu" "In11.Cu" "In12.Cu" "In13.Cu" "In14.Cu"
			"In15.Cu" "In16.Cu"
		)
		(hatch none 0.5)
		(connect_pads
			(clearance 0)
		)
		(min_thickness 0.25)
		(keepout
			(tracks not_allowed)
			(vias allowed)
			(pads allowed)
			(copperpour not_allowed)
			(footprints allowed)
		)
		(placement
			(enabled no)
			(sheetname "")
		)
		(fill
			(thermal_gap 0.5)
			(thermal_bridge_width 0.5)
			(island_removal_mode 0)
		)
		(polygon
			(pts
				(arc
					(start 242.68938 -52.03825)
					(mid 242.30838 -51.65725)
					(end 241.92738 -52.03825)
				)
				(arc
					(start 241.92738 -52.90185)
					(mid 242.30838 -53.28285)
					(end 242.68938 -52.90185)
				)
			)
		)
	)
	(zone
		(layers "F.Cu" "B.Cu" "In1.Cu" "In2.Cu" "In3.Cu" "In4.Cu" "In5.Cu" "In6.Cu"
			"In7.Cu" "In8.Cu" "In9.Cu" "In10.Cu" "In11.Cu" "In12.Cu" "In13.Cu" "In14.Cu"
			"In15.Cu" "In16.Cu"
		)
		(hatch none 0.5)
		(connect_pads
			(clearance 0)
		)
		(min_thickness 0.25)
		(keepout
			(tracks not_allowed)
			(vias allowed)
			(pads allowed)
			(copperpour not_allowed)
			(footprints allowed)
		)
		(placement
			(enabled no)
			(sheetname "")
		)
		(fill
			(thermal_gap 0.5)
			(thermal_bridge_width 0.5)
			(island_removal_mode 0)
		)
		(polygon
			(pts
				(arc
					(start 351.402396 -276.610064)
					(mid 351.330407 -276.537905)
					(end 351.231962 -276.511512)
				)
				(arc
					(start 351.231962 -276.511512)
					(mid 351.092768 -276.569168)
					(end 351.035112 -276.708362)
				)
				(arc
					(start 351.035112 -276.708362)
					(mid 351.041869 -276.759243)
					(end 351.061528 -276.80666)
				)
				(arc
					(start 351.531428 -277.62073)
					(mid 351.603417 -277.692889)
					(end 351.701862 -277.719282)
				)
				(arc
					(start 351.701862 -277.719282)
					(mid 351.841056 -277.661626)
					(end 351.898712 -277.522432)
				)
				(arc
					(start 351.898712 -277.522432)
					(mid 351.891955 -277.471551)
					(end 351.872296 -277.424134)
				)
			)
		)
	)
	(zone
		(layers "F.Cu" "B.Cu" "In1.Cu" "In2.Cu" "In3.Cu" "In4.Cu" "In5.Cu" "In6.Cu"
			"In7.Cu" "In8.Cu" "In9.Cu" "In10.Cu" "In11.Cu" "In12.Cu" "In13.Cu" "In14.Cu"
			"In15.Cu" "In16.Cu"
		)
		(hatch none 0.5)
		(connect_pads
			(clearance 0)
		)
		(min_thickness 0.25)
		(keepout
			(tracks not_allowed)
			(vias allowed)
			(pads allowed)
			(copperpour not_allowed)
			(footprints allowed)
		)
		(placement
			(enabled no)
			(sheetname "")
		)
		(fill
			(thermal_gap 0.5)
			(thermal_bridge_width 0.5)
			(island_removal_mode 0)
		)
		(polygon
			(pts
				(arc
					(start 359.1433 -46.421802)
					(mid 358.7623 -46.802802)
					(end 359.1433 -47.183802)
				)
				(arc
					(start 360.0069 -47.183802)
					(mid 360.3879 -46.802802)
					(end 360.0069 -46.421802)
				)
			)
		)
	)
	(zone
		(layers "F.Cu" "B.Cu" "In1.Cu" "In2.Cu" "In3.Cu" "In4.Cu" "In5.Cu" "In6.Cu"
			"In7.Cu" "In8.Cu" "In9.Cu" "In10.Cu" "In11.Cu" "In12.Cu" "In13.Cu" "In14.Cu"
			"In15.Cu" "In16.Cu"
		)
		(hatch none 0.5)
		(connect_pads
			(clearance 0)
		)
		(min_thickness 0.25)
		(keepout
			(tracks not_allowed)
			(vias allowed)
			(pads allowed)
			(copperpour not_allowed)
			(footprints allowed)
		)
		(placement
			(enabled no)
			(sheetname "")
		)
		(fill
			(thermal_gap 0.5)
			(thermal_bridge_width 0.5)
			(island_removal_mode 0)
		)
		(polygon
			(pts
				(arc
					(start 184.37098 -66.06794)
					(mid 178.86299 -60.55995)
					(end 173.355 -66.06794)
				)
				(arc
					(start 173.355 -74.767948)
					(mid 178.86299 -80.275938)
					(end 184.37098 -74.767948)
				)
			)
		)
	)
	(zone
		(layers "F.Cu" "B.Cu" "In1.Cu" "In2.Cu" "In3.Cu" "In4.Cu" "In5.Cu" "In6.Cu"
			"In7.Cu" "In8.Cu" "In9.Cu" "In10.Cu" "In11.Cu" "In12.Cu" "In13.Cu" "In14.Cu"
			"In15.Cu" "In16.Cu"
		)
		(hatch none 0.5)
		(connect_pads
			(clearance 0)
		)
		(min_thickness 0.25)
		(keepout
			(tracks not_allowed)
			(vias allowed)
			(pads allowed)
			(copperpour not_allowed)
			(footprints allowed)
		)
		(placement
			(enabled no)
			(sheetname "")
		)
		(fill
			(thermal_gap 0.5)
			(thermal_bridge_width 0.5)
			(island_removal_mode 0)
		)
		(polygon
			(pts
				(arc
					(start 103.432864 -285.661354)
					(mid 104.090724 -285.661354)
					(end 103.432864 -285.661354)
				)
			)
		)
	)
	(zone
		(layers "F.Cu" "B.Cu" "In1.Cu" "In2.Cu" "In3.Cu" "In4.Cu" "In5.Cu" "In6.Cu"
			"In7.Cu" "In8.Cu" "In9.Cu" "In10.Cu" "In11.Cu" "In12.Cu" "In13.Cu" "In14.Cu"
			"In15.Cu" "In16.Cu"
		)
		(hatch none 0.5)
		(connect_pads
			(clearance 0)
		)
		(min_thickness 0.25)
		(keepout
			(tracks not_allowed)
			(vias allowed)
			(pads allowed)
			(copperpour not_allowed)
			(footprints allowed)
		)
		(placement
			(enabled no)
			(sheetname "")
		)
		(fill
			(thermal_gap 0.5)
			(thermal_bridge_width 0.5)
			(island_removal_mode 0)
		)
		(polygon
			(pts
				(arc
					(start 361.160822 -216.966292)
					(mid 361.088833 -216.894133)
					(end 360.990388 -216.86774)
				)
				(arc
					(start 360.990388 -216.86774)
					(mid 360.851194 -216.925396)
					(end 360.793538 -217.06459)
				)
				(arc
					(start 360.793538 -217.06459)
					(mid 360.800295 -217.115471)
					(end 360.819954 -217.162888)
				)
				(arc
					(start 361.2896 -217.976704)
					(mid 361.361589 -218.048863)
					(end 361.460034 -218.075256)
				)
				(arc
					(start 361.460034 -218.075256)
					(mid 361.599228 -218.0176)
					(end 361.656884 -217.878406)
				)
				(arc
					(start 361.656884 -217.878406)
					(mid 361.650127 -217.827525)
					(end 361.630468 -217.780108)
				)
			)
		)
	)
	(zone
		(layers "F.Cu" "B.Cu" "In1.Cu" "In2.Cu" "In3.Cu" "In4.Cu" "In5.Cu" "In6.Cu"
			"In7.Cu" "In8.Cu" "In9.Cu" "In10.Cu" "In11.Cu" "In12.Cu" "In13.Cu" "In14.Cu"
			"In15.Cu" "In16.Cu"
		)
		(hatch none 0.5)
		(connect_pads
			(clearance 0)
		)
		(min_thickness 0.25)
		(keepout
			(tracks not_allowed)
			(vias allowed)
			(pads allowed)
			(copperpour not_allowed)
			(footprints allowed)
		)
		(placement
			(enabled no)
			(sheetname "")
		)
		(fill
			(thermal_gap 0.5)
			(thermal_bridge_width 0.5)
			(island_removal_mode 0)
		)
		(polygon
			(pts
				(arc
					(start 133.396736 -220.319854)
					(mid 134.054596 -220.319854)
					(end 133.396736 -220.319854)
				)
			)
		)
	)
	(zone
		(layers "F.Cu" "B.Cu" "In1.Cu" "In2.Cu" "In3.Cu" "In4.Cu" "In5.Cu" "In6.Cu"
			"In7.Cu" "In8.Cu" "In9.Cu" "In10.Cu" "In11.Cu" "In12.Cu" "In13.Cu" "In14.Cu"
			"In15.Cu" "In16.Cu"
		)
		(hatch none 0.5)
		(connect_pads
			(clearance 0)
		)
		(min_thickness 0.25)
		(keepout
			(tracks not_allowed)
			(vias allowed)
			(pads allowed)
			(copperpour not_allowed)
			(footprints allowed)
		)
		(placement
			(enabled no)
			(sheetname "")
		)
		(fill
			(thermal_gap 0.5)
			(thermal_bridge_width 0.5)
			(island_removal_mode 0)
		)
		(polygon
			(pts
				(arc
					(start 108.210096 -221.133924)
					(mid 107.552236 -221.133924)
					(end 108.210096 -221.133924)
				)
			)
		)
	)
	(zone
		(layers "F.Cu" "B.Cu" "In1.Cu" "In2.Cu" "In3.Cu" "In4.Cu" "In5.Cu" "In6.Cu"
			"In7.Cu" "In8.Cu" "In9.Cu" "In10.Cu" "In11.Cu" "In12.Cu" "In13.Cu" "In14.Cu"
			"In15.Cu" "In16.Cu"
		)
		(hatch none 0.5)
		(connect_pads
			(clearance 0)
		)
		(min_thickness 0.25)
		(keepout
			(tracks not_allowed)
			(vias allowed)
			(pads allowed)
			(copperpour not_allowed)
			(footprints allowed)
		)
		(placement
			(enabled no)
			(sheetname "")
		)
		(fill
			(thermal_gap 0.5)
			(thermal_bridge_width 0.5)
			(island_removal_mode 0)
		)
		(polygon
			(pts
				(arc
					(start 371.42293 -400.477228)
					(mid 371.04193 -400.858228)
					(end 371.42293 -401.239228)
				)
				(arc
					(start 372.28653 -401.239228)
					(mid 372.66753 -400.858228)
					(end 372.28653 -400.477228)
				)
			)
		)
	)
	(zone
		(layers "F.Cu" "B.Cu" "In1.Cu" "In2.Cu" "In3.Cu" "In4.Cu" "In5.Cu" "In6.Cu"
			"In7.Cu" "In8.Cu" "In9.Cu" "In10.Cu" "In11.Cu" "In12.Cu" "In13.Cu" "In14.Cu"
			"In15.Cu" "In16.Cu"
		)
		(hatch none 0.5)
		(connect_pads
			(clearance 0)
		)
		(min_thickness 0.25)
		(keepout
			(tracks not_allowed)
			(vias allowed)
			(pads allowed)
			(copperpour not_allowed)
			(footprints allowed)
		)
		(placement
			(enabled no)
			(sheetname "")
		)
		(fill
			(thermal_gap 0.5)
			(thermal_bridge_width 0.5)
			(island_removal_mode 0)
		)
		(polygon
			(pts
				(arc
					(start 361.160822 -220.22181)
					(mid 361.088833 -220.149651)
					(end 360.990388 -220.123258)
				)
				(arc
					(start 360.990388 -220.123258)
					(mid 360.851194 -220.180914)
					(end 360.793538 -220.320108)
				)
				(arc
					(start 360.793538 -220.320108)
					(mid 360.800295 -220.370989)
					(end 360.819954 -220.418406)
				)
				(arc
					(start 361.2896 -221.232222)
					(mid 361.361589 -221.304381)
					(end 361.460034 -221.330774)
				)
				(arc
					(start 361.460034 -221.330774)
					(mid 361.599228 -221.273118)
					(end 361.656884 -221.133924)
				)
				(arc
					(start 361.656884 -221.133924)
					(mid 361.650127 -221.083043)
					(end 361.630468 -221.035626)
				)
			)
		)
	)
	(zone
		(layers "F.Cu" "B.Cu" "In1.Cu" "In2.Cu" "In3.Cu" "In4.Cu" "In5.Cu" "In6.Cu"
			"In7.Cu" "In8.Cu" "In9.Cu" "In10.Cu" "In11.Cu" "In12.Cu" "In13.Cu" "In14.Cu"
			"In15.Cu" "In16.Cu"
		)
		(hatch none 0.5)
		(connect_pads
			(clearance 0)
		)
		(min_thickness 0.25)
		(keepout
			(tracks not_allowed)
			(vias allowed)
			(pads allowed)
			(copperpour not_allowed)
			(footprints allowed)
		)
		(placement
			(enabled no)
			(sheetname "")
		)
		(fill
			(thermal_gap 0.5)
			(thermal_bridge_width 0.5)
			(island_removal_mode 0)
		)
		(polygon
			(pts
				(arc
					(start 356.149656 -214.622634)
					(mid 355.491796 -214.622634)
					(end 356.149656 -214.622634)
				)
			)
		)
	)
	(zone
		(layers "F.Cu" "B.Cu" "In1.Cu" "In2.Cu" "In3.Cu" "In4.Cu" "In5.Cu" "In6.Cu"
			"In7.Cu" "In8.Cu" "In9.Cu" "In10.Cu" "In11.Cu" "In12.Cu" "In13.Cu" "In14.Cu"
			"In15.Cu" "In16.Cu"
		)
		(hatch none 0.5)
		(connect_pads
			(clearance 0)
		)
		(min_thickness 0.25)
		(keepout
			(tracks not_allowed)
			(vias allowed)
			(pads allowed)
			(copperpour not_allowed)
			(footprints allowed)
		)
		(placement
			(enabled no)
			(sheetname "")
		)
		(fill
			(thermal_gap 0.5)
			(thermal_bridge_width 0.5)
			(island_removal_mode 0)
		)
		(polygon
			(pts
				(arc
					(start 347.302582 -283.121608)
					(mid 347.282898 -283.169018)
					(end 347.276166 -283.219906)
				)
				(arc
					(start 347.276166 -283.219906)
					(mid 347.333822 -283.3591)
					(end 347.473016 -283.416756)
				)
				(arc
					(start 347.473016 -283.416756)
					(mid 347.571447 -283.39034)
					(end 347.64345 -283.318204)
				)
				(arc
					(start 348.11335 -282.504134)
					(mid 348.133034 -282.456724)
					(end 348.139766 -282.405836)
				)
				(arc
					(start 348.139766 -282.405836)
					(mid 348.08211 -282.266642)
					(end 347.942916 -282.208986)
				)
				(arc
					(start 347.942916 -282.208986)
					(mid 347.844485 -282.235402)
					(end 347.772482 -282.307538)
				)
			)
		)
	)
	(zone
		(layers "F.Cu" "B.Cu" "In1.Cu" "In2.Cu" "In3.Cu" "In4.Cu" "In5.Cu" "In6.Cu"
			"In7.Cu" "In8.Cu" "In9.Cu" "In10.Cu" "In11.Cu" "In12.Cu" "In13.Cu" "In14.Cu"
			"In15.Cu" "In16.Cu"
		)
		(hatch none 0.5)
		(connect_pads
			(clearance 0)
		)
		(min_thickness 0.25)
		(keepout
			(tracks not_allowed)
			(vias allowed)
			(pads allowed)
			(copperpour not_allowed)
			(footprints allowed)
		)
		(placement
			(enabled no)
			(sheetname "")
		)
		(fill
			(thermal_gap 0.5)
			(thermal_bridge_width 0.5)
			(island_removal_mode 0)
		)
		(polygon
			(pts
				(arc
					(start 135.471154 -403.502876)
					(mid 135.090154 -403.883876)
					(end 135.471154 -404.264876)
				)
				(arc
					(start 136.334754 -404.264876)
					(mid 136.715754 -403.883876)
					(end 136.334754 -403.502876)
				)
			)
		)
	)
	(zone
		(layers "F.Cu" "B.Cu" "In1.Cu" "In2.Cu" "In3.Cu" "In4.Cu" "In5.Cu" "In6.Cu"
			"In7.Cu" "In8.Cu" "In9.Cu" "In10.Cu" "In11.Cu" "In12.Cu" "In13.Cu" "In14.Cu"
			"In15.Cu" "In16.Cu"
		)
		(hatch none 0.5)
		(connect_pads
			(clearance 0)
		)
		(min_thickness 0.25)
		(keepout
			(tracks not_allowed)
			(vias allowed)
			(pads allowed)
			(copperpour not_allowed)
			(footprints allowed)
		)
		(placement
			(enabled no)
			(sheetname "")
		)
		(fill
			(thermal_gap 0.5)
			(thermal_bridge_width 0.5)
			(island_removal_mode 0)
		)
		(polygon
			(pts
				(arc
					(start 373.646446 -288.917126)
					(mid 372.988586 -288.917126)
					(end 373.646446 -288.917126)
				)
			)
		)
	)
	(zone
		(layers "F.Cu" "B.Cu" "In1.Cu" "In2.Cu" "In3.Cu" "In4.Cu" "In5.Cu" "In6.Cu"
			"In7.Cu" "In8.Cu" "In9.Cu" "In10.Cu" "In11.Cu" "In12.Cu" "In13.Cu" "In14.Cu"
			"In15.Cu" "In16.Cu"
		)
		(hatch none 0.5)
		(connect_pads
			(clearance 0)
		)
		(min_thickness 0.25)
		(keepout
			(tracks not_allowed)
			(vias allowed)
			(pads allowed)
			(copperpour not_allowed)
			(footprints allowed)
		)
		(placement
			(enabled no)
			(sheetname "")
		)
		(fill
			(thermal_gap 0.5)
			(thermal_bridge_width 0.5)
			(island_removal_mode 0)
		)
		(polygon
			(pts
				(arc
					(start 123.998482 -220.319854)
					(mid 124.656342 -220.319854)
					(end 123.998482 -220.319854)
				)
			)
		)
	)
	(zone
		(layers "F.Cu" "B.Cu" "In1.Cu" "In2.Cu" "In3.Cu" "In4.Cu" "In5.Cu" "In6.Cu"
			"In7.Cu" "In8.Cu" "In9.Cu" "In10.Cu" "In11.Cu" "In12.Cu" "In13.Cu" "In14.Cu"
			"In15.Cu" "In16.Cu"
		)
		(hatch none 0.5)
		(connect_pads
			(clearance 0)
		)
		(min_thickness 0.25)
		(keepout
			(tracks not_allowed)
			(vias allowed)
			(pads allowed)
			(copperpour not_allowed)
			(footprints allowed)
		)
		(placement
			(enabled no)
			(sheetname "")
		)
		(fill
			(thermal_gap 0.5)
			(thermal_bridge_width 0.5)
			(island_removal_mode 0)
		)
		(polygon
			(pts
				(arc
					(start 340.253828 -285.563056)
					(mid 340.234144 -285.610466)
					(end 340.227412 -285.661354)
				)
				(arc
					(start 340.227412 -285.661354)
					(mid 340.285068 -285.800548)
					(end 340.424262 -285.858204)
				)
				(arc
					(start 340.424262 -285.858204)
					(mid 340.522693 -285.831788)
					(end 340.594696 -285.759652)
				)
				(arc
					(start 341.064596 -284.945582)
					(mid 341.08428 -284.898172)
					(end 341.091012 -284.847284)
				)
				(arc
					(start 341.091012 -284.847284)
					(mid 341.033356 -284.70809)
					(end 340.894162 -284.650434)
				)
				(arc
					(start 340.894162 -284.650434)
					(mid 340.795731 -284.67685)
					(end 340.723728 -284.748986)
				)
			)
		)
	)
	(zone
		(layers "F.Cu" "B.Cu" "In1.Cu" "In2.Cu" "In3.Cu" "In4.Cu" "In5.Cu" "In6.Cu"
			"In7.Cu" "In8.Cu" "In9.Cu" "In10.Cu" "In11.Cu" "In12.Cu" "In13.Cu" "In14.Cu"
			"In15.Cu" "In16.Cu"
		)
		(hatch none 0.5)
		(connect_pads
			(clearance 0)
		)
		(min_thickness 0.25)
		(keepout
			(tracks not_allowed)
			(vias allowed)
			(pads allowed)
			(copperpour not_allowed)
			(footprints allowed)
		)
		(placement
			(enabled no)
			(sheetname "")
		)
		(fill
			(thermal_gap 0.5)
			(thermal_bridge_width 0.5)
			(island_removal_mode 0)
		)
		(polygon
			(pts
				(arc
					(start 126.535942 -223.575626)
					(mid 125.878082 -223.575626)
					(end 126.535942 -223.575626)
				)
			)
		)
	)
	(zone
		(layers "F.Cu" "B.Cu" "In1.Cu" "In2.Cu" "In3.Cu" "In4.Cu" "In5.Cu" "In6.Cu"
			"In7.Cu" "In8.Cu" "In9.Cu" "In10.Cu" "In11.Cu" "In12.Cu" "In13.Cu" "In14.Cu"
			"In15.Cu" "In16.Cu"
		)
		(hatch none 0.5)
		(connect_pads
			(clearance 0)
		)
		(min_thickness 0.25)
		(keepout
			(tracks not_allowed)
			(vias allowed)
			(pads allowed)
			(copperpour not_allowed)
			(footprints allowed)
		)
		(placement
			(enabled no)
			(sheetname "")
		)
		(fill
			(thermal_gap 0.5)
			(thermal_bridge_width 0.5)
			(island_removal_mode 0)
		)
		(polygon
			(pts
				(arc
					(start 123.716542 -221.94774)
					(mid 123.058682 -221.94774)
					(end 123.716542 -221.94774)
				)
			)
		)
	)
	(zone
		(layers "F.Cu" "B.Cu" "In1.Cu" "In2.Cu" "In3.Cu" "In4.Cu" "In5.Cu" "In6.Cu"
			"In7.Cu" "In8.Cu" "In9.Cu" "In10.Cu" "In11.Cu" "In12.Cu" "In13.Cu" "In14.Cu"
			"In15.Cu" "In16.Cu"
		)
		(hatch none 0.5)
		(connect_pads
			(clearance 0)
		)
		(min_thickness 0.25)
		(keepout
			(tracks not_allowed)
			(vias allowed)
			(pads allowed)
			(copperpour not_allowed)
			(footprints allowed)
		)
		(placement
			(enabled no)
			(sheetname "")
		)
		(fill
			(thermal_gap 0.5)
			(thermal_bridge_width 0.5)
			(island_removal_mode 0)
		)
		(polygon
			(pts
				(arc
					(start 97.794064 -285.661354)
					(mid 98.451924 -285.661354)
					(end 97.794064 -285.661354)
				)
			)
		)
	)
	(zone
		(layers "F.Cu" "B.Cu" "In1.Cu" "In2.Cu" "In3.Cu" "In4.Cu" "In5.Cu" "In6.Cu"
			"In7.Cu" "In8.Cu" "In9.Cu" "In10.Cu" "In11.Cu" "In12.Cu" "In13.Cu" "In14.Cu"
			"In15.Cu" "In16.Cu"
		)
		(hatch none 0.5)
		(connect_pads
			(clearance 0)
		)
		(min_thickness 0.25)
		(keepout
			(tracks not_allowed)
			(vias allowed)
			(pads allowed)
			(copperpour not_allowed)
			(footprints allowed)
		)
		(placement
			(enabled no)
			(sheetname "")
		)
		(fill
			(thermal_gap 0.5)
			(thermal_bridge_width 0.5)
			(island_removal_mode 0)
		)
		(polygon
			(pts
				(arc
					(start 366.95761 -220.319854)
					(mid 366.29975 -220.319854)
					(end 366.95761 -220.319854)
				)
			)
		)
	)
	(zone
		(layers "F.Cu" "B.Cu" "In1.Cu" "In2.Cu" "In3.Cu" "In4.Cu" "In5.Cu" "In6.Cu"
			"In7.Cu" "In8.Cu" "In9.Cu" "In10.Cu" "In11.Cu" "In12.Cu" "In13.Cu" "In14.Cu"
			"In15.Cu" "In16.Cu"
		)
		(hatch none 0.5)
		(connect_pads
			(clearance 0)
		)
		(min_thickness 0.25)
		(keepout
			(tracks not_allowed)
			(vias allowed)
			(pads allowed)
			(copperpour not_allowed)
			(footprints allowed)
		)
		(placement
			(enabled no)
			(sheetname "")
		)
		(fill
			(thermal_gap 0.5)
			(thermal_bridge_width 0.5)
			(island_removal_mode 0)
		)
		(polygon
			(pts
				(arc
					(start 109.149896 -221.133924)
					(mid 108.492036 -221.133924)
					(end 109.149896 -221.133924)
				)
			)
		)
	)
	(zone
		(layers "F.Cu" "B.Cu" "In1.Cu" "In2.Cu" "In3.Cu" "In4.Cu" "In5.Cu" "In6.Cu"
			"In7.Cu" "In8.Cu" "In9.Cu" "In10.Cu" "In11.Cu" "In12.Cu" "In13.Cu" "In14.Cu"
			"In15.Cu" "In16.Cu"
		)
		(hatch none 0.5)
		(connect_pads
			(clearance 0)
		)
		(min_thickness 0.25)
		(keepout
			(tracks not_allowed)
			(vias allowed)
			(pads allowed)
			(copperpour not_allowed)
			(footprints allowed)
		)
		(placement
			(enabled no)
			(sheetname "")
		)
		(fill
			(thermal_gap 0.5)
			(thermal_bridge_width 0.5)
			(island_removal_mode 0)
		)
		(polygon
			(pts
				(arc
					(start 126.065788 -214.622634)
					(mid 125.407928 -214.622634)
					(end 126.065788 -214.622634)
				)
			)
		)
	)
	(zone
		(layers "F.Cu" "B.Cu" "In1.Cu" "In2.Cu" "In3.Cu" "In4.Cu" "In5.Cu" "In6.Cu"
			"In7.Cu" "In8.Cu" "In9.Cu" "In10.Cu" "In11.Cu" "In12.Cu" "In13.Cu" "In14.Cu"
			"In15.Cu" "In16.Cu"
		)
		(hatch none 0.5)
		(connect_pads
			(clearance 0)
		)
		(min_thickness 0.25)
		(keepout
			(tracks not_allowed)
			(vias allowed)
			(pads allowed)
			(copperpour not_allowed)
			(footprints allowed)
		)
		(placement
			(enabled no)
			(sheetname "")
		)
		(fill
			(thermal_gap 0.5)
			(thermal_bridge_width 0.5)
			(island_removal_mode 0)
		)
		(polygon
			(pts
				(arc
					(start 381.05461 -218.692222)
					(mid 380.39675 -218.692222)
					(end 381.05461 -218.692222)
				)
			)
		)
	)
	(zone
		(layers "F.Cu" "B.Cu" "In1.Cu" "In2.Cu" "In3.Cu" "In4.Cu" "In5.Cu" "In6.Cu"
			"In7.Cu" "In8.Cu" "In9.Cu" "In10.Cu" "In11.Cu" "In12.Cu" "In13.Cu" "In14.Cu"
			"In15.Cu" "In16.Cu"
		)
		(hatch none 0.5)
		(connect_pads
			(clearance 0)
		)
		(min_thickness 0.25)
		(keepout
			(tracks not_allowed)
			(vias allowed)
			(pads allowed)
			(copperpour not_allowed)
			(footprints allowed)
		)
		(placement
			(enabled no)
			(sheetname "")
		)
		(fill
			(thermal_gap 0.5)
			(thermal_bridge_width 0.5)
			(island_removal_mode 0)
		)
		(polygon
			(pts
				(arc
					(start 44.331382 -4.581652)
					(mid 43.950382 -4.962652)
					(end 44.331382 -5.343652)
				)
				(arc
					(start 45.194982 -5.343652)
					(mid 45.575982 -4.962652)
					(end 45.194982 -4.581652)
				)
			)
		)
	)
	(zone
		(layers "F.Cu" "B.Cu" "In1.Cu" "In2.Cu" "In3.Cu" "In4.Cu" "In5.Cu" "In6.Cu"
			"In7.Cu" "In8.Cu" "In9.Cu" "In10.Cu" "In11.Cu" "In12.Cu" "In13.Cu" "In14.Cu"
			"In15.Cu" "In16.Cu"
		)
		(hatch none 0.5)
		(connect_pads
			(clearance 0)
		)
		(min_thickness 0.25)
		(keepout
			(tracks not_allowed)
			(vias allowed)
			(pads allowed)
			(copperpour not_allowed)
			(footprints allowed)
		)
		(placement
			(enabled no)
			(sheetname "")
		)
		(fill
			(thermal_gap 0.5)
			(thermal_bridge_width 0.5)
			(island_removal_mode 0)
		)
		(polygon
			(pts
				(arc
					(start 352.390964 -224.389442)
					(mid 351.733104 -224.389442)
					(end 352.390964 -224.389442)
				)
			)
		)
	)
	(zone
		(layers "F.Cu" "B.Cu" "In1.Cu" "In2.Cu" "In3.Cu" "In4.Cu" "In5.Cu" "In6.Cu"
			"In7.Cu" "In8.Cu" "In9.Cu" "In10.Cu" "In11.Cu" "In12.Cu" "In13.Cu" "In14.Cu"
			"In15.Cu" "In16.Cu"
		)
		(hatch none 0.5)
		(connect_pads
			(clearance 0)
		)
		(min_thickness 0.25)
		(keepout
			(tracks not_allowed)
			(vias allowed)
			(pads allowed)
			(copperpour not_allowed)
			(footprints allowed)
		)
		(placement
			(enabled no)
			(sheetname "")
		)
		(fill
			(thermal_gap 0.5)
			(thermal_bridge_width 0.5)
			(island_removal_mode 0)
		)
		(polygon
			(pts
				(arc
					(start 327.352914 -0.048006)
					(mid 327.733914 -0.429006)
					(end 328.114914 -0.048006)
				)
				(arc
					(start 328.114914 0.815594)
					(mid 327.733914 1.196594)
					(end 327.352914 0.815594)
				)
			)
		)
	)
	(zone
		(layers "F.Cu" "B.Cu" "In1.Cu" "In2.Cu" "In3.Cu" "In4.Cu" "In5.Cu" "In6.Cu"
			"In7.Cu" "In8.Cu" "In9.Cu" "In10.Cu" "In11.Cu" "In12.Cu" "In13.Cu" "In14.Cu"
			"In15.Cu" "In16.Cu"
		)
		(hatch none 0.5)
		(connect_pads
			(clearance 0)
		)
		(min_thickness 0.25)
		(keepout
			(tracks not_allowed)
			(vias allowed)
			(pads allowed)
			(copperpour not_allowed)
			(footprints allowed)
		)
		(placement
			(enabled no)
			(sheetname "")
		)
		(fill
			(thermal_gap 0.5)
			(thermal_bridge_width 0.5)
			(island_removal_mode 0)
		)
		(polygon
			(pts
				(arc
					(start 123.716542 -218.692222)
					(mid 123.058682 -218.692222)
					(end 123.716542 -218.692222)
				)
			)
		)
	)
	(zone
		(layers "F.Cu" "B.Cu" "In1.Cu" "In2.Cu" "In3.Cu" "In4.Cu" "In5.Cu" "In6.Cu"
			"In7.Cu" "In8.Cu" "In9.Cu" "In10.Cu" "In11.Cu" "In12.Cu" "In13.Cu" "In14.Cu"
			"In15.Cu" "In16.Cu"
		)
		(hatch none 0.5)
		(connect_pads
			(clearance 0)
		)
		(min_thickness 0.25)
		(keepout
			(tracks not_allowed)
			(vias allowed)
			(pads allowed)
			(copperpour not_allowed)
			(footprints allowed)
		)
		(placement
			(enabled no)
			(sheetname "")
		)
		(fill
			(thermal_gap 0.5)
			(thermal_bridge_width 0.5)
			(island_removal_mode 0)
		)
		(polygon
			(pts
				(arc
					(start 303.980088 -400.477228)
					(mid 303.599088 -400.858228)
					(end 303.980088 -401.239228)
				)
				(arc
					(start 304.843688 -401.239228)
					(mid 305.224688 -400.858228)
					(end 304.843688 -400.477228)
				)
			)
		)
	)
	(zone
		(layers "F.Cu" "B.Cu" "In1.Cu" "In2.Cu" "In3.Cu" "In4.Cu" "In5.Cu" "In6.Cu"
			"In7.Cu" "In8.Cu" "In9.Cu" "In10.Cu" "In11.Cu" "In12.Cu" "In13.Cu" "In14.Cu"
			"In15.Cu" "In16.Cu"
		)
		(hatch none 0.5)
		(connect_pads
			(clearance 0)
		)
		(min_thickness 0.25)
		(keepout
			(tracks not_allowed)
			(vias allowed)
			(pads allowed)
			(copperpour not_allowed)
			(footprints allowed)
		)
		(placement
			(enabled no)
			(sheetname "")
		)
		(fill
			(thermal_gap 0.5)
			(thermal_bridge_width 0.5)
			(island_removal_mode 0)
		)
		(polygon
			(pts
				(arc
					(start 250.80976 -109.142022)
					(mid 250.42876 -109.523022)
					(end 250.80976 -109.904022)
				)
				(arc
					(start 251.67336 -109.904022)
					(mid 252.05436 -109.523022)
					(end 251.67336 -109.142022)
				)
			)
		)
	)
	(zone
		(layers "F.Cu" "B.Cu" "In1.Cu" "In2.Cu" "In3.Cu" "In4.Cu" "In5.Cu" "In6.Cu"
			"In7.Cu" "In8.Cu" "In9.Cu" "In10.Cu" "In11.Cu" "In12.Cu" "In13.Cu" "In14.Cu"
			"In15.Cu" "In16.Cu"
		)
		(hatch none 0.5)
		(connect_pads
			(clearance 0)
		)
		(min_thickness 0.25)
		(keepout
			(tracks not_allowed)
			(vias allowed)
			(pads allowed)
			(copperpour not_allowed)
			(footprints allowed)
		)
		(placement
			(enabled no)
			(sheetname "")
		)
		(fill
			(thermal_gap 0.5)
			(thermal_bridge_width 0.5)
			(island_removal_mode 0)
		)
		(polygon
			(pts
				(arc
					(start 95.522542 -225.203258)
					(mid 94.864682 -225.203258)
					(end 95.522542 -225.203258)
				)
			)
		)
	)
	(zone
		(layers "F.Cu" "B.Cu" "In1.Cu" "In2.Cu" "In3.Cu" "In4.Cu" "In5.Cu" "In6.Cu"
			"In7.Cu" "In8.Cu" "In9.Cu" "In10.Cu" "In11.Cu" "In12.Cu" "In13.Cu" "In14.Cu"
			"In15.Cu" "In16.Cu"
		)
		(hatch none 0.5)
		(connect_pads
			(clearance 0)
		)
		(min_thickness 0.25)
		(keepout
			(tracks not_allowed)
			(vias allowed)
			(pads allowed)
			(copperpour not_allowed)
			(footprints allowed)
		)
		(placement
			(enabled no)
			(sheetname "")
		)
		(fill
			(thermal_gap 0.5)
			(thermal_bridge_width 0.5)
			(island_removal_mode 0)
		)
		(polygon
			(pts
				(arc
					(start 104.53116 -280.679906)
					(mid 104.511476 -280.727316)
					(end 104.504744 -280.778204)
				)
				(arc
					(start 104.504744 -280.778204)
					(mid 104.5624 -280.917398)
					(end 104.701594 -280.975054)
				)
				(arc
					(start 104.701594 -280.975054)
					(mid 104.800025 -280.948638)
					(end 104.872028 -280.876502)
				)
				(arc
					(start 105.341928 -280.062432)
					(mid 105.361612 -280.015022)
					(end 105.368344 -279.964134)
				)
				(arc
					(start 105.368344 -279.964134)
					(mid 105.310688 -279.82494)
					(end 105.171494 -279.767284)
				)
				(arc
					(start 105.171494 -279.767284)
					(mid 105.073063 -279.7937)
					(end 105.00106 -279.865836)
				)
			)
		)
	)
	(zone
		(layers "F.Cu" "B.Cu" "In1.Cu" "In2.Cu" "In3.Cu" "In4.Cu" "In5.Cu" "In6.Cu"
			"In7.Cu" "In8.Cu" "In9.Cu" "In10.Cu" "In11.Cu" "In12.Cu" "In13.Cu" "In14.Cu"
			"In15.Cu" "In16.Cu"
		)
		(hatch none 0.5)
		(connect_pads
			(clearance 0)
		)
		(min_thickness 0.25)
		(keepout
			(tracks not_allowed)
			(vias allowed)
			(pads allowed)
			(copperpour not_allowed)
			(footprints allowed)
		)
		(placement
			(enabled no)
			(sheetname "")
		)
		(fill
			(thermal_gap 0.5)
			(thermal_bridge_width 0.5)
			(island_removal_mode 0)
		)
		(polygon
			(pts
				(arc
					(start 115.728496 -221.133924)
					(mid 115.070636 -221.133924)
					(end 115.728496 -221.133924)
				)
			)
		)
	)
	(zone
		(layers "F.Cu" "B.Cu" "In1.Cu" "In2.Cu" "In3.Cu" "In4.Cu" "In5.Cu" "In6.Cu"
			"In7.Cu" "In8.Cu" "In9.Cu" "In10.Cu" "In11.Cu" "In12.Cu" "In13.Cu" "In14.Cu"
			"In15.Cu" "In16.Cu"
		)
		(hatch none 0.5)
		(connect_pads
			(clearance 0)
		)
		(min_thickness 0.25)
		(keepout
			(tracks not_allowed)
			(vias allowed)
			(pads allowed)
			(copperpour not_allowed)
			(footprints allowed)
		)
		(placement
			(enabled no)
			(sheetname "")
		)
		(fill
			(thermal_gap 0.5)
			(thermal_bridge_width 0.5)
			(island_removal_mode 0)
		)
		(polygon
			(pts
				(arc
					(start 372.126764 -217.878406)
					(mid 371.468904 -217.878406)
					(end 372.126764 -217.878406)
				)
			)
		)
	)
	(zone
		(layers "F.Cu" "B.Cu" "In1.Cu" "In2.Cu" "In3.Cu" "In4.Cu" "In5.Cu" "In6.Cu"
			"In7.Cu" "In8.Cu" "In9.Cu" "In10.Cu" "In11.Cu" "In12.Cu" "In13.Cu" "In14.Cu"
			"In15.Cu" "In16.Cu"
		)
		(hatch none 0.5)
		(connect_pads
			(clearance 0)
		)
		(min_thickness 0.25)
		(keepout
			(tracks not_allowed)
			(vias allowed)
			(pads allowed)
			(copperpour not_allowed)
			(footprints allowed)
		)
		(placement
			(enabled no)
			(sheetname "")
		)
		(fill
			(thermal_gap 0.5)
			(thermal_bridge_width 0.5)
			(island_removal_mode 0)
		)
		(polygon
			(pts
				(arc
					(start 344.823796 -279.865836)
					(mid 344.751807 -279.793677)
					(end 344.653362 -279.767284)
				)
				(arc
					(start 344.653362 -279.767284)
					(mid 344.514168 -279.82494)
					(end 344.456512 -279.964134)
				)
				(arc
					(start 344.456512 -279.964134)
					(mid 344.463269 -280.015015)
					(end 344.482928 -280.062432)
				)
				(arc
					(start 344.952828 -280.876502)
					(mid 345.024817 -280.948661)
					(end 345.123262 -280.975054)
				)
				(arc
					(start 345.123262 -280.975054)
					(mid 345.262456 -280.917398)
					(end 345.320112 -280.778204)
				)
				(arc
					(start 345.320112 -280.778204)
					(mid 345.313355 -280.727323)
					(end 345.293696 -280.679906)
				)
			)
		)
	)
	(zone
		(layers "F.Cu" "B.Cu" "In1.Cu" "In2.Cu" "In3.Cu" "In4.Cu" "In5.Cu" "In6.Cu"
			"In7.Cu" "In8.Cu" "In9.Cu" "In10.Cu" "In11.Cu" "In12.Cu" "In13.Cu" "In14.Cu"
			"In15.Cu" "In16.Cu"
		)
		(hatch none 0.5)
		(connect_pads
			(clearance 0)
		)
		(min_thickness 0.25)
		(keepout
			(tracks not_allowed)
			(vias allowed)
			(pads allowed)
			(copperpour not_allowed)
			(footprints allowed)
		)
		(placement
			(enabled no)
			(sheetname "")
		)
		(fill
			(thermal_gap 0.5)
			(thermal_bridge_width 0.5)
			(island_removal_mode 0)
		)
		(polygon
			(pts
				(arc
					(start 350.511364 -224.389442)
					(mid 349.853504 -224.389442)
					(end 350.511364 -224.389442)
				)
			)
		)
	)
	(zone
		(layers "F.Cu" "B.Cu" "In1.Cu" "In2.Cu" "In3.Cu" "In4.Cu" "In5.Cu" "In6.Cu"
			"In7.Cu" "In8.Cu" "In9.Cu" "In10.Cu" "In11.Cu" "In12.Cu" "In13.Cu" "In14.Cu"
			"In15.Cu" "In16.Cu"
		)
		(hatch none 0.5)
		(connect_pads
			(clearance 0)
		)
		(min_thickness 0.25)
		(keepout
			(tracks not_allowed)
			(vias allowed)
			(pads allowed)
			(copperpour not_allowed)
			(footprints allowed)
		)
		(placement
			(enabled no)
			(sheetname "")
		)
		(fill
			(thermal_gap 0.5)
			(thermal_bridge_width 0.5)
			(island_removal_mode 0)
		)
		(polygon
			(pts
				(arc
					(start 125.048264 -285.661354)
					(mid 125.706124 -285.661354)
					(end 125.048264 -285.661354)
				)
			)
		)
	)
	(zone
		(layers "F.Cu" "B.Cu" "In1.Cu" "In2.Cu" "In3.Cu" "In4.Cu" "In5.Cu" "In6.Cu"
			"In7.Cu" "In8.Cu" "In9.Cu" "In10.Cu" "In11.Cu" "In12.Cu" "In13.Cu" "In14.Cu"
			"In15.Cu" "In16.Cu"
		)
		(hatch none 0.5)
		(connect_pads
			(clearance 0)
		)
		(min_thickness 0.25)
		(keepout
			(tracks not_allowed)
			(vias allowed)
			(pads allowed)
			(copperpour not_allowed)
			(footprints allowed)
		)
		(placement
			(enabled no)
			(sheetname "")
		)
		(fill
			(thermal_gap 0.5)
			(thermal_bridge_width 0.5)
			(island_removal_mode 0)
		)
		(polygon
			(pts
				(arc
					(start 105.390696 -224.389442)
					(mid 104.732836 -224.389442)
					(end 105.390696 -224.389442)
				)
			)
		)
	)
	(zone
		(layers "F.Cu" "B.Cu" "In1.Cu" "In2.Cu" "In3.Cu" "In4.Cu" "In5.Cu" "In6.Cu"
			"In7.Cu" "In8.Cu" "In9.Cu" "In10.Cu" "In11.Cu" "In12.Cu" "In13.Cu" "In14.Cu"
			"In15.Cu" "In16.Cu"
		)
		(hatch none 0.5)
		(connect_pads
			(clearance 0)
		)
		(min_thickness 0.25)
		(keepout
			(tracks not_allowed)
			(vias allowed)
			(pads allowed)
			(copperpour not_allowed)
			(footprints allowed)
		)
		(placement
			(enabled no)
			(sheetname "")
		)
		(fill
			(thermal_gap 0.5)
			(thermal_bridge_width 0.5)
			(island_removal_mode 0)
		)
		(polygon
			(pts
				(arc
					(start 364.44936 -221.231968)
					(mid 364.469044 -221.184558)
					(end 364.475776 -221.13367)
				)
				(arc
					(start 364.475776 -221.13367)
					(mid 364.41812 -220.994476)
					(end 364.278926 -220.93682)
				)
				(arc
					(start 364.278926 -220.93682)
					(mid 364.180495 -220.963236)
					(end 364.108492 -221.035372)
				)
				(arc
					(start 363.638846 -221.849442)
					(mid 363.619162 -221.896852)
					(end 363.61243 -221.94774)
				)
				(arc
					(start 363.61243 -221.94774)
					(mid 363.670086 -222.086934)
					(end 363.80928 -222.14459)
				)
				(arc
					(start 363.80928 -222.14459)
					(mid 363.907711 -222.118174)
					(end 363.979714 -222.046038)
				)
			)
		)
	)
	(zone
		(layers "F.Cu" "B.Cu" "In1.Cu" "In2.Cu" "In3.Cu" "In4.Cu" "In5.Cu" "In6.Cu"
			"In7.Cu" "In8.Cu" "In9.Cu" "In10.Cu" "In11.Cu" "In12.Cu" "In13.Cu" "In14.Cu"
			"In15.Cu" "In16.Cu"
		)
		(hatch none 0.5)
		(connect_pads
			(clearance 0)
		)
		(min_thickness 0.25)
		(keepout
			(tracks not_allowed)
			(vias allowed)
			(pads allowed)
			(copperpour not_allowed)
			(footprints allowed)
		)
		(placement
			(enabled no)
			(sheetname "")
		)
		(fill
			(thermal_gap 0.5)
			(thermal_bridge_width 0.5)
			(island_removal_mode 0)
		)
		(polygon
			(pts
				(arc
					(start 117.419882 -215.436704)
					(mid 118.077742 -215.436704)
					(end 117.419882 -215.436704)
				)
			)
		)
	)
	(zone
		(layers "F.Cu" "B.Cu" "In1.Cu" "In2.Cu" "In3.Cu" "In4.Cu" "In5.Cu" "In6.Cu"
			"In7.Cu" "In8.Cu" "In9.Cu" "In10.Cu" "In11.Cu" "In12.Cu" "In13.Cu" "In14.Cu"
			"In15.Cu" "In16.Cu"
		)
		(hatch none 0.5)
		(connect_pads
			(clearance 0)
		)
		(min_thickness 0.25)
		(keepout
			(tracks not_allowed)
			(vias allowed)
			(pads allowed)
			(copperpour not_allowed)
			(footprints allowed)
		)
		(placement
			(enabled no)
			(sheetname "")
		)
		(fill
			(thermal_gap 0.5)
			(thermal_bridge_width 0.5)
			(island_removal_mode 0)
		)
		(polygon
			(pts
				(arc
					(start 338.293456 -214.622634)
					(mid 337.635596 -214.622634)
					(end 338.293456 -214.622634)
				)
			)
		)
	)
	(zone
		(layers "F.Cu" "B.Cu" "In1.Cu" "In2.Cu" "In3.Cu" "In4.Cu" "In5.Cu" "In6.Cu"
			"In7.Cu" "In8.Cu" "In9.Cu" "In10.Cu" "In11.Cu" "In12.Cu" "In13.Cu" "In14.Cu"
			"In15.Cu" "In16.Cu"
		)
		(hatch none 0.5)
		(connect_pads
			(clearance 0)
		)
		(min_thickness 0.25)
		(keepout
			(tracks not_allowed)
			(vias allowed)
			(pads allowed)
			(copperpour not_allowed)
			(footprints allowed)
		)
		(placement
			(enabled no)
			(sheetname "")
		)
		(fill
			(thermal_gap 0.5)
			(thermal_bridge_width 0.5)
			(island_removal_mode 0)
		)
		(polygon
			(pts
				(arc
					(start 112.438942 -221.94774)
					(mid 111.781082 -221.94774)
					(end 112.438942 -221.94774)
				)
			)
		)
	)
	(zone
		(layers "F.Cu" "B.Cu" "In1.Cu" "In2.Cu" "In3.Cu" "In4.Cu" "In5.Cu" "In6.Cu"
			"In7.Cu" "In8.Cu" "In9.Cu" "In10.Cu" "In11.Cu" "In12.Cu" "In13.Cu" "In14.Cu"
			"In15.Cu" "In16.Cu"
		)
		(hatch none 0.5)
		(connect_pads
			(clearance 0)
		)
		(min_thickness 0.25)
		(keepout
			(tracks not_allowed)
			(vias allowed)
			(pads allowed)
			(copperpour not_allowed)
			(footprints allowed)
		)
		(placement
			(enabled no)
			(sheetname "")
		)
		(fill
			(thermal_gap 0.5)
			(thermal_bridge_width 0.5)
			(island_removal_mode 0)
		)
		(polygon
			(pts
				(arc
					(start 347.801946 -283.219906)
					(mid 347.144086 -283.219906)
					(end 347.801946 -283.219906)
				)
			)
		)
	)
	(zone
		(layers "F.Cu" "B.Cu" "In1.Cu" "In2.Cu" "In3.Cu" "In4.Cu" "In5.Cu" "In6.Cu"
			"In7.Cu" "In8.Cu" "In9.Cu" "In10.Cu" "In11.Cu" "In12.Cu" "In13.Cu" "In14.Cu"
			"In15.Cu" "In16.Cu"
		)
		(hatch none 0.5)
		(connect_pads
			(clearance 0)
		)
		(min_thickness 0.25)
		(keepout
			(tracks not_allowed)
			(vias allowed)
			(pads allowed)
			(copperpour not_allowed)
			(footprints allowed)
		)
		(placement
			(enabled no)
			(sheetname "")
		)
		(fill
			(thermal_gap 0.5)
			(thermal_bridge_width 0.5)
			(island_removal_mode 0)
		)
		(polygon
			(pts
				(arc
					(start 94.113096 -224.389442)
					(mid 93.455236 -224.389442)
					(end 94.113096 -224.389442)
				)
			)
		)
	)
	(zone
		(layers "F.Cu" "B.Cu" "In1.Cu" "In2.Cu" "In3.Cu" "In4.Cu" "In5.Cu" "In6.Cu"
			"In7.Cu" "In8.Cu" "In9.Cu" "In10.Cu" "In11.Cu" "In12.Cu" "In13.Cu" "In14.Cu"
			"In15.Cu" "In16.Cu"
		)
		(hatch none 0.5)
		(connect_pads
			(clearance 0)
		)
		(min_thickness 0.25)
		(keepout
			(tracks not_allowed)
			(vias allowed)
			(pads allowed)
			(copperpour not_allowed)
			(footprints allowed)
		)
		(placement
			(enabled no)
			(sheetname "")
		)
		(fill
			(thermal_gap 0.5)
			(thermal_bridge_width 0.5)
			(island_removal_mode 0)
		)
		(polygon
			(pts
				(arc
					(start 353.874324 -184.08269)
					(mid 354.233534 -183.9339)
					(end 354.382324 -183.57469)
				)
				(arc
					(start 354.382324 -183.57469)
					(mid 354.314267 -183.320693)
					(end 354.128324 -183.134762)
				)
				(arc
					(start 353.204272 -182.601108)
					(mid 353.081978 -182.550571)
					(end 352.95078 -182.53329)
				)
				(arc
					(start 352.950272 -182.53329)
					(mid 352.591062 -182.68208)
					(end 352.442272 -183.04129)
				)
				(arc
					(start 352.442272 -183.04129)
					(mid 352.510329 -183.295287)
					(end 352.696272 -183.481218)
				)
				(arc
					(start 353.620324 -184.014872)
					(mid 353.742618 -184.065409)
					(end 353.873816 -184.08269)
				)
			)
		)
	)
	(zone
		(layers "F.Cu" "B.Cu" "In1.Cu" "In2.Cu" "In3.Cu" "In4.Cu" "In5.Cu" "In6.Cu"
			"In7.Cu" "In8.Cu" "In9.Cu" "In10.Cu" "In11.Cu" "In12.Cu" "In13.Cu" "In14.Cu"
			"In15.Cu" "In16.Cu"
		)
		(hatch none 0.5)
		(connect_pads
			(clearance 0)
		)
		(min_thickness 0.25)
		(keepout
			(tracks not_allowed)
			(vias allowed)
			(pads allowed)
			(copperpour not_allowed)
			(footprints allowed)
		)
		(placement
			(enabled no)
			(sheetname "")
		)
		(fill
			(thermal_gap 0.5)
			(thermal_bridge_width 0.5)
			(island_removal_mode 0)
		)
		(polygon
			(pts
				(arc
					(start 400.33829 -409.649168)
					(mid 399.95729 -410.030168)
					(end 400.33829 -410.411168)
				)
				(arc
					(start 401.20189 -410.411168)
					(mid 401.58289 -410.030168)
					(end 401.20189 -409.649168)
				)
			)
		)
	)
	(zone
		(layers "F.Cu" "B.Cu" "In1.Cu" "In2.Cu" "In3.Cu" "In4.Cu" "In5.Cu" "In6.Cu"
			"In7.Cu" "In8.Cu" "In9.Cu" "In10.Cu" "In11.Cu" "In12.Cu" "In13.Cu" "In14.Cu"
			"In15.Cu" "In16.Cu"
		)
		(hatch none 0.5)
		(connect_pads
			(clearance 0)
		)
		(min_thickness 0.25)
		(keepout
			(tracks not_allowed)
			(vias allowed)
			(pads allowed)
			(copperpour not_allowed)
			(footprints allowed)
		)
		(placement
			(enabled no)
			(sheetname "")
		)
		(fill
			(thermal_gap 0.5)
			(thermal_bridge_width 0.5)
			(island_removal_mode 0)
		)
		(polygon
			(pts
				(arc
					(start 344.714068 -224.291144)
					(mid 344.642079 -224.218985)
					(end 344.543634 -224.192592)
				)
				(arc
					(start 344.543634 -224.192592)
					(mid 344.40444 -224.250248)
					(end 344.346784 -224.389442)
				)
				(arc
					(start 344.346784 -224.389442)
					(mid 344.353541 -224.440323)
					(end 344.3732 -224.48774)
				)
				(arc
					(start 344.842846 -225.301556)
					(mid 344.914835 -225.373715)
					(end 345.01328 -225.400108)
				)
				(arc
					(start 345.01328 -225.400108)
					(mid 345.152474 -225.342452)
					(end 345.21013 -225.203258)
				)
				(arc
					(start 345.21013 -225.203258)
					(mid 345.203373 -225.152377)
					(end 345.183714 -225.10496)
				)
			)
		)
	)
	(zone
		(layers "F.Cu" "B.Cu" "In1.Cu" "In2.Cu" "In3.Cu" "In4.Cu" "In5.Cu" "In6.Cu"
			"In7.Cu" "In8.Cu" "In9.Cu" "In10.Cu" "In11.Cu" "In12.Cu" "In13.Cu" "In14.Cu"
			"In15.Cu" "In16.Cu"
		)
		(hatch none 0.5)
		(connect_pads
			(clearance 0)
		)
		(min_thickness 0.25)
		(keepout
			(tracks not_allowed)
			(vias allowed)
			(pads allowed)
			(copperpour not_allowed)
			(footprints allowed)
		)
		(placement
			(enabled no)
			(sheetname "")
		)
		(fill
			(thermal_gap 0.5)
			(thermal_bridge_width 0.5)
			(island_removal_mode 0)
		)
		(polygon
			(pts
				(arc
					(start 54.106318 -400.477228)
					(mid 53.725318 -400.858228)
					(end 54.106318 -401.239228)
				)
				(arc
					(start 54.969918 -401.239228)
					(mid 55.350918 -400.858228)
					(end 54.969918 -400.477228)
				)
			)
		)
	)
	(zone
		(layers "F.Cu" "B.Cu" "In1.Cu" "In2.Cu" "In3.Cu" "In4.Cu" "In5.Cu" "In6.Cu"
			"In7.Cu" "In8.Cu" "In9.Cu" "In10.Cu" "In11.Cu" "In12.Cu" "In13.Cu" "In14.Cu"
			"In15.Cu" "In16.Cu"
		)
		(hatch none 0.5)
		(connect_pads
			(clearance 0)
		)
		(min_thickness 0.25)
		(keepout
			(tracks not_allowed)
			(vias allowed)
			(pads allowed)
			(copperpour not_allowed)
			(footprints allowed)
		)
		(placement
			(enabled no)
			(sheetname "")
		)
		(fill
			(thermal_gap 0.5)
			(thermal_bridge_width 0.5)
			(island_removal_mode 0)
		)
		(polygon
			(pts
				(arc
					(start 343.932764 -224.389442)
					(mid 343.274904 -224.389442)
					(end 343.932764 -224.389442)
				)
			)
		)
	)
	(zone
		(layers "F.Cu" "B.Cu" "In1.Cu" "In2.Cu" "In3.Cu" "In4.Cu" "In5.Cu" "In6.Cu"
			"In7.Cu" "In8.Cu" "In9.Cu" "In10.Cu" "In11.Cu" "In12.Cu" "In13.Cu" "In14.Cu"
			"In15.Cu" "In16.Cu"
		)
		(hatch none 0.5)
		(connect_pads
			(clearance 0)
		)
		(min_thickness 0.25)
		(keepout
			(tracks not_allowed)
			(vias allowed)
			(pads allowed)
			(copperpour not_allowed)
			(footprints allowed)
		)
		(placement
			(enabled no)
			(sheetname "")
		)
		(fill
			(thermal_gap 0.5)
			(thermal_bridge_width 0.5)
			(island_removal_mode 0)
		)
		(polygon
			(pts
				(arc
					(start 365.548164 -224.389442)
					(mid 364.890304 -224.389442)
					(end 365.548164 -224.389442)
				)
			)
		)
	)
	(zone
		(layers "F.Cu" "B.Cu" "In1.Cu" "In2.Cu" "In3.Cu" "In4.Cu" "In5.Cu" "In6.Cu"
			"In7.Cu" "In8.Cu" "In9.Cu" "In10.Cu" "In11.Cu" "In12.Cu" "In13.Cu" "In14.Cu"
			"In15.Cu" "In16.Cu"
		)
		(hatch none 0.5)
		(connect_pads
			(clearance 0)
		)
		(min_thickness 0.25)
		(keepout
			(tracks not_allowed)
			(vias allowed)
			(pads allowed)
			(copperpour not_allowed)
			(footprints allowed)
		)
		(placement
			(enabled no)
			(sheetname "")
		)
		(fill
			(thermal_gap 0.5)
			(thermal_bridge_width 0.5)
			(island_removal_mode 0)
		)
		(polygon
			(pts
				(arc
					(start 91.293188 -214.622634)
					(mid 90.635328 -214.622634)
					(end 91.293188 -214.622634)
				)
			)
		)
	)
	(zone
		(layers "F.Cu" "B.Cu" "In1.Cu" "In2.Cu" "In3.Cu" "In4.Cu" "In5.Cu" "In6.Cu"
			"In7.Cu" "In8.Cu" "In9.Cu" "In10.Cu" "In11.Cu" "In12.Cu" "In13.Cu" "In14.Cu"
			"In15.Cu" "In16.Cu"
		)
		(hatch none 0.5)
		(connect_pads
			(clearance 0)
		)
		(min_thickness 0.25)
		(keepout
			(tracks not_allowed)
			(vias allowed)
			(pads allowed)
			(copperpour not_allowed)
			(footprints allowed)
		)
		(placement
			(enabled no)
			(sheetname "")
		)
		(fill
			(thermal_gap 0.5)
			(thermal_bridge_width 0.5)
			(island_removal_mode 0)
		)
		(polygon
			(pts
				(arc
					(start 106.330496 -224.389442)
					(mid 105.672636 -224.389442)
					(end 106.330496 -224.389442)
				)
			)
		)
	)
	(zone
		(layers "F.Cu" "B.Cu" "In1.Cu" "In2.Cu" "In3.Cu" "In4.Cu" "In5.Cu" "In6.Cu"
			"In7.Cu" "In8.Cu" "In9.Cu" "In10.Cu" "In11.Cu" "In12.Cu" "In13.Cu" "In14.Cu"
			"In15.Cu" "In16.Cu"
		)
		(hatch none 0.5)
		(connect_pads
			(clearance 0)
		)
		(min_thickness 0.25)
		(keepout
			(tracks not_allowed)
			(vias allowed)
			(pads allowed)
			(copperpour not_allowed)
			(footprints allowed)
		)
		(placement
			(enabled no)
			(sheetname "")
		)
		(fill
			(thermal_gap 0.5)
			(thermal_bridge_width 0.5)
			(island_removal_mode 0)
		)
		(polygon
			(pts
				(arc
					(start 371.138704 -288.005012)
					(mid 371.066715 -287.932853)
					(end 370.96827 -287.90646)
				)
				(arc
					(start 370.96827 -287.90646)
					(mid 370.829076 -287.964116)
					(end 370.77142 -288.10331)
				)
				(arc
					(start 370.77142 -288.10331)
					(mid 370.778177 -288.154191)
					(end 370.797836 -288.201608)
				)
				(arc
					(start 371.267482 -289.015424)
					(mid 371.339471 -289.087583)
					(end 371.437916 -289.113976)
				)
				(arc
					(start 371.437916 -289.113976)
					(mid 371.57711 -289.05632)
					(end 371.634766 -288.917126)
				)
				(arc
					(start 371.634766 -288.917126)
					(mid 371.628009 -288.866245)
					(end 371.60835 -288.818828)
				)
			)
		)
	)
	(zone
		(layers "F.Cu" "B.Cu" "In1.Cu" "In2.Cu" "In3.Cu" "In4.Cu" "In5.Cu" "In6.Cu"
			"In7.Cu" "In8.Cu" "In9.Cu" "In10.Cu" "In11.Cu" "In12.Cu" "In13.Cu" "In14.Cu"
			"In15.Cu" "In16.Cu"
		)
		(hatch none 0.5)
		(connect_pads
			(clearance 0)
		)
		(min_thickness 0.25)
		(keepout
			(tracks not_allowed)
			(vias allowed)
			(pads allowed)
			(copperpour not_allowed)
			(footprints allowed)
		)
		(placement
			(enabled no)
			(sheetname "")
		)
		(fill
			(thermal_gap 0.5)
			(thermal_bridge_width 0.5)
			(island_removal_mode 0)
		)
		(polygon
			(pts
				(arc
					(start 112.908588 -214.546434)
					(mid 112.250728 -214.546434)
					(end 112.908588 -214.546434)
				)
			)
		)
	)
	(zone
		(layers "F.Cu" "B.Cu" "In1.Cu" "In2.Cu" "In3.Cu" "In4.Cu" "In5.Cu" "In6.Cu"
			"In7.Cu" "In8.Cu" "In9.Cu" "In10.Cu" "In11.Cu" "In12.Cu" "In13.Cu" "In14.Cu"
			"In15.Cu" "In16.Cu"
		)
		(hatch none 0.5)
		(connect_pads
			(clearance 0)
		)
		(min_thickness 0.25)
		(keepout
			(tracks not_allowed)
			(vias allowed)
			(pads allowed)
			(copperpour not_allowed)
			(footprints allowed)
		)
		(placement
			(enabled no)
			(sheetname "")
		)
		(fill
			(thermal_gap 0.5)
			(thermal_bridge_width 0.5)
			(island_removal_mode 0)
		)
		(polygon
			(pts
				(arc
					(start 340.64321 -217.064336)
					(mid 339.98535 -217.064336)
					(end 340.64321 -217.064336)
				)
			)
		)
	)
	(zone
		(layers "F.Cu" "B.Cu" "In1.Cu" "In2.Cu" "In3.Cu" "In4.Cu" "In5.Cu" "In6.Cu"
			"In7.Cu" "In8.Cu" "In9.Cu" "In10.Cu" "In11.Cu" "In12.Cu" "In13.Cu" "In14.Cu"
			"In15.Cu" "In16.Cu"
		)
		(hatch none 0.5)
		(connect_pads
			(clearance 0)
		)
		(min_thickness 0.25)
		(keepout
			(tracks not_allowed)
			(vias allowed)
			(pads allowed)
			(copperpour not_allowed)
			(footprints allowed)
		)
		(placement
			(enabled no)
			(sheetname "")
		)
		(fill
			(thermal_gap 0.5)
			(thermal_bridge_width 0.5)
			(island_removal_mode 0)
		)
		(polygon
			(pts
				(arc
					(start 119.487696 -224.389442)
					(mid 118.829836 -224.389442)
					(end 119.487696 -224.389442)
				)
			)
		)
	)
	(zone
		(layers "F.Cu" "B.Cu" "In1.Cu" "In2.Cu" "In3.Cu" "In4.Cu" "In5.Cu" "In6.Cu"
			"In7.Cu" "In8.Cu" "In9.Cu" "In10.Cu" "In11.Cu" "In12.Cu" "In13.Cu" "In14.Cu"
			"In15.Cu" "In16.Cu"
		)
		(hatch none 0.5)
		(connect_pads
			(clearance 0)
		)
		(min_thickness 0.25)
		(keepout
			(tracks not_allowed)
			(vias allowed)
			(pads allowed)
			(copperpour not_allowed)
			(footprints allowed)
		)
		(placement
			(enabled no)
			(sheetname "")
		)
		(fill
			(thermal_gap 0.5)
			(thermal_bridge_width 0.5)
			(island_removal_mode 0)
		)
		(polygon
			(pts
				(arc
					(start 369.77701 -221.94774)
					(mid 369.11915 -221.94774)
					(end 369.77701 -221.94774)
				)
			)
		)
	)
	(zone
		(layers "F.Cu" "B.Cu" "In1.Cu" "In2.Cu" "In3.Cu" "In4.Cu" "In5.Cu" "In6.Cu"
			"In7.Cu" "In8.Cu" "In9.Cu" "In10.Cu" "In11.Cu" "In12.Cu" "In13.Cu" "In14.Cu"
			"In15.Cu" "In16.Cu"
		)
		(hatch none 0.5)
		(connect_pads
			(clearance 0)
		)
		(min_thickness 0.25)
		(keepout
			(tracks not_allowed)
			(vias allowed)
			(pads allowed)
			(copperpour not_allowed)
			(footprints allowed)
		)
		(placement
			(enabled no)
			(sheetname "")
		)
		(fill
			(thermal_gap 0.5)
			(thermal_bridge_width 0.5)
			(island_removal_mode 0)
		)
		(polygon
			(pts
				(arc
					(start 227.21824 -123.093988)
					(mid 227.59924 -123.474988)
					(end 227.98024 -123.093988)
				)
				(arc
					(start 227.98024 -122.230388)
					(mid 227.59924 -121.849388)
					(end 227.21824 -122.230388)
				)
			)
		)
	)
	(zone
		(layers "F.Cu" "B.Cu" "In1.Cu" "In2.Cu" "In3.Cu" "In4.Cu" "In5.Cu" "In6.Cu"
			"In7.Cu" "In8.Cu" "In9.Cu" "In10.Cu" "In11.Cu" "In12.Cu" "In13.Cu" "In14.Cu"
			"In15.Cu" "In16.Cu"
		)
		(hatch none 0.5)
		(connect_pads
			(clearance 0)
		)
		(min_thickness 0.25)
		(keepout
			(tracks not_allowed)
			(vias allowed)
			(pads allowed)
			(copperpour not_allowed)
			(footprints allowed)
		)
		(placement
			(enabled no)
			(sheetname "")
		)
		(fill
			(thermal_gap 0.5)
			(thermal_bridge_width 0.5)
			(island_removal_mode 0)
		)
		(polygon
			(pts
				(arc
					(start 112.579658 -214.349584)
					(mid 112.382808 -214.546434)
					(end 112.579658 -214.743284)
				)
				(arc
					(start 113.519458 -214.743284)
					(mid 113.716308 -214.546434)
					(end 113.519458 -214.349584)
				)
			)
		)
	)
	(zone
		(layers "F.Cu" "B.Cu" "In1.Cu" "In2.Cu" "In3.Cu" "In4.Cu" "In5.Cu" "In6.Cu"
			"In7.Cu" "In8.Cu" "In9.Cu" "In10.Cu" "In11.Cu" "In12.Cu" "In13.Cu" "In14.Cu"
			"In15.Cu" "In16.Cu"
		)
		(hatch none 0.5)
		(connect_pads
			(clearance 0)
		)
		(min_thickness 0.25)
		(keepout
			(tracks not_allowed)
			(vias allowed)
			(pads allowed)
			(copperpour not_allowed)
			(footprints allowed)
		)
		(placement
			(enabled no)
			(sheetname "")
		)
		(fill
			(thermal_gap 0.5)
			(thermal_bridge_width 0.5)
			(island_removal_mode 0)
		)
		(polygon
			(pts
				(arc
					(start 133.584696 -217.878406)
					(mid 132.926836 -217.878406)
					(end 133.584696 -217.878406)
				)
			)
		)
	)
	(zone
		(layers "F.Cu" "B.Cu" "In1.Cu" "In2.Cu" "In3.Cu" "In4.Cu" "In5.Cu" "In6.Cu"
			"In7.Cu" "In8.Cu" "In9.Cu" "In10.Cu" "In11.Cu" "In12.Cu" "In13.Cu" "In14.Cu"
			"In15.Cu" "In16.Cu"
		)
		(hatch none 0.5)
		(connect_pads
			(clearance 0)
		)
		(min_thickness 0.25)
		(keepout
			(tracks not_allowed)
			(vias allowed)
			(pads allowed)
			(copperpour not_allowed)
			(footprints allowed)
		)
		(placement
			(enabled no)
			(sheetname "")
		)
		(fill
			(thermal_gap 0.5)
			(thermal_bridge_width 0.5)
			(island_removal_mode 0)
		)
		(polygon
			(pts
				(arc
					(start 337.195668 -221.035626)
					(mid 337.123679 -220.963467)
					(end 337.025234 -220.937074)
				)
				(arc
					(start 337.025234 -220.937074)
					(mid 336.88604 -220.99473)
					(end 336.828384 -221.133924)
				)
				(arc
					(start 336.828384 -221.133924)
					(mid 336.835141 -221.184805)
					(end 336.8548 -221.232222)
				)
				(arc
					(start 337.324446 -222.046038)
					(mid 337.396435 -222.118197)
					(end 337.49488 -222.14459)
				)
				(arc
					(start 337.49488 -222.14459)
					(mid 337.634074 -222.086934)
					(end 337.69173 -221.94774)
				)
				(arc
					(start 337.69173 -221.94774)
					(mid 337.684973 -221.896859)
					(end 337.665314 -221.849442)
				)
			)
		)
	)
	(zone
		(layers "F.Cu" "B.Cu" "In1.Cu" "In2.Cu" "In3.Cu" "In4.Cu" "In5.Cu" "In6.Cu"
			"In7.Cu" "In8.Cu" "In9.Cu" "In10.Cu" "In11.Cu" "In12.Cu" "In13.Cu" "In14.Cu"
			"In15.Cu" "In16.Cu"
		)
		(hatch none 0.5)
		(connect_pads
			(clearance 0)
		)
		(min_thickness 0.25)
		(keepout
			(tracks not_allowed)
			(vias allowed)
			(pads allowed)
			(copperpour not_allowed)
			(footprints allowed)
		)
		(placement
			(enabled no)
			(sheetname "")
		)
		(fill
			(thermal_gap 0.5)
			(thermal_bridge_width 0.5)
			(island_removal_mode 0)
		)
		(polygon
			(pts
				(arc
					(start 376.2121 -0.048006)
					(mid 376.5931 -0.429006)
					(end 376.9741 -0.048006)
				)
				(arc
					(start 376.9741 0.815594)
					(mid 376.5931 1.196594)
					(end 376.2121 0.815594)
				)
			)
		)
	)
	(zone
		(layers "F.Cu" "B.Cu" "In1.Cu" "In2.Cu" "In3.Cu" "In4.Cu" "In5.Cu" "In6.Cu"
			"In7.Cu" "In8.Cu" "In9.Cu" "In10.Cu" "In11.Cu" "In12.Cu" "In13.Cu" "In14.Cu"
			"In15.Cu" "In16.Cu"
		)
		(hatch none 0.5)
		(connect_pads
			(clearance 0)
		)
		(min_thickness 0.25)
		(keepout
			(tracks not_allowed)
			(vias allowed)
			(pads allowed)
			(copperpour not_allowed)
			(footprints allowed)
		)
		(placement
			(enabled no)
			(sheetname "")
		)
		(fill
			(thermal_gap 0.5)
			(thermal_bridge_width 0.5)
			(island_removal_mode 0)
		)
		(polygon
			(pts
				(arc
					(start 308.389528 -409.649168)
					(mid 308.008528 -410.030168)
					(end 308.389528 -410.411168)
				)
				(arc
					(start 309.253128 -410.411168)
					(mid 309.634128 -410.030168)
					(end 309.253128 -409.649168)
				)
			)
		)
	)
	(zone
		(layers "F.Cu" "B.Cu" "In1.Cu" "In2.Cu" "In3.Cu" "In4.Cu" "In5.Cu" "In6.Cu"
			"In7.Cu" "In8.Cu" "In9.Cu" "In10.Cu" "In11.Cu" "In12.Cu" "In13.Cu" "In14.Cu"
			"In15.Cu" "In16.Cu"
		)
		(hatch none 0.5)
		(connect_pads
			(clearance 0)
		)
		(min_thickness 0.25)
		(keepout
			(tracks allowed)
			(vias allowed)
			(pads allowed)
			(copperpour allowed)
			(footprints not_allowed)
		)
		(placement
			(enabled no)
			(sheetname "")
		)
		(fill
			(thermal_gap 0.5)
			(thermal_bridge_width 0.5)
			(island_removal_mode 0)
		)
		(polygon
			(pts
				(arc
					(start 51.052984 -417.770056)
					(mid 45.036994 -411.754066)
					(end 39.021004 -417.770056)
				)
				(arc
					(start 39.021004 -424.470068)
					(mid 45.036994 -430.486058)
					(end 51.052984 -424.470068)
				)
			)
		)
	)
	(zone
		(layers "F.Cu" "B.Cu" "In1.Cu" "In2.Cu" "In3.Cu" "In4.Cu" "In5.Cu" "In6.Cu"
			"In7.Cu" "In8.Cu" "In9.Cu" "In10.Cu" "In11.Cu" "In12.Cu" "In13.Cu" "In14.Cu"
			"In15.Cu" "In16.Cu"
		)
		(hatch none 0.5)
		(connect_pads
			(clearance 0)
		)
		(min_thickness 0.25)
		(keepout
			(tracks not_allowed)
			(vias allowed)
			(pads allowed)
			(copperpour not_allowed)
			(footprints allowed)
		)
		(placement
			(enabled no)
			(sheetname "")
		)
		(fill
			(thermal_gap 0.5)
			(thermal_bridge_width 0.5)
			(island_removal_mode 0)
		)
		(polygon
			(pts
				(arc
					(start 179.39258 -54.618128)
					(mid 179.01158 -54.237128)
					(end 178.63058 -54.618128)
				)
				(arc
					(start 178.63058 -55.481728)
					(mid 179.01158 -55.862728)
					(end 179.39258 -55.481728)
				)
			)
		)
	)
	(zone
		(layers "F.Cu" "B.Cu" "In1.Cu" "In2.Cu" "In3.Cu" "In4.Cu" "In5.Cu" "In6.Cu"
			"In7.Cu" "In8.Cu" "In9.Cu" "In10.Cu" "In11.Cu" "In12.Cu" "In13.Cu" "In14.Cu"
			"In15.Cu" "In16.Cu"
		)
		(hatch none 0.5)
		(connect_pads
			(clearance 0)
		)
		(min_thickness 0.25)
		(keepout
			(tracks not_allowed)
			(vias allowed)
			(pads allowed)
			(copperpour not_allowed)
			(footprints allowed)
		)
		(placement
			(enabled no)
			(sheetname "")
		)
		(fill
			(thermal_gap 0.5)
			(thermal_bridge_width 0.5)
			(island_removal_mode 0)
		)
		(polygon
			(pts
				(arc
					(start 375.72696 -221.231968)
					(mid 375.746644 -221.184558)
					(end 375.753376 -221.13367)
				)
				(arc
					(start 375.753376 -221.13367)
					(mid 375.69572 -220.994476)
					(end 375.556526 -220.93682)
				)
				(arc
					(start 375.556526 -220.93682)
					(mid 375.458095 -220.963236)
					(end 375.386092 -221.035372)
				)
				(arc
					(start 374.916446 -221.849442)
					(mid 374.896762 -221.896852)
					(end 374.89003 -221.94774)
				)
				(arc
					(start 374.89003 -221.94774)
					(mid 374.947686 -222.086934)
					(end 375.08688 -222.14459)
				)
				(arc
					(start 375.08688 -222.14459)
					(mid 375.185311 -222.118174)
					(end 375.257314 -222.046038)
				)
			)
		)
	)
	(zone
		(layers "F.Cu" "B.Cu" "In1.Cu" "In2.Cu" "In3.Cu" "In4.Cu" "In5.Cu" "In6.Cu"
			"In7.Cu" "In8.Cu" "In9.Cu" "In10.Cu" "In11.Cu" "In12.Cu" "In13.Cu" "In14.Cu"
			"In15.Cu" "In16.Cu"
		)
		(hatch none 0.5)
		(connect_pads
			(clearance 0)
		)
		(min_thickness 0.25)
		(keepout
			(tracks not_allowed)
			(vias allowed)
			(pads allowed)
			(copperpour not_allowed)
			(footprints allowed)
		)
		(placement
			(enabled no)
			(sheetname "")
		)
		(fill
			(thermal_gap 0.5)
			(thermal_bridge_width 0.5)
			(island_removal_mode 0)
		)
		(polygon
			(pts
				(arc
					(start 357.401114 -223.67367)
					(mid 357.420798 -223.62626)
					(end 357.42753 -223.575372)
				)
				(arc
					(start 357.42753 -223.575372)
					(mid 357.369874 -223.436178)
					(end 357.23068 -223.378522)
				)
				(arc
					(start 357.23068 -223.378522)
					(mid 357.132249 -223.404938)
					(end 357.060246 -223.477074)
				)
				(arc
					(start 356.5906 -224.291144)
					(mid 356.570916 -224.338554)
					(end 356.564184 -224.389442)
				)
				(arc
					(start 356.564184 -224.389442)
					(mid 356.62184 -224.528636)
					(end 356.761034 -224.586292)
				)
				(arc
					(start 356.761034 -224.586292)
					(mid 356.859465 -224.559876)
					(end 356.931468 -224.48774)
				)
			)
		)
	)
	(zone
		(layers "F.Cu" "B.Cu" "In1.Cu" "In2.Cu" "In3.Cu" "In4.Cu" "In5.Cu" "In6.Cu"
			"In7.Cu" "In8.Cu" "In9.Cu" "In10.Cu" "In11.Cu" "In12.Cu" "In13.Cu" "In14.Cu"
			"In15.Cu" "In16.Cu"
		)
		(hatch none 0.5)
		(connect_pads
			(clearance 0)
		)
		(min_thickness 0.25)
		(keepout
			(tracks not_allowed)
			(vias allowed)
			(pads allowed)
			(copperpour not_allowed)
			(footprints allowed)
		)
		(placement
			(enabled no)
			(sheetname "")
		)
		(fill
			(thermal_gap 0.5)
			(thermal_bridge_width 0.5)
			(island_removal_mode 0)
		)
		(polygon
			(pts
				(arc
					(start 150.787354 -400.477228)
					(mid 150.406354 -400.858228)
					(end 150.787354 -401.239228)
				)
				(arc
					(start 151.650954 -401.239228)
					(mid 152.031954 -400.858228)
					(end 151.650954 -400.477228)
				)
			)
		)
	)
	(zone
		(layers "F.Cu" "B.Cu" "In1.Cu" "In2.Cu" "In3.Cu" "In4.Cu" "In5.Cu" "In6.Cu"
			"In7.Cu" "In8.Cu" "In9.Cu" "In10.Cu" "In11.Cu" "In12.Cu" "In13.Cu" "In14.Cu"
			"In15.Cu" "In16.Cu"
		)
		(hatch none 0.5)
		(connect_pads
			(clearance 0)
		)
		(min_thickness 0.25)
		(keepout
			(tracks not_allowed)
			(vias allowed)
			(pads allowed)
			(copperpour not_allowed)
			(footprints allowed)
		)
		(placement
			(enabled no)
			(sheetname "")
		)
		(fill
			(thermal_gap 0.5)
			(thermal_bridge_width 0.5)
			(island_removal_mode 0)
		)
		(polygon
			(pts
				(arc
					(start 109.461046 -217.162634)
					(mid 109.48073 -217.115224)
					(end 109.487462 -217.064336)
				)
				(arc
					(start 109.487462 -217.064336)
					(mid 109.429806 -216.925142)
					(end 109.290612 -216.867486)
				)
				(arc
					(start 109.290612 -216.867486)
					(mid 109.192181 -216.893902)
					(end 109.120178 -216.966038)
				)
				(arc
					(start 108.650532 -217.780108)
					(mid 108.630848 -217.827518)
					(end 108.624116 -217.878406)
				)
				(arc
					(start 108.624116 -217.878406)
					(mid 108.681772 -218.0176)
					(end 108.820966 -218.075256)
				)
				(arc
					(start 108.820966 -218.075256)
					(mid 108.919397 -218.04884)
					(end 108.9914 -217.976704)
				)
			)
		)
	)
	(zone
		(layers "F.Cu" "B.Cu" "In1.Cu" "In2.Cu" "In3.Cu" "In4.Cu" "In5.Cu" "In6.Cu"
			"In7.Cu" "In8.Cu" "In9.Cu" "In10.Cu" "In11.Cu" "In12.Cu" "In13.Cu" "In14.Cu"
			"In15.Cu" "In16.Cu"
		)
		(hatch none 0.5)
		(connect_pads
			(clearance 0)
		)
		(min_thickness 0.25)
		(keepout
			(tracks not_allowed)
			(vias allowed)
			(pads allowed)
			(copperpour not_allowed)
			(footprints allowed)
		)
		(placement
			(enabled no)
			(sheetname "")
		)
		(fill
			(thermal_gap 0.5)
			(thermal_bridge_width 0.5)
			(island_removal_mode 0)
		)
		(polygon
			(pts
				(arc
					(start 364.608364 -221.133924)
					(mid 363.950504 -221.133924)
					(end 364.608364 -221.133924)
				)
			)
		)
	)
	(zone
		(layers "F.Cu" "B.Cu" "In1.Cu" "In2.Cu" "In3.Cu" "In4.Cu" "In5.Cu" "In6.Cu"
			"In7.Cu" "In8.Cu" "In9.Cu" "In10.Cu" "In11.Cu" "In12.Cu" "In13.Cu" "In14.Cu"
			"In15.Cu" "In16.Cu"
		)
		(hatch none 0.5)
		(connect_pads
			(clearance 0)
		)
		(min_thickness 0.25)
		(keepout
			(tracks not_allowed)
			(vias allowed)
			(pads allowed)
			(copperpour not_allowed)
			(footprints allowed)
		)
		(placement
			(enabled no)
			(sheetname "")
		)
		(fill
			(thermal_gap 0.5)
			(thermal_bridge_width 0.5)
			(island_removal_mode 0)
		)
		(polygon
			(pts
				(arc
					(start 95.804482 -220.319854)
					(mid 96.462342 -220.319854)
					(end 95.804482 -220.319854)
				)
			)
		)
	)
	(zone
		(layers "F.Cu" "B.Cu" "In1.Cu" "In2.Cu" "In3.Cu" "In4.Cu" "In5.Cu" "In6.Cu"
			"In7.Cu" "In8.Cu" "In9.Cu" "In10.Cu" "In11.Cu" "In12.Cu" "In13.Cu" "In14.Cu"
			"In15.Cu" "In16.Cu"
		)
		(hatch none 0.5)
		(connect_pads
			(clearance 0)
		)
		(min_thickness 0.25)
		(keepout
			(tracks not_allowed)
			(vias allowed)
			(pads allowed)
			(copperpour not_allowed)
			(footprints allowed)
		)
		(placement
			(enabled no)
			(sheetname "")
		)
		(fill
			(thermal_gap 0.5)
			(thermal_bridge_width 0.5)
			(island_removal_mode 0)
		)
		(polygon
			(pts
				(arc
					(start 357.669592 -274.266914)
					(mid 357.011732 -274.266914)
					(end 357.669592 -274.266914)
				)
			)
		)
	)
	(zone
		(layers "F.Cu" "B.Cu" "In1.Cu" "In2.Cu" "In3.Cu" "In4.Cu" "In5.Cu" "In6.Cu"
			"In7.Cu" "In8.Cu" "In9.Cu" "In10.Cu" "In11.Cu" "In12.Cu" "In13.Cu" "In14.Cu"
			"In15.Cu" "In16.Cu"
		)
		(hatch none 0.5)
		(connect_pads
			(clearance 0)
		)
		(min_thickness 0.25)
		(keepout
			(tracks not_allowed)
			(vias allowed)
			(pads allowed)
			(copperpour not_allowed)
			(footprints allowed)
		)
		(placement
			(enabled no)
			(sheetname "")
		)
		(fill
			(thermal_gap 0.5)
			(thermal_bridge_width 0.5)
			(island_removal_mode 0)
		)
		(polygon
			(pts
				(arc
					(start 239.279938 -117.224048)
					(mid 238.898938 -117.605048)
					(end 239.279938 -117.986048)
				)
				(arc
					(start 240.143538 -117.986048)
					(mid 240.524538 -117.605048)
					(end 240.143538 -117.224048)
				)
			)
		)
	)
	(zone
		(layers "F.Cu" "B.Cu" "In1.Cu" "In2.Cu" "In3.Cu" "In4.Cu" "In5.Cu" "In6.Cu"
			"In7.Cu" "In8.Cu" "In9.Cu" "In10.Cu" "In11.Cu" "In12.Cu" "In13.Cu" "In14.Cu"
			"In15.Cu" "In16.Cu"
		)
		(hatch none 0.5)
		(connect_pads
			(clearance 0)
		)
		(min_thickness 0.25)
		(keepout
			(tracks not_allowed)
			(vias allowed)
			(pads allowed)
			(copperpour not_allowed)
			(footprints allowed)
		)
		(placement
			(enabled no)
			(sheetname "")
		)
		(fill
			(thermal_gap 0.5)
			(thermal_bridge_width 0.5)
			(island_removal_mode 0)
		)
		(polygon
			(pts
				(arc
					(start 152.133554 -409.649168)
					(mid 151.752554 -410.030168)
					(end 152.133554 -410.411168)
				)
				(arc
					(start 152.997154 -410.411168)
					(mid 153.378154 -410.030168)
					(end 152.997154 -409.649168)
				)
			)
		)
	)
	(zone
		(layers "F.Cu" "B.Cu" "In1.Cu" "In2.Cu" "In3.Cu" "In4.Cu" "In5.Cu" "In6.Cu"
			"In7.Cu" "In8.Cu" "In9.Cu" "In10.Cu" "In11.Cu" "In12.Cu" "In13.Cu" "In14.Cu"
			"In15.Cu" "In16.Cu"
		)
		(hatch none 0.5)
		(connect_pads
			(clearance 0)
		)
		(min_thickness 0.25)
		(keepout
			(tracks not_allowed)
			(vias allowed)
			(pads allowed)
			(copperpour not_allowed)
			(footprints allowed)
		)
		(placement
			(enabled no)
			(sheetname "")
		)
		(fill
			(thermal_gap 0.5)
			(thermal_bridge_width 0.5)
			(island_removal_mode 0)
		)
		(polygon
			(pts
				(arc
					(start 149.070314 -409.649168)
					(mid 148.689314 -410.030168)
					(end 149.070314 -410.411168)
				)
				(arc
					(start 149.933914 -410.411168)
					(mid 150.314914 -410.030168)
					(end 149.933914 -409.649168)
				)
			)
		)
	)
	(zone
		(layers "F.Cu" "B.Cu" "In1.Cu" "In2.Cu" "In3.Cu" "In4.Cu" "In5.Cu" "In6.Cu"
			"In7.Cu" "In8.Cu" "In9.Cu" "In10.Cu" "In11.Cu" "In12.Cu" "In13.Cu" "In14.Cu"
			"In15.Cu" "In16.Cu"
		)
		(hatch none 0.5)
		(connect_pads
			(clearance 0)
		)
		(min_thickness 0.25)
		(keepout
			(tracks not_allowed)
			(vias allowed)
			(pads allowed)
			(copperpour not_allowed)
			(footprints allowed)
		)
		(placement
			(enabled no)
			(sheetname "")
		)
		(fill
			(thermal_gap 0.5)
			(thermal_bridge_width 0.5)
			(island_removal_mode 0)
		)
		(polygon
			(pts
				(arc
					(start 187.50534 -153.375868)
					(mid 187.12434 -152.994868)
					(end 186.74334 -153.375868)
				)
				(arc
					(start 186.74334 -154.239468)
					(mid 187.12434 -154.620468)
					(end 187.50534 -154.239468)
				)
			)
		)
	)
	(zone
		(layers "F.Cu" "B.Cu" "In1.Cu" "In2.Cu" "In3.Cu" "In4.Cu" "In5.Cu" "In6.Cu"
			"In7.Cu" "In8.Cu" "In9.Cu" "In10.Cu" "In11.Cu" "In12.Cu" "In13.Cu" "In14.Cu"
			"In15.Cu" "In16.Cu"
		)
		(hatch none 0.5)
		(connect_pads
			(clearance 0)
		)
		(min_thickness 0.25)
		(keepout
			(tracks not_allowed)
			(vias allowed)
			(pads allowed)
			(copperpour not_allowed)
			(footprints allowed)
		)
		(placement
			(enabled no)
			(sheetname "")
		)
		(fill
			(thermal_gap 0.5)
			(thermal_bridge_width 0.5)
			(island_removal_mode 0)
		)
		(polygon
			(pts
				(arc
					(start 226.298506 -124.358146)
					(mid 225.917506 -123.977146)
					(end 225.536506 -124.358146)
				)
				(arc
					(start 225.536506 -125.221746)
					(mid 225.917506 -125.602746)
					(end 226.298506 -125.221746)
				)
			)
		)
	)
	(zone
		(layers "F.Cu" "B.Cu" "In1.Cu" "In2.Cu" "In3.Cu" "In4.Cu" "In5.Cu" "In6.Cu"
			"In7.Cu" "In8.Cu" "In9.Cu" "In10.Cu" "In11.Cu" "In12.Cu" "In13.Cu" "In14.Cu"
			"In15.Cu" "In16.Cu"
		)
		(hatch none 0.5)
		(connect_pads
			(clearance 0)
		)
		(min_thickness 0.25)
		(keepout
			(tracks not_allowed)
			(vias allowed)
			(pads allowed)
			(copperpour not_allowed)
			(footprints allowed)
		)
		(placement
			(enabled no)
			(sheetname "")
		)
		(fill
			(thermal_gap 0.5)
			(thermal_bridge_width 0.5)
			(island_removal_mode 0)
		)
		(polygon
			(pts
				(arc
					(start 395.92885 -403.502876)
					(mid 395.54785 -403.883876)
					(end 395.92885 -404.264876)
				)
				(arc
					(start 396.79245 -404.264876)
					(mid 397.17345 -403.883876)
					(end 396.79245 -403.502876)
				)
			)
		)
	)
	(zone
		(layers "F.Cu" "B.Cu" "In1.Cu" "In2.Cu" "In3.Cu" "In4.Cu" "In5.Cu" "In6.Cu"
			"In7.Cu" "In8.Cu" "In9.Cu" "In10.Cu" "In11.Cu" "In12.Cu" "In13.Cu" "In14.Cu"
			"In15.Cu" "In16.Cu"
		)
		(hatch none 0.5)
		(connect_pads
			(clearance 0)
		)
		(min_thickness 0.25)
		(keepout
			(tracks not_allowed)
			(vias allowed)
			(pads allowed)
			(copperpour not_allowed)
			(footprints allowed)
		)
		(placement
			(enabled no)
			(sheetname "")
		)
		(fill
			(thermal_gap 0.5)
			(thermal_bridge_width 0.5)
			(island_removal_mode 0)
		)
		(polygon
			(pts
				(arc
					(start 381.945896 -285.759652)
					(mid 381.96558 -285.712242)
					(end 381.972312 -285.661354)
				)
				(arc
					(start 381.972312 -285.661354)
					(mid 381.914656 -285.52216)
					(end 381.775462 -285.464504)
				)
				(arc
					(start 381.775462 -285.464504)
					(mid 381.677031 -285.49092)
					(end 381.605028 -285.563056)
				)
				(arc
					(start 381.135382 -286.377126)
					(mid 381.115698 -286.424536)
					(end 381.108966 -286.475424)
				)
				(arc
					(start 381.108966 -286.475424)
					(mid 381.166622 -286.614618)
					(end 381.305816 -286.672274)
				)
				(arc
					(start 381.305816 -286.672274)
					(mid 381.404247 -286.645858)
					(end 381.47625 -286.573722)
				)
			)
		)
	)
	(zone
		(layers "F.Cu" "B.Cu" "In1.Cu" "In2.Cu" "In3.Cu" "In4.Cu" "In5.Cu" "In6.Cu"
			"In7.Cu" "In8.Cu" "In9.Cu" "In10.Cu" "In11.Cu" "In12.Cu" "In13.Cu" "In14.Cu"
			"In15.Cu" "In16.Cu"
		)
		(hatch none 0.5)
		(connect_pads
			(clearance 0)
		)
		(min_thickness 0.25)
		(keepout
			(tracks not_allowed)
			(vias allowed)
			(pads allowed)
			(copperpour not_allowed)
			(footprints allowed)
		)
		(placement
			(enabled no)
			(sheetname "")
		)
		(fill
			(thermal_gap 0.5)
			(thermal_bridge_width 0.5)
			(island_removal_mode 0)
		)
		(polygon
			(pts
				(arc
					(start 63.296038 -403.502876)
					(mid 62.915038 -403.883876)
					(end 63.296038 -404.264876)
				)
				(arc
					(start 64.159638 -404.264876)
					(mid 64.540638 -403.883876)
					(end 64.159638 -403.502876)
				)
			)
		)
	)
	(zone
		(layers "F.Cu" "B.Cu" "In1.Cu" "In2.Cu" "In3.Cu" "In4.Cu" "In5.Cu" "In6.Cu"
			"In7.Cu" "In8.Cu" "In9.Cu" "In10.Cu" "In11.Cu" "In12.Cu" "In13.Cu" "In14.Cu"
			"In15.Cu" "In16.Cu"
		)
		(hatch none 0.5)
		(connect_pads
			(clearance 0)
		)
		(min_thickness 0.25)
		(keepout
			(tracks not_allowed)
			(vias allowed)
			(pads allowed)
			(copperpour not_allowed)
			(footprints allowed)
		)
		(placement
			(enabled no)
			(sheetname "")
		)
		(fill
			(thermal_gap 0.5)
			(thermal_bridge_width 0.5)
			(island_removal_mode 0)
		)
		(polygon
			(pts
				(arc
					(start 337.463892 -288.103056)
					(mid 336.806032 -288.103056)
					(end 337.463892 -288.103056)
				)
			)
		)
	)
	(zone
		(layers "F.Cu" "B.Cu" "In1.Cu" "In2.Cu" "In3.Cu" "In4.Cu" "In5.Cu" "In6.Cu"
			"In7.Cu" "In8.Cu" "In9.Cu" "In10.Cu" "In11.Cu" "In12.Cu" "In13.Cu" "In14.Cu"
			"In15.Cu" "In16.Cu"
		)
		(hatch none 0.5)
		(connect_pads
			(clearance 0)
		)
		(min_thickness 0.25)
		(keepout
			(tracks not_allowed)
			(vias allowed)
			(pads allowed)
			(copperpour not_allowed)
			(footprints allowed)
		)
		(placement
			(enabled no)
			(sheetname "")
		)
		(fill
			(thermal_gap 0.5)
			(thermal_bridge_width 0.5)
			(island_removal_mode 0)
		)
		(polygon
			(pts
				(arc
					(start 101.161342 -221.94774)
					(mid 100.503482 -221.94774)
					(end 101.161342 -221.94774)
				)
			)
		)
	)
	(zone
		(layers "F.Cu" "B.Cu" "In1.Cu" "In2.Cu" "In3.Cu" "In4.Cu" "In5.Cu" "In6.Cu"
			"In7.Cu" "In8.Cu" "In9.Cu" "In10.Cu" "In11.Cu" "In12.Cu" "In13.Cu" "In14.Cu"
			"In15.Cu" "In16.Cu"
		)
		(hatch none 0.5)
		(connect_pads
			(clearance 0)
		)
		(min_thickness 0.25)
		(keepout
			(tracks not_allowed)
			(vias allowed)
			(pads allowed)
			(copperpour not_allowed)
			(footprints allowed)
		)
		(placement
			(enabled no)
			(sheetname "")
		)
		(fill
			(thermal_gap 0.5)
			(thermal_bridge_width 0.5)
			(island_removal_mode 0)
		)
		(polygon
			(pts
				(arc
					(start 61.578998 -406.62352)
					(mid 61.197998 -407.00452)
					(end 61.578998 -407.38552)
				)
				(arc
					(start 62.442598 -407.38552)
					(mid 62.823598 -407.00452)
					(end 62.442598 -406.62352)
				)
			)
		)
	)
	(zone
		(layers "F.Cu" "B.Cu" "In1.Cu" "In2.Cu" "In3.Cu" "In4.Cu" "In5.Cu" "In6.Cu"
			"In7.Cu" "In8.Cu" "In9.Cu" "In10.Cu" "In11.Cu" "In12.Cu" "In13.Cu" "In14.Cu"
			"In15.Cu" "In16.Cu"
		)
		(hatch none 0.5)
		(connect_pads
			(clearance 0)
		)
		(min_thickness 0.25)
		(keepout
			(tracks allowed)
			(vias allowed)
			(pads allowed)
			(copperpour allowed)
			(footprints not_allowed)
		)
		(placement
			(enabled no)
			(sheetname "")
		)
		(fill
			(thermal_gap 0.5)
			(thermal_bridge_width 0.5)
			(island_removal_mode 0)
		)
		(polygon
			(pts
				(arc
					(start 420.762938 -424.470068)
					(mid 426.778928 -430.486058)
					(end 432.794918 -424.470068)
				)
				(arc
					(start 432.794918 -417.770056)
					(mid 426.778928 -411.754066)
					(end 420.762938 -417.770056)
				)
			)
		)
	)
	(zone
		(layers "F.Cu" "B.Cu" "In1.Cu" "In2.Cu" "In3.Cu" "In4.Cu" "In5.Cu" "In6.Cu"
			"In7.Cu" "In8.Cu" "In9.Cu" "In10.Cu" "In11.Cu" "In12.Cu" "In13.Cu" "In14.Cu"
			"In15.Cu" "In16.Cu"
		)
		(hatch none 0.5)
		(connect_pads
			(clearance 0)
		)
		(min_thickness 0.25)
		(keepout
			(tracks not_allowed)
			(vias allowed)
			(pads allowed)
			(copperpour not_allowed)
			(footprints allowed)
		)
		(placement
			(enabled no)
			(sheetname "")
		)
		(fill
			(thermal_gap 0.5)
			(thermal_bridge_width 0.5)
			(island_removal_mode 0)
		)
		(polygon
			(pts
				(arc
					(start 123.356878 -288.103056)
					(mid 122.699018 -288.103056)
					(end 123.356878 -288.103056)
				)
			)
		)
	)
	(zone
		(layers "F.Cu" "B.Cu" "In1.Cu" "In2.Cu" "In3.Cu" "In4.Cu" "In5.Cu" "In6.Cu"
			"In7.Cu" "In8.Cu" "In9.Cu" "In10.Cu" "In11.Cu" "In12.Cu" "In13.Cu" "In14.Cu"
			"In15.Cu" "In16.Cu"
		)
		(hatch none 0.5)
		(connect_pads
			(clearance 0)
		)
		(min_thickness 0.25)
		(keepout
			(tracks not_allowed)
			(vias allowed)
			(pads allowed)
			(copperpour not_allowed)
			(footprints allowed)
		)
		(placement
			(enabled no)
			(sheetname "")
		)
		(fill
			(thermal_gap 0.5)
			(thermal_bridge_width 0.5)
			(island_removal_mode 0)
		)
		(polygon
			(pts
				(arc
					(start 367.37925 -284.74924)
					(mid 367.307261 -284.677081)
					(end 367.208816 -284.650688)
				)
				(arc
					(start 367.208816 -284.650688)
					(mid 367.069622 -284.708344)
					(end 367.011966 -284.847538)
				)
				(arc
					(start 367.011966 -284.847538)
					(mid 367.018723 -284.898419)
					(end 367.038382 -284.945836)
				)
				(arc
					(start 367.508028 -285.759652)
					(mid 367.580017 -285.831811)
					(end 367.678462 -285.858204)
				)
				(arc
					(start 367.678462 -285.858204)
					(mid 367.817656 -285.800548)
					(end 367.875312 -285.661354)
				)
				(arc
					(start 367.875312 -285.661354)
					(mid 367.868555 -285.610473)
					(end 367.848896 -285.563056)
				)
			)
		)
	)
	(zone
		(layers "F.Cu" "B.Cu" "In1.Cu" "In2.Cu" "In3.Cu" "In4.Cu" "In5.Cu" "In6.Cu"
			"In7.Cu" "In8.Cu" "In9.Cu" "In10.Cu" "In11.Cu" "In12.Cu" "In13.Cu" "In14.Cu"
			"In15.Cu" "In16.Cu"
		)
		(hatch none 0.5)
		(connect_pads
			(clearance 0)
		)
		(min_thickness 0.25)
		(keepout
			(tracks not_allowed)
			(vias allowed)
			(pads allowed)
			(copperpour not_allowed)
			(footprints allowed)
		)
		(placement
			(enabled no)
			(sheetname "")
		)
		(fill
			(thermal_gap 0.5)
			(thermal_bridge_width 0.5)
			(island_removal_mode 0)
		)
		(polygon
			(pts
				(arc
					(start 121.758964 -289.807142)
					(mid 122.416824 -289.807142)
					(end 121.758964 -289.807142)
				)
			)
		)
	)
	(zone
		(layers "F.Cu" "B.Cu" "In1.Cu" "In2.Cu" "In3.Cu" "In4.Cu" "In5.Cu" "In6.Cu"
			"In7.Cu" "In8.Cu" "In9.Cu" "In10.Cu" "In11.Cu" "In12.Cu" "In13.Cu" "In14.Cu"
			"In15.Cu" "In16.Cu"
		)
		(hatch none 0.5)
		(connect_pads
			(clearance 0)
		)
		(min_thickness 0.25)
		(keepout
			(tracks not_allowed)
			(vias allowed)
			(pads allowed)
			(copperpour not_allowed)
			(footprints allowed)
		)
		(placement
			(enabled no)
			(sheetname "")
		)
		(fill
			(thermal_gap 0.5)
			(thermal_bridge_width 0.5)
			(island_removal_mode 0)
		)
		(polygon
			(pts
				(arc
					(start 35.091878 -18.75536)
					(mid 34.710878 -19.13636)
					(end 35.091878 -19.51736)
				)
				(arc
					(start 35.955478 -19.51736)
					(mid 36.336478 -19.13636)
					(end 35.955478 -18.75536)
				)
			)
		)
	)
	(zone
		(layers "F.Cu" "B.Cu" "In1.Cu" "In2.Cu" "In3.Cu" "In4.Cu" "In5.Cu" "In6.Cu"
			"In7.Cu" "In8.Cu" "In9.Cu" "In10.Cu" "In11.Cu" "In12.Cu" "In13.Cu" "In14.Cu"
			"In15.Cu" "In16.Cu"
		)
		(hatch none 0.5)
		(connect_pads
			(clearance 0)
		)
		(min_thickness 0.25)
		(keepout
			(tracks not_allowed)
			(vias allowed)
			(pads allowed)
			(copperpour not_allowed)
			(footprints allowed)
		)
		(placement
			(enabled no)
			(sheetname "")
		)
		(fill
			(thermal_gap 0.5)
			(thermal_bridge_width 0.5)
			(island_removal_mode 0)
		)
		(polygon
			(pts
				(arc
					(start 344.243914 -220.418152)
					(mid 344.263598 -220.370742)
					(end 344.27033 -220.319854)
				)
				(arc
					(start 344.27033 -220.319854)
					(mid 344.212674 -220.18066)
					(end 344.07348 -220.123004)
				)
				(arc
					(start 344.07348 -220.123004)
					(mid 343.975049 -220.14942)
					(end 343.903046 -220.221556)
				)
				(arc
					(start 343.4334 -221.035626)
					(mid 343.413716 -221.083036)
					(end 343.406984 -221.133924)
				)
				(arc
					(start 343.406984 -221.133924)
					(mid 343.46464 -221.273118)
					(end 343.603834 -221.330774)
				)
				(arc
					(start 343.603834 -221.330774)
					(mid 343.702265 -221.304358)
					(end 343.774268 -221.232222)
				)
			)
		)
	)
	(zone
		(layers "F.Cu" "B.Cu" "In1.Cu" "In2.Cu" "In3.Cu" "In4.Cu" "In5.Cu" "In6.Cu"
			"In7.Cu" "In8.Cu" "In9.Cu" "In10.Cu" "In11.Cu" "In12.Cu" "In13.Cu" "In14.Cu"
			"In15.Cu" "In16.Cu"
		)
		(hatch none 0.5)
		(connect_pads
			(clearance 0)
		)
		(min_thickness 0.25)
		(keepout
			(tracks not_allowed)
			(vias allowed)
			(pads allowed)
			(copperpour not_allowed)
			(footprints allowed)
		)
		(placement
			(enabled no)
			(sheetname "")
		)
		(fill
			(thermal_gap 0.5)
			(thermal_bridge_width 0.5)
			(island_removal_mode 0)
		)
		(polygon
			(pts
				(arc
					(start 342.632792 -285.661354)
					(mid 341.974932 -285.661354)
					(end 342.632792 -285.661354)
				)
			)
		)
	)
	(zone
		(layers "F.Cu" "B.Cu" "In1.Cu" "In2.Cu" "In3.Cu" "In4.Cu" "In5.Cu" "In6.Cu"
			"In7.Cu" "In8.Cu" "In9.Cu" "In10.Cu" "In11.Cu" "In12.Cu" "In13.Cu" "In14.Cu"
			"In15.Cu" "In16.Cu"
		)
		(hatch none 0.5)
		(connect_pads
			(clearance 0)
		)
		(min_thickness 0.25)
		(keepout
			(tracks not_allowed)
			(vias allowed)
			(pads allowed)
			(copperpour not_allowed)
			(footprints allowed)
		)
		(placement
			(enabled no)
			(sheetname "")
		)
		(fill
			(thermal_gap 0.5)
			(thermal_bridge_width 0.5)
			(island_removal_mode 0)
		)
		(polygon
			(pts
				(arc
					(start 363.040422 -220.22181)
					(mid 362.968433 -220.149651)
					(end 362.869988 -220.123258)
				)
				(arc
					(start 362.869988 -220.123258)
					(mid 362.730794 -220.180914)
					(end 362.673138 -220.320108)
				)
				(arc
					(start 362.673138 -220.320108)
					(mid 362.679895 -220.370989)
					(end 362.699554 -220.418406)
				)
				(arc
					(start 363.1692 -221.232222)
					(mid 363.241189 -221.304381)
					(end 363.339634 -221.330774)
				)
				(arc
					(start 363.339634 -221.330774)
					(mid 363.478828 -221.273118)
					(end 363.536484 -221.133924)
				)
				(arc
					(start 363.536484 -221.133924)
					(mid 363.529727 -221.083043)
					(end 363.510068 -221.035626)
				)
			)
		)
	)
	(zone
		(layers "F.Cu" "B.Cu" "In1.Cu" "In2.Cu" "In3.Cu" "In4.Cu" "In5.Cu" "In6.Cu"
			"In7.Cu" "In8.Cu" "In9.Cu" "In10.Cu" "In11.Cu" "In12.Cu" "In13.Cu" "In14.Cu"
			"In15.Cu" "In16.Cu"
		)
		(hatch none 0.5)
		(connect_pads
			(clearance 0)
		)
		(min_thickness 0.25)
		(keepout
			(tracks not_allowed)
			(vias allowed)
			(pads allowed)
			(copperpour not_allowed)
			(footprints allowed)
		)
		(placement
			(enabled no)
			(sheetname "")
		)
		(fill
			(thermal_gap 0.5)
			(thermal_bridge_width 0.5)
			(island_removal_mode 0)
		)
		(polygon
			(pts
				(arc
					(start 49.326038 -406.62352)
					(mid 48.945038 -407.00452)
					(end 49.326038 -407.38552)
				)
				(arc
					(start 50.189638 -407.38552)
					(mid 50.570638 -407.00452)
					(end 50.189638 -406.62352)
				)
			)
		)
	)
	(zone
		(layers "F.Cu" "B.Cu" "In1.Cu" "In2.Cu" "In3.Cu" "In4.Cu" "In5.Cu" "In6.Cu"
			"In7.Cu" "In8.Cu" "In9.Cu" "In10.Cu" "In11.Cu" "In12.Cu" "In13.Cu" "In14.Cu"
			"In15.Cu" "In16.Cu"
		)
		(hatch none 0.5)
		(connect_pads
			(clearance 0)
		)
		(min_thickness 0.25)
		(keepout
			(tracks not_allowed)
			(vias allowed)
			(pads allowed)
			(copperpour not_allowed)
			(footprints allowed)
		)
		(placement
			(enabled no)
			(sheetname "")
		)
		(fill
			(thermal_gap 0.5)
			(thermal_bridge_width 0.5)
			(island_removal_mode 0)
		)
		(polygon
			(pts
				(arc
					(start 382.104392 -285.661354)
					(mid 381.446532 -285.661354)
					(end 382.104392 -285.661354)
				)
			)
		)
	)
	(zone
		(layers "F.Cu" "B.Cu" "In1.Cu" "In2.Cu" "In3.Cu" "In4.Cu" "In5.Cu" "In6.Cu"
			"In7.Cu" "In8.Cu" "In9.Cu" "In10.Cu" "In11.Cu" "In12.Cu" "In13.Cu" "In14.Cu"
			"In15.Cu" "In16.Cu"
		)
		(hatch none 0.5)
		(connect_pads
			(clearance 0)
		)
		(min_thickness 0.25)
		(keepout
			(tracks not_allowed)
			(vias allowed)
			(pads allowed)
			(copperpour not_allowed)
			(footprints allowed)
		)
		(placement
			(enabled no)
			(sheetname "")
		)
		(fill
			(thermal_gap 0.5)
			(thermal_bridge_width 0.5)
			(island_removal_mode 0)
		)
		(polygon
			(pts
				(arc
					(start 182.422292 -53.091334)
					(mid 182.041292 -52.710334)
					(end 181.660292 -53.091334)
				)
				(arc
					(start 181.660292 -53.954934)
					(mid 182.041292 -54.335934)
					(end 182.422292 -53.954934)
				)
			)
		)
	)
	(zone
		(layers "F.Cu" "B.Cu" "In1.Cu" "In2.Cu" "In3.Cu" "In4.Cu" "In5.Cu" "In6.Cu"
			"In7.Cu" "In8.Cu" "In9.Cu" "In10.Cu" "In11.Cu" "In12.Cu" "In13.Cu" "In14.Cu"
			"In15.Cu" "In16.Cu"
		)
		(hatch none 0.5)
		(connect_pads
			(clearance 0)
		)
		(min_thickness 0.25)
		(keepout
			(tracks not_allowed)
			(vias allowed)
			(pads allowed)
			(copperpour not_allowed)
			(footprints allowed)
		)
		(placement
			(enabled no)
			(sheetname "")
		)
		(fill
			(thermal_gap 0.5)
			(thermal_bridge_width 0.5)
			(island_removal_mode 0)
		)
		(polygon
			(pts
				(arc
					(start 164.386514 -406.62352)
					(mid 164.005514 -407.00452)
					(end 164.386514 -407.38552)
				)
				(arc
					(start 165.250114 -407.38552)
					(mid 165.631114 -407.00452)
					(end 165.250114 -406.62352)
				)
			)
		)
	)
	(zone
		(layers "F.Cu" "B.Cu" "In1.Cu" "In2.Cu" "In3.Cu" "In4.Cu" "In5.Cu" "In6.Cu"
			"In7.Cu" "In8.Cu" "In9.Cu" "In10.Cu" "In11.Cu" "In12.Cu" "In13.Cu" "In14.Cu"
			"In15.Cu" "In16.Cu"
		)
		(hatch none 0.5)
		(connect_pads
			(clearance 0)
		)
		(min_thickness 0.25)
		(keepout
			(tracks not_allowed)
			(vias allowed)
			(pads allowed)
			(copperpour not_allowed)
			(footprints allowed)
		)
		(placement
			(enabled no)
			(sheetname "")
		)
		(fill
			(thermal_gap 0.5)
			(thermal_bridge_width 0.5)
			(island_removal_mode 0)
		)
		(polygon
			(pts
				(arc
					(start 371.65661 -218.692222)
					(mid 370.99875 -218.692222)
					(end 371.65661 -218.692222)
				)
			)
		)
	)
	(zone
		(layers "F.Cu" "B.Cu" "In1.Cu" "In2.Cu" "In3.Cu" "In4.Cu" "In5.Cu" "In6.Cu"
			"In7.Cu" "In8.Cu" "In9.Cu" "In10.Cu" "In11.Cu" "In12.Cu" "In13.Cu" "In14.Cu"
			"In15.Cu" "In16.Cu"
		)
		(hatch none 0.5)
		(connect_pads
			(clearance 0)
		)
		(min_thickness 0.25)
		(keepout
			(tracks not_allowed)
			(vias allowed)
			(pads allowed)
			(copperpour not_allowed)
			(footprints allowed)
		)
		(placement
			(enabled no)
			(sheetname "")
		)
		(fill
			(thermal_gap 0.5)
			(thermal_bridge_width 0.5)
			(island_removal_mode 0)
		)
		(polygon
			(pts
				(arc
					(start 374.47601 -220.319854)
					(mid 373.81815 -220.319854)
					(end 374.47601 -220.319854)
				)
			)
		)
	)
	(zone
		(layers "F.Cu" "B.Cu" "In1.Cu" "In2.Cu" "In3.Cu" "In4.Cu" "In5.Cu" "In6.Cu"
			"In7.Cu" "In8.Cu" "In9.Cu" "In10.Cu" "In11.Cu" "In12.Cu" "In13.Cu" "In14.Cu"
			"In15.Cu" "In16.Cu"
		)
		(hatch none 0.5)
		(connect_pads
			(clearance 0)
		)
		(min_thickness 0.25)
		(keepout
			(tracks not_allowed)
			(vias allowed)
			(pads allowed)
			(copperpour not_allowed)
			(footprints allowed)
		)
		(placement
			(enabled no)
			(sheetname "")
		)
		(fill
			(thermal_gap 0.5)
			(thermal_bridge_width 0.5)
			(island_removal_mode 0)
		)
		(polygon
			(pts
				(arc
					(start 100.691188 -214.622634)
					(mid 100.033328 -214.622634)
					(end 100.691188 -214.622634)
				)
			)
		)
	)
	(zone
		(layers "F.Cu" "B.Cu" "In1.Cu" "In2.Cu" "In3.Cu" "In4.Cu" "In5.Cu" "In6.Cu"
			"In7.Cu" "In8.Cu" "In9.Cu" "In10.Cu" "In11.Cu" "In12.Cu" "In13.Cu" "In14.Cu"
			"In15.Cu" "In16.Cu"
		)
		(hatch none 0.5)
		(connect_pads
			(clearance 0)
		)
		(min_thickness 0.25)
		(keepout
			(tracks not_allowed)
			(vias allowed)
			(pads allowed)
			(copperpour not_allowed)
			(footprints allowed)
		)
		(placement
			(enabled no)
			(sheetname "")
		)
		(fill
			(thermal_gap 0.5)
			(thermal_bridge_width 0.5)
			(island_removal_mode 0)
		)
		(polygon
			(pts
				(arc
					(start 426.448982 -4.57073)
					(mid 426.067982 -4.95173)
					(end 426.448982 -5.33273)
				)
				(arc
					(start 427.312582 -5.33273)
					(mid 427.693582 -4.95173)
					(end 427.312582 -4.57073)
				)
			)
		)
	)
	(zone
		(layers "F.Cu" "B.Cu" "In1.Cu" "In2.Cu" "In3.Cu" "In4.Cu" "In5.Cu" "In6.Cu"
			"In7.Cu" "In8.Cu" "In9.Cu" "In10.Cu" "In11.Cu" "In12.Cu" "In13.Cu" "In14.Cu"
			"In15.Cu" "In16.Cu"
		)
		(hatch none 0.5)
		(connect_pads
			(clearance 0)
		)
		(min_thickness 0.25)
		(keepout
			(tracks not_allowed)
			(vias allowed)
			(pads allowed)
			(copperpour not_allowed)
			(footprints allowed)
		)
		(placement
			(enabled no)
			(sheetname "")
		)
		(fill
			(thermal_gap 0.5)
			(thermal_bridge_width 0.5)
			(island_removal_mode 0)
		)
		(polygon
			(pts
				(arc
					(start 104.450388 -214.622634)
					(mid 103.792528 -214.622634)
					(end 104.450388 -214.622634)
				)
			)
		)
	)
	(zone
		(layers "F.Cu" "B.Cu" "In1.Cu" "In2.Cu" "In3.Cu" "In4.Cu" "In5.Cu" "In6.Cu"
			"In7.Cu" "In8.Cu" "In9.Cu" "In10.Cu" "In11.Cu" "In12.Cu" "In13.Cu" "In14.Cu"
			"In15.Cu" "In16.Cu"
		)
		(hatch none 0.5)
		(connect_pads
			(clearance 0)
		)
		(min_thickness 0.25)
		(keepout
			(tracks not_allowed)
			(vias allowed)
			(pads allowed)
			(copperpour not_allowed)
			(footprints allowed)
		)
		(placement
			(enabled no)
			(sheetname "")
		)
		(fill
			(thermal_gap 0.5)
			(thermal_bridge_width 0.5)
			(island_removal_mode 0)
		)
		(polygon
			(pts
				(arc
					(start 232.002076 -132.121148)
					(mid 231.621076 -132.502148)
					(end 232.002076 -132.883148)
				)
				(arc
					(start 232.865676 -132.883148)
					(mid 233.246676 -132.502148)
					(end 232.865676 -132.121148)
				)
			)
		)
	)
	(zone
		(layers "F.Cu" "B.Cu" "In1.Cu" "In2.Cu" "In3.Cu" "In4.Cu" "In5.Cu" "In6.Cu"
			"In7.Cu" "In8.Cu" "In9.Cu" "In10.Cu" "In11.Cu" "In12.Cu" "In13.Cu" "In14.Cu"
			"In15.Cu" "In16.Cu"
		)
		(hatch none 0.5)
		(connect_pads
			(clearance 0)
		)
		(min_thickness 0.25)
		(keepout
			(tracks not_allowed)
			(vias allowed)
			(pads allowed)
			(copperpour not_allowed)
			(footprints allowed)
		)
		(placement
			(enabled no)
			(sheetname "")
		)
		(fill
			(thermal_gap 0.5)
			(thermal_bridge_width 0.5)
			(island_removal_mode 0)
		)
		(polygon
			(pts
				(arc
					(start 358.95788 -28.450032)
					(mid 354.842064 -28.450032)
					(end 358.95788 -28.450032)
				)
			)
		)
	)
	(zone
		(layers "F.Cu" "B.Cu" "In1.Cu" "In2.Cu" "In3.Cu" "In4.Cu" "In5.Cu" "In6.Cu"
			"In7.Cu" "In8.Cu" "In9.Cu" "In10.Cu" "In11.Cu" "In12.Cu" "In13.Cu" "In14.Cu"
			"In15.Cu" "In16.Cu"
		)
		(hatch none 0.5)
		(connect_pads
			(clearance 0)
		)
		(min_thickness 0.25)
		(keepout
			(tracks not_allowed)
			(vias allowed)
			(pads allowed)
			(copperpour not_allowed)
			(footprints allowed)
		)
		(placement
			(enabled no)
			(sheetname "")
		)
		(fill
			(thermal_gap 0.5)
			(thermal_bridge_width 0.5)
			(island_removal_mode 0)
		)
		(polygon
			(pts
				(arc
					(start 375.995946 -286.475424)
					(mid 375.338086 -286.475424)
					(end 375.995946 -286.475424)
				)
			)
		)
	)
	(zone
		(layers "F.Cu" "B.Cu" "In1.Cu" "In2.Cu" "In3.Cu" "In4.Cu" "In5.Cu" "In6.Cu"
			"In7.Cu" "In8.Cu" "In9.Cu" "In10.Cu" "In11.Cu" "In12.Cu" "In13.Cu" "In14.Cu"
			"In15.Cu" "In16.Cu"
		)
		(hatch none 0.5)
		(connect_pads
			(clearance 0)
		)
		(min_thickness 0.25)
		(keepout
			(tracks not_allowed)
			(vias allowed)
			(pads allowed)
			(copperpour not_allowed)
			(footprints allowed)
		)
		(placement
			(enabled no)
			(sheetname "")
		)
		(fill
			(thermal_gap 0.5)
			(thermal_bridge_width 0.5)
			(island_removal_mode 0)
		)
		(polygon
			(pts
				(arc
					(start 94.424246 -220.418152)
					(mid 94.44393 -220.370742)
					(end 94.450662 -220.319854)
				)
				(arc
					(start 94.450662 -220.319854)
					(mid 94.393006 -220.18066)
					(end 94.253812 -220.123004)
				)
				(arc
					(start 94.253812 -220.123004)
					(mid 94.155381 -220.14942)
					(end 94.083378 -220.221556)
				)
				(arc
					(start 93.613732 -221.035626)
					(mid 93.594048 -221.083036)
					(end 93.587316 -221.133924)
				)
				(arc
					(start 93.587316 -221.133924)
					(mid 93.644972 -221.273118)
					(end 93.784166 -221.330774)
				)
				(arc
					(start 93.784166 -221.330774)
					(mid 93.882597 -221.304358)
					(end 93.9546 -221.232222)
				)
			)
		)
	)
	(zone
		(layers "F.Cu" "B.Cu" "In1.Cu" "In2.Cu" "In3.Cu" "In4.Cu" "In5.Cu" "In6.Cu"
			"In7.Cu" "In8.Cu" "In9.Cu" "In10.Cu" "In11.Cu" "In12.Cu" "In13.Cu" "In14.Cu"
			"In15.Cu" "In16.Cu"
		)
		(hatch none 0.5)
		(connect_pads
			(clearance 0)
		)
		(min_thickness 0.25)
		(keepout
			(tracks not_allowed)
			(vias allowed)
			(pads allowed)
			(copperpour not_allowed)
			(footprints allowed)
		)
		(placement
			(enabled no)
			(sheetname "")
		)
		(fill
			(thermal_gap 0.5)
			(thermal_bridge_width 0.5)
			(island_removal_mode 0)
		)
		(polygon
			(pts
				(arc
					(start 127.945896 -221.133924)
					(mid 127.288036 -221.133924)
					(end 127.945896 -221.133924)
				)
			)
		)
	)
	(zone
		(layers "F.Cu" "B.Cu" "In1.Cu" "In2.Cu" "In3.Cu" "In4.Cu" "In5.Cu" "In6.Cu"
			"In7.Cu" "In8.Cu" "In9.Cu" "In10.Cu" "In11.Cu" "In12.Cu" "In13.Cu" "In14.Cu"
			"In15.Cu" "In16.Cu"
		)
		(hatch none 0.5)
		(connect_pads
			(clearance 0)
		)
		(min_thickness 0.25)
		(keepout
			(tracks not_allowed)
			(vias allowed)
			(pads allowed)
			(copperpour not_allowed)
			(footprints allowed)
		)
		(placement
			(enabled no)
			(sheetname "")
		)
		(fill
			(thermal_gap 0.5)
			(thermal_bridge_width 0.5)
			(island_removal_mode 0)
		)
		(polygon
			(pts
				(xy 23.580852 -444.189866) (xy 28.580842 -444.189866) (xy 28.276042 -444.494666) (xy 23.885652 -444.494666)
			)
		)
	)
	(zone
		(layers "F.Cu" "B.Cu" "In1.Cu" "In2.Cu" "In3.Cu" "In4.Cu" "In5.Cu" "In6.Cu"
			"In7.Cu" "In8.Cu" "In9.Cu" "In10.Cu" "In11.Cu" "In12.Cu" "In13.Cu" "In14.Cu"
			"In15.Cu" "In16.Cu"
		)
		(hatch none 0.5)
		(connect_pads
			(clearance 0)
		)
		(min_thickness 0.25)
		(keepout
			(tracks not_allowed)
			(vias allowed)
			(pads allowed)
			(copperpour not_allowed)
			(footprints allowed)
		)
		(placement
			(enabled no)
			(sheetname "")
		)
		(fill
			(thermal_gap 0.5)
			(thermal_bridge_width 0.5)
			(island_removal_mode 0)
		)
		(polygon
			(pts
				(arc
					(start 123.356878 -284.847538)
					(mid 122.699018 -284.847538)
					(end 123.356878 -284.847538)
				)
			)
		)
	)
	(zone
		(layers "F.Cu" "B.Cu" "In1.Cu" "In2.Cu" "In3.Cu" "In4.Cu" "In5.Cu" "In6.Cu"
			"In7.Cu" "In8.Cu" "In9.Cu" "In10.Cu" "In11.Cu" "In12.Cu" "In13.Cu" "In14.Cu"
			"In15.Cu" "In16.Cu"
		)
		(hatch none 0.5)
		(connect_pads
			(clearance 0)
		)
		(min_thickness 0.25)
		(keepout
			(tracks not_allowed)
			(vias allowed)
			(pads allowed)
			(copperpour not_allowed)
			(footprints allowed)
		)
		(placement
			(enabled no)
			(sheetname "")
		)
		(fill
			(thermal_gap 0.5)
			(thermal_bridge_width 0.5)
			(island_removal_mode 0)
		)
		(polygon
			(pts
				(arc
					(start 342.834468 -221.035626)
					(mid 342.762479 -220.963467)
					(end 342.664034 -220.937074)
				)
				(arc
					(start 342.664034 -220.937074)
					(mid 342.52484 -220.99473)
					(end 342.467184 -221.133924)
				)
				(arc
					(start 342.467184 -221.133924)
					(mid 342.473941 -221.184805)
					(end 342.4936 -221.232222)
				)
				(arc
					(start 342.963246 -222.046038)
					(mid 343.035235 -222.118197)
					(end 343.13368 -222.14459)
				)
				(arc
					(start 343.13368 -222.14459)
					(mid 343.272874 -222.086934)
					(end 343.33053 -221.94774)
				)
				(arc
					(start 343.33053 -221.94774)
					(mid 343.323773 -221.896859)
					(end 343.304114 -221.849442)
				)
			)
		)
	)
	(zone
		(layers "F.Cu" "B.Cu" "In1.Cu" "In2.Cu" "In3.Cu" "In4.Cu" "In5.Cu" "In6.Cu"
			"In7.Cu" "In8.Cu" "In9.Cu" "In10.Cu" "In11.Cu" "In12.Cu" "In13.Cu" "In14.Cu"
			"In15.Cu" "In16.Cu"
		)
		(hatch none 0.5)
		(connect_pads
			(clearance 0)
		)
		(min_thickness 0.25)
		(keepout
			(tracks not_allowed)
			(vias allowed)
			(pads allowed)
			(copperpour not_allowed)
			(footprints allowed)
		)
		(placement
			(enabled no)
			(sheetname "")
		)
		(fill
			(thermal_gap 0.5)
			(thermal_bridge_width 0.5)
			(island_removal_mode 0)
		)
		(polygon
			(pts
				(arc
					(start 101.161342 -218.692222)
					(mid 100.503482 -218.692222)
					(end 101.161342 -218.692222)
				)
			)
		)
	)
	(zone
		(layers "F.Cu" "B.Cu" "In1.Cu" "In2.Cu" "In3.Cu" "In4.Cu" "In5.Cu" "In6.Cu"
			"In7.Cu" "In8.Cu" "In9.Cu" "In10.Cu" "In11.Cu" "In12.Cu" "In13.Cu" "In14.Cu"
			"In15.Cu" "In16.Cu"
		)
		(hatch none 0.5)
		(connect_pads
			(clearance 0)
		)
		(min_thickness 0.25)
		(keepout
			(tracks not_allowed)
			(vias allowed)
			(pads allowed)
			(copperpour not_allowed)
			(footprints allowed)
		)
		(placement
			(enabled no)
			(sheetname "")
		)
		(fill
			(thermal_gap 0.5)
			(thermal_bridge_width 0.5)
			(island_removal_mode 0)
		)
		(polygon
			(pts
				(arc
					(start 126.817882 -215.436704)
					(mid 127.475742 -215.436704)
					(end 126.817882 -215.436704)
				)
			)
		)
	)
	(zone
		(layers "F.Cu" "B.Cu" "In1.Cu" "In2.Cu" "In3.Cu" "In4.Cu" "In5.Cu" "In6.Cu"
			"In7.Cu" "In8.Cu" "In9.Cu" "In10.Cu" "In11.Cu" "In12.Cu" "In13.Cu" "In14.Cu"
			"In15.Cu" "In16.Cu"
		)
		(hatch none 0.5)
		(connect_pads
			(clearance 0)
		)
		(min_thickness 0.25)
		(keepout
			(tracks not_allowed)
			(vias allowed)
			(pads allowed)
			(copperpour not_allowed)
			(footprints allowed)
		)
		(placement
			(enabled no)
			(sheetname "")
		)
		(fill
			(thermal_gap 0.5)
			(thermal_bridge_width 0.5)
			(island_removal_mode 0)
		)
		(polygon
			(pts
				(arc
					(start 337.353656 -216.25052)
					(mid 336.695796 -216.25052)
					(end 337.353656 -216.25052)
				)
			)
		)
	)
	(zone
		(layers "F.Cu" "B.Cu" "In1.Cu" "In2.Cu" "In3.Cu" "In4.Cu" "In5.Cu" "In6.Cu"
			"In7.Cu" "In8.Cu" "In9.Cu" "In10.Cu" "In11.Cu" "In12.Cu" "In13.Cu" "In14.Cu"
			"In15.Cu" "In16.Cu"
		)
		(hatch none 0.5)
		(connect_pads
			(clearance 0)
		)
		(min_thickness 0.25)
		(keepout
			(tracks not_allowed)
			(vias allowed)
			(pads allowed)
			(copperpour not_allowed)
			(footprints allowed)
		)
		(placement
			(enabled no)
			(sheetname "")
		)
		(fill
			(thermal_gap 0.5)
			(thermal_bridge_width 0.5)
			(island_removal_mode 0)
		)
		(polygon
			(pts
				(arc
					(start 358.029764 -217.878406)
					(mid 357.371904 -217.878406)
					(end 358.029764 -217.878406)
				)
			)
		)
	)
	(zone
		(layers "F.Cu" "B.Cu" "In1.Cu" "In2.Cu" "In3.Cu" "In4.Cu" "In5.Cu" "In6.Cu"
			"In7.Cu" "In8.Cu" "In9.Cu" "In10.Cu" "In11.Cu" "In12.Cu" "In13.Cu" "In14.Cu"
			"In15.Cu" "In16.Cu"
		)
		(hatch none 0.5)
		(connect_pads
			(clearance 0)
		)
		(min_thickness 0.25)
		(keepout
			(tracks not_allowed)
			(vias allowed)
			(pads allowed)
			(copperpour not_allowed)
			(footprints allowed)
		)
		(placement
			(enabled no)
			(sheetname "")
		)
		(fill
			(thermal_gap 0.5)
			(thermal_bridge_width 0.5)
			(island_removal_mode 0)
		)
		(polygon
			(pts
				(arc
					(start 119.3292 -224.291144)
					(mid 119.257211 -224.218985)
					(end 119.158766 -224.192592)
				)
				(arc
					(start 119.158766 -224.192592)
					(mid 119.019572 -224.250248)
					(end 118.961916 -224.389442)
				)
				(arc
					(start 118.961916 -224.389442)
					(mid 118.968673 -224.440323)
					(end 118.988332 -224.48774)
				)
				(arc
					(start 119.457978 -225.301556)
					(mid 119.529967 -225.373715)
					(end 119.628412 -225.400108)
				)
				(arc
					(start 119.628412 -225.400108)
					(mid 119.767606 -225.342452)
					(end 119.825262 -225.203258)
				)
				(arc
					(start 119.825262 -225.203258)
					(mid 119.818505 -225.152377)
					(end 119.798846 -225.10496)
				)
			)
		)
	)
	(zone
		(layers "F.Cu" "B.Cu" "In1.Cu" "In2.Cu" "In3.Cu" "In4.Cu" "In5.Cu" "In6.Cu"
			"In7.Cu" "In8.Cu" "In9.Cu" "In10.Cu" "In11.Cu" "In12.Cu" "In13.Cu" "In14.Cu"
			"In15.Cu" "In16.Cu"
		)
		(hatch none 0.5)
		(connect_pads
			(clearance 0)
		)
		(min_thickness 0.25)
		(keepout
			(tracks not_allowed)
			(vias allowed)
			(pads allowed)
			(copperpour not_allowed)
			(footprints allowed)
		)
		(placement
			(enabled no)
			(sheetname "")
		)
		(fill
			(thermal_gap 0.5)
			(thermal_bridge_width 0.5)
			(island_removal_mode 0)
		)
		(polygon
			(pts
				(arc
					(start 431.84318 -12.483846)
					(mid 431.46218 -12.864846)
					(end 431.84318 -13.245846)
				)
				(arc
					(start 432.70678 -13.245846)
					(mid 433.08778 -12.864846)
					(end 432.70678 -12.483846)
				)
			)
		)
	)
	(zone
		(layers "F.Cu" "B.Cu" "In1.Cu" "In2.Cu" "In3.Cu" "In4.Cu" "In5.Cu" "In6.Cu"
			"In7.Cu" "In8.Cu" "In9.Cu" "In10.Cu" "In11.Cu" "In12.Cu" "In13.Cu" "In14.Cu"
			"In15.Cu" "In16.Cu"
		)
		(hatch none 0.5)
		(connect_pads
			(clearance 0)
		)
		(min_thickness 0.25)
		(keepout
			(tracks not_allowed)
			(vias allowed)
			(pads allowed)
			(copperpour not_allowed)
			(footprints allowed)
		)
		(placement
			(enabled no)
			(sheetname "")
		)
		(fill
			(thermal_gap 0.5)
			(thermal_bridge_width 0.5)
			(island_removal_mode 0)
		)
		(polygon
			(pts
				(xy 470.499948 -254.75819) (xy 470.499948 -249.7582) (xy 470.804748 -250.063) (xy 470.804748 -254.45339)
			)
		)
	)
	(zone
		(layers "F.Cu" "B.Cu" "In1.Cu" "In2.Cu" "In3.Cu" "In4.Cu" "In5.Cu" "In6.Cu"
			"In7.Cu" "In8.Cu" "In9.Cu" "In10.Cu" "In11.Cu" "In12.Cu" "In13.Cu" "In14.Cu"
			"In15.Cu" "In16.Cu"
		)
		(hatch none 0.5)
		(connect_pads
			(clearance 0)
		)
		(min_thickness 0.25)
		(keepout
			(tracks not_allowed)
			(vias allowed)
			(pads allowed)
			(copperpour not_allowed)
			(footprints allowed)
		)
		(placement
			(enabled no)
			(sheetname "")
		)
		(fill
			(thermal_gap 0.5)
			(thermal_bridge_width 0.5)
			(island_removal_mode 0)
		)
		(polygon
			(pts
				(arc
					(start 129.825496 -217.878406)
					(mid 129.167636 -217.878406)
					(end 129.825496 -217.878406)
				)
			)
		)
	)
	(zone
		(layers "F.Cu" "B.Cu" "In1.Cu" "In2.Cu" "In3.Cu" "In4.Cu" "In5.Cu" "In6.Cu"
			"In7.Cu" "In8.Cu" "In9.Cu" "In10.Cu" "In11.Cu" "In12.Cu" "In13.Cu" "In14.Cu"
			"In15.Cu" "In16.Cu"
		)
		(hatch none 0.5)
		(connect_pads
			(clearance 0)
		)
		(min_thickness 0.25)
		(keepout
			(tracks not_allowed)
			(vias allowed)
			(pads allowed)
			(copperpour not_allowed)
			(footprints allowed)
		)
		(placement
			(enabled no)
			(sheetname "")
		)
		(fill
			(thermal_gap 0.5)
			(thermal_bridge_width 0.5)
			(island_removal_mode 0)
		)
		(polygon
			(pts
				(arc
					(start 364.13821 -218.692222)
					(mid 363.48035 -218.692222)
					(end 364.13821 -218.692222)
				)
			)
		)
	)
	(zone
		(layers "F.Cu" "B.Cu" "In1.Cu" "In2.Cu" "In3.Cu" "In4.Cu" "In5.Cu" "In6.Cu"
			"In7.Cu" "In8.Cu" "In9.Cu" "In10.Cu" "In11.Cu" "In12.Cu" "In13.Cu" "In14.Cu"
			"In15.Cu" "In16.Cu"
		)
		(hatch none 0.5)
		(connect_pads
			(clearance 0)
		)
		(min_thickness 0.25)
		(keepout
			(tracks not_allowed)
			(vias allowed)
			(pads allowed)
			(copperpour not_allowed)
			(footprints allowed)
		)
		(placement
			(enabled no)
			(sheetname "")
		)
		(fill
			(thermal_gap 0.5)
			(thermal_bridge_width 0.5)
			(island_removal_mode 0)
		)
		(polygon
			(pts
				(arc
					(start 118.077742 -221.94774)
					(mid 117.419882 -221.94774)
					(end 118.077742 -221.94774)
				)
			)
		)
	)
	(zone
		(layers "F.Cu" "B.Cu" "In1.Cu" "In2.Cu" "In3.Cu" "In4.Cu" "In5.Cu" "In6.Cu"
			"In7.Cu" "In8.Cu" "In9.Cu" "In10.Cu" "In11.Cu" "In12.Cu" "In13.Cu" "In14.Cu"
			"In15.Cu" "In16.Cu"
		)
		(hatch none 0.5)
		(connect_pads
			(clearance 0)
		)
		(min_thickness 0.25)
		(keepout
			(tracks not_allowed)
			(vias allowed)
			(pads allowed)
			(copperpour not_allowed)
			(footprints allowed)
		)
		(placement
			(enabled no)
			(sheetname "")
		)
		(fill
			(thermal_gap 0.5)
			(thermal_bridge_width 0.5)
			(island_removal_mode 0)
		)
		(polygon
			(pts
				(arc
					(start 334.612488 -403.502876)
					(mid 334.231488 -403.883876)
					(end 334.612488 -404.264876)
				)
				(arc
					(start 335.476088 -404.264876)
					(mid 335.857088 -403.883876)
					(end 335.476088 -403.502876)
				)
			)
		)
	)
	(zone
		(layers "F.Cu" "B.Cu" "In1.Cu" "In2.Cu" "In3.Cu" "In4.Cu" "In5.Cu" "In6.Cu"
			"In7.Cu" "In8.Cu" "In9.Cu" "In10.Cu" "In11.Cu" "In12.Cu" "In13.Cu" "In14.Cu"
			"In15.Cu" "In16.Cu"
		)
		(hatch none 0.5)
		(connect_pads
			(clearance 0)
		)
		(min_thickness 0.25)
		(keepout
			(tracks not_allowed)
			(vias allowed)
			(pads allowed)
			(copperpour not_allowed)
			(footprints allowed)
		)
		(placement
			(enabled no)
			(sheetname "")
		)
		(fill
			(thermal_gap 0.5)
			(thermal_bridge_width 0.5)
			(island_removal_mode 0)
		)
		(polygon
			(pts
				(arc
					(start 350.621092 -276.708616)
					(mid 349.963232 -276.708616)
					(end 350.621092 -276.708616)
				)
			)
		)
	)
	(zone
		(layers "F.Cu" "B.Cu" "In1.Cu" "In2.Cu" "In3.Cu" "In4.Cu" "In5.Cu" "In6.Cu"
			"In7.Cu" "In8.Cu" "In9.Cu" "In10.Cu" "In11.Cu" "In12.Cu" "In13.Cu" "In14.Cu"
			"In15.Cu" "In16.Cu"
		)
		(hatch none 0.5)
		(connect_pads
			(clearance 0)
		)
		(min_thickness 0.25)
		(keepout
			(tracks not_allowed)
			(vias allowed)
			(pads allowed)
			(copperpour not_allowed)
			(footprints allowed)
		)
		(placement
			(enabled no)
			(sheetname "")
		)
		(fill
			(thermal_gap 0.5)
			(thermal_bridge_width 0.5)
			(island_removal_mode 0)
		)
		(polygon
			(pts
				(arc
					(start 117.608096 -224.389442)
					(mid 116.950236 -224.389442)
					(end 117.608096 -224.389442)
				)
			)
		)
	)
	(zone
		(layers "F.Cu" "B.Cu" "In1.Cu" "In2.Cu" "In3.Cu" "In4.Cu" "In5.Cu" "In6.Cu"
			"In7.Cu" "In8.Cu" "In9.Cu" "In10.Cu" "In11.Cu" "In12.Cu" "In13.Cu" "In14.Cu"
			"In15.Cu" "In16.Cu"
		)
		(hatch none 0.5)
		(connect_pads
			(clearance 0)
		)
		(min_thickness 0.25)
		(keepout
			(tracks not_allowed)
			(vias allowed)
			(pads allowed)
			(copperpour not_allowed)
			(footprints allowed)
		)
		(placement
			(enabled no)
			(sheetname "")
		)
		(fill
			(thermal_gap 0.5)
			(thermal_bridge_width 0.5)
			(island_removal_mode 0)
		)
		(polygon
			(pts
				(arc
					(start 94.113096 -217.878406)
					(mid 93.455236 -217.878406)
					(end 94.113096 -217.878406)
				)
			)
		)
	)
	(zone
		(layers "F.Cu" "B.Cu" "In1.Cu" "In2.Cu" "In3.Cu" "In4.Cu" "In5.Cu" "In6.Cu"
			"In7.Cu" "In8.Cu" "In9.Cu" "In10.Cu" "In11.Cu" "In12.Cu" "In13.Cu" "In14.Cu"
			"In15.Cu" "In16.Cu"
		)
		(hatch none 0.5)
		(connect_pads
			(clearance 0)
		)
		(min_thickness 0.25)
		(keepout
			(tracks not_allowed)
			(vias allowed)
			(pads allowed)
			(copperpour not_allowed)
			(footprints allowed)
		)
		(placement
			(enabled no)
			(sheetname "")
		)
		(fill
			(thermal_gap 0.5)
			(thermal_bridge_width 0.5)
			(island_removal_mode 0)
		)
		(polygon
			(pts
				(arc
					(start 167.449754 -409.649168)
					(mid 167.068754 -410.030168)
					(end 167.449754 -410.411168)
				)
				(arc
					(start 168.313354 -410.411168)
					(mid 168.694354 -410.030168)
					(end 168.313354 -409.649168)
				)
			)
		)
	)
	(zone
		(layers "F.Cu" "B.Cu" "In1.Cu" "In2.Cu" "In3.Cu" "In4.Cu" "In5.Cu" "In6.Cu"
			"In7.Cu" "In8.Cu" "In9.Cu" "In10.Cu" "In11.Cu" "In12.Cu" "In13.Cu" "In14.Cu"
			"In15.Cu" "In16.Cu"
		)
		(hatch none 0.5)
		(connect_pads
			(clearance 0)
		)
		(min_thickness 0.25)
		(keepout
			(tracks not_allowed)
			(vias allowed)
			(pads allowed)
			(copperpour not_allowed)
			(footprints allowed)
		)
		(placement
			(enabled no)
			(sheetname "")
		)
		(fill
			(thermal_gap 0.5)
			(thermal_bridge_width 0.5)
			(island_removal_mode 0)
		)
		(polygon
			(pts
				(arc
					(start 89.883742 -221.94774)
					(mid 89.225882 -221.94774)
					(end 89.883742 -221.94774)
				)
			)
		)
	)
	(zone
		(layers "F.Cu" "B.Cu" "In1.Cu" "In2.Cu" "In3.Cu" "In4.Cu" "In5.Cu" "In6.Cu"
			"In7.Cu" "In8.Cu" "In9.Cu" "In10.Cu" "In11.Cu" "In12.Cu" "In13.Cu" "In14.Cu"
			"In15.Cu" "In16.Cu"
		)
		(hatch none 0.5)
		(connect_pads
			(clearance 0)
		)
		(min_thickness 0.25)
		(keepout
			(tracks not_allowed)
			(vias allowed)
			(pads allowed)
			(copperpour not_allowed)
			(footprints allowed)
		)
		(placement
			(enabled no)
			(sheetname "")
		)
		(fill
			(thermal_gap 0.5)
			(thermal_bridge_width 0.5)
			(island_removal_mode 0)
		)
		(polygon
			(pts
				(arc
					(start 361.31881 -223.575626)
					(mid 360.66095 -223.575626)
					(end 361.31881 -223.575626)
				)
			)
		)
	)
	(zone
		(layers "F.Cu" "B.Cu" "In1.Cu" "In2.Cu" "In3.Cu" "In4.Cu" "In5.Cu" "In6.Cu"
			"In7.Cu" "In8.Cu" "In9.Cu" "In10.Cu" "In11.Cu" "In12.Cu" "In13.Cu" "In14.Cu"
			"In15.Cu" "In16.Cu"
		)
		(hatch none 0.5)
		(connect_pads
			(clearance 0)
		)
		(min_thickness 0.25)
		(keepout
			(tracks not_allowed)
			(vias allowed)
			(pads allowed)
			(copperpour not_allowed)
			(footprints allowed)
		)
		(placement
			(enabled no)
			(sheetname "")
		)
		(fill
			(thermal_gap 0.5)
			(thermal_bridge_width 0.5)
			(island_removal_mode 0)
		)
		(polygon
			(pts
				(arc
					(start 126.487428 -285.759652)
					(mid 126.507112 -285.712242)
					(end 126.513844 -285.661354)
				)
				(arc
					(start 126.513844 -285.661354)
					(mid 126.456188 -285.52216)
					(end 126.316994 -285.464504)
				)
				(arc
					(start 126.316994 -285.464504)
					(mid 126.218563 -285.49092)
					(end 126.14656 -285.563056)
				)
				(arc
					(start 125.676914 -286.377126)
					(mid 125.65723 -286.424536)
					(end 125.650498 -286.475424)
				)
				(arc
					(start 125.650498 -286.475424)
					(mid 125.708154 -286.614618)
					(end 125.847348 -286.672274)
				)
				(arc
					(start 125.847348 -286.672274)
					(mid 125.945779 -286.645858)
					(end 126.017782 -286.573722)
				)
			)
		)
	)
	(zone
		(layers "F.Cu" "B.Cu" "In1.Cu" "In2.Cu" "In3.Cu" "In4.Cu" "In5.Cu" "In6.Cu"
			"In7.Cu" "In8.Cu" "In9.Cu" "In10.Cu" "In11.Cu" "In12.Cu" "In13.Cu" "In14.Cu"
			"In15.Cu" "In16.Cu"
		)
		(hatch none 0.5)
		(connect_pads
			(clearance 0)
		)
		(min_thickness 0.25)
		(keepout
			(tracks not_allowed)
			(vias allowed)
			(pads allowed)
			(copperpour not_allowed)
			(footprints allowed)
		)
		(placement
			(enabled no)
			(sheetname "")
		)
		(fill
			(thermal_gap 0.5)
			(thermal_bridge_width 0.5)
			(island_removal_mode 0)
		)
		(polygon
			(pts
				(arc
					(start 100.063046 -220.418152)
					(mid 100.08273 -220.370742)
					(end 100.089462 -220.319854)
				)
				(arc
					(start 100.089462 -220.319854)
					(mid 100.031806 -220.18066)
					(end 99.892612 -220.123004)
				)
				(arc
					(start 99.892612 -220.123004)
					(mid 99.794181 -220.14942)
					(end 99.722178 -220.221556)
				)
				(arc
					(start 99.252532 -221.035626)
					(mid 99.232848 -221.083036)
					(end 99.226116 -221.133924)
				)
				(arc
					(start 99.226116 -221.133924)
					(mid 99.283772 -221.273118)
					(end 99.422966 -221.330774)
				)
				(arc
					(start 99.422966 -221.330774)
					(mid 99.521397 -221.304358)
					(end 99.5934 -221.232222)
				)
			)
		)
	)
	(zone
		(layers "F.Cu" "B.Cu" "In1.Cu" "In2.Cu" "In3.Cu" "In4.Cu" "In5.Cu" "In6.Cu"
			"In7.Cu" "In8.Cu" "In9.Cu" "In10.Cu" "In11.Cu" "In12.Cu" "In13.Cu" "In14.Cu"
			"In15.Cu" "In16.Cu"
		)
		(hatch none 0.5)
		(connect_pads
			(clearance 0)
		)
		(min_thickness 0.25)
		(keepout
			(tracks not_allowed)
			(vias allowed)
			(pads allowed)
			(copperpour not_allowed)
			(footprints allowed)
		)
		(placement
			(enabled no)
			(sheetname "")
		)
		(fill
			(thermal_gap 0.5)
			(thermal_bridge_width 0.5)
			(island_removal_mode 0)
		)
		(polygon
			(pts
				(arc
					(start 133.584188 -214.622634)
					(mid 132.926328 -214.622634)
					(end 133.584188 -214.622634)
				)
			)
		)
	)
	(zone
		(layers "F.Cu" "B.Cu" "In1.Cu" "In2.Cu" "In3.Cu" "In4.Cu" "In5.Cu" "In6.Cu"
			"In7.Cu" "In8.Cu" "In9.Cu" "In10.Cu" "In11.Cu" "In12.Cu" "In13.Cu" "In14.Cu"
			"In15.Cu" "In16.Cu"
		)
		(hatch none 0.5)
		(connect_pads
			(clearance 0)
		)
		(min_thickness 0.25)
		(keepout
			(tracks not_allowed)
			(vias allowed)
			(pads allowed)
			(copperpour not_allowed)
			(footprints allowed)
		)
		(placement
			(enabled no)
			(sheetname "")
		)
		(fill
			(thermal_gap 0.5)
			(thermal_bridge_width 0.5)
			(island_removal_mode 0)
		)
		(polygon
			(pts
				(arc
					(start 343.932764 -221.133924)
					(mid 343.274904 -221.133924)
					(end 343.932764 -221.133924)
				)
			)
		)
	)
	(zone
		(layers "F.Cu" "B.Cu" "In1.Cu" "In2.Cu" "In3.Cu" "In4.Cu" "In5.Cu" "In6.Cu"
			"In7.Cu" "In8.Cu" "In9.Cu" "In10.Cu" "In11.Cu" "In12.Cu" "In13.Cu" "In14.Cu"
			"In15.Cu" "In16.Cu"
		)
		(hatch none 0.5)
		(connect_pads
			(clearance 0)
		)
		(min_thickness 0.25)
		(keepout
			(tracks not_allowed)
			(vias allowed)
			(pads allowed)
			(copperpour not_allowed)
			(footprints allowed)
		)
		(placement
			(enabled no)
			(sheetname "")
		)
		(fill
			(thermal_gap 0.5)
			(thermal_bridge_width 0.5)
			(island_removal_mode 0)
		)
		(polygon
			(pts
				(arc
					(start 94.41688 -213.646766)
					(mid 94.349172 -213.574915)
					(end 94.254066 -213.548468)
				)
				(arc
					(start 94.254066 -213.548468)
					(mid 94.123852 -213.602404)
					(end 94.069916 -213.732618)
				)
				(arc
					(start 94.069916 -213.732618)
					(mid 94.075367 -213.776839)
					(end 94.091252 -213.81847)
				)
				(arc
					(start 94.560644 -214.708486)
					(mid 94.628352 -214.780337)
					(end 94.723458 -214.806784)
				)
				(arc
					(start 94.723458 -214.806784)
					(mid 94.853672 -214.752848)
					(end 94.907608 -214.622634)
				)
				(arc
					(start 94.907608 -214.622634)
					(mid 94.902157 -214.578413)
					(end 94.886272 -214.536782)
				)
			)
		)
	)
	(zone
		(layers "F.Cu" "B.Cu" "In1.Cu" "In2.Cu" "In3.Cu" "In4.Cu" "In5.Cu" "In6.Cu"
			"In7.Cu" "In8.Cu" "In9.Cu" "In10.Cu" "In11.Cu" "In12.Cu" "In13.Cu" "In14.Cu"
			"In15.Cu" "In16.Cu"
		)
		(hatch none 0.5)
		(connect_pads
			(clearance 0)
		)
		(min_thickness 0.25)
		(keepout
			(tracks not_allowed)
			(vias allowed)
			(pads allowed)
			(copperpour not_allowed)
			(footprints allowed)
		)
		(placement
			(enabled no)
			(sheetname "")
		)
		(fill
			(thermal_gap 0.5)
			(thermal_bridge_width 0.5)
			(island_removal_mode 0)
		)
		(polygon
			(pts
				(arc
					(start 339.813646 -288.917126)
					(mid 339.155786 -288.917126)
					(end 339.813646 -288.917126)
				)
			)
		)
	)
	(zone
		(layers "F.Cu" "B.Cu" "In1.Cu" "In2.Cu" "In3.Cu" "In4.Cu" "In5.Cu" "In6.Cu"
			"In7.Cu" "In8.Cu" "In9.Cu" "In10.Cu" "In11.Cu" "In12.Cu" "In13.Cu" "In14.Cu"
			"In15.Cu" "In16.Cu"
		)
		(hatch none 0.5)
		(connect_pads
			(clearance 0)
		)
		(min_thickness 0.25)
		(keepout
			(tracks not_allowed)
			(vias allowed)
			(pads allowed)
			(copperpour not_allowed)
			(footprints allowed)
		)
		(placement
			(enabled no)
			(sheetname "")
		)
		(fill
			(thermal_gap 0.5)
			(thermal_bridge_width 0.5)
			(island_removal_mode 0)
		)
		(polygon
			(pts
				(arc
					(start 355.210364 -217.878406)
					(mid 354.552504 -217.878406)
					(end 355.210364 -217.878406)
				)
			)
		)
	)
	(zone
		(layers "F.Cu" "B.Cu" "In1.Cu" "In2.Cu" "In3.Cu" "In4.Cu" "In5.Cu" "In6.Cu"
			"In7.Cu" "In8.Cu" "In9.Cu" "In10.Cu" "In11.Cu" "In12.Cu" "In13.Cu" "In14.Cu"
			"In15.Cu" "In16.Cu"
		)
		(hatch none 0.5)
		(connect_pads
			(clearance 0)
		)
		(min_thickness 0.25)
		(keepout
			(tracks not_allowed)
			(vias allowed)
			(pads allowed)
			(copperpour not_allowed)
			(footprints allowed)
		)
		(placement
			(enabled no)
			(sheetname "")
		)
		(fill
			(thermal_gap 0.5)
			(thermal_bridge_width 0.5)
			(island_removal_mode 0)
		)
		(polygon
			(pts
				(arc
					(start 355.68001 -223.575626)
					(mid 355.02215 -223.575626)
					(end 355.68001 -223.575626)
				)
			)
		)
	)
	(zone
		(layers "F.Cu" "B.Cu" "In1.Cu" "In2.Cu" "In3.Cu" "In4.Cu" "In5.Cu" "In6.Cu"
			"In7.Cu" "In8.Cu" "In9.Cu" "In10.Cu" "In11.Cu" "In12.Cu" "In13.Cu" "In14.Cu"
			"In15.Cu" "In16.Cu"
		)
		(hatch none 0.5)
		(connect_pads
			(clearance 0)
		)
		(min_thickness 0.25)
		(keepout
			(tracks not_allowed)
			(vias allowed)
			(pads allowed)
			(copperpour not_allowed)
			(footprints allowed)
		)
		(placement
			(enabled no)
			(sheetname "")
		)
		(fill
			(thermal_gap 0.5)
			(thermal_bridge_width 0.5)
			(island_removal_mode 0)
		)
		(polygon
			(pts
				(arc
					(start 121.477278 -284.847538)
					(mid 120.819418 -284.847538)
					(end 121.477278 -284.847538)
				)
			)
		)
	)
	(zone
		(layers "F.Cu" "B.Cu" "In1.Cu" "In2.Cu" "In3.Cu" "In4.Cu" "In5.Cu" "In6.Cu"
			"In7.Cu" "In8.Cu" "In9.Cu" "In10.Cu" "In11.Cu" "In12.Cu" "In13.Cu" "In14.Cu"
			"In15.Cu" "In16.Cu"
		)
		(hatch none 0.5)
		(connect_pads
			(clearance 0)
		)
		(min_thickness 0.25)
		(keepout
			(tracks not_allowed)
			(vias allowed)
			(pads allowed)
			(copperpour not_allowed)
			(footprints allowed)
		)
		(placement
			(enabled no)
			(sheetname "")
		)
		(fill
			(thermal_gap 0.5)
			(thermal_bridge_width 0.5)
			(island_removal_mode 0)
		)
		(polygon
			(pts
				(arc
					(start 105.860596 -213.732618)
					(mid 105.202736 -213.732618)
					(end 105.860596 -213.732618)
				)
			)
		)
	)
	(zone
		(layers "F.Cu" "B.Cu" "In1.Cu" "In2.Cu" "In3.Cu" "In4.Cu" "In5.Cu" "In6.Cu"
			"In7.Cu" "In8.Cu" "In9.Cu" "In10.Cu" "In11.Cu" "In12.Cu" "In13.Cu" "In14.Cu"
			"In15.Cu" "In16.Cu"
		)
		(hatch none 0.5)
		(connect_pads
			(clearance 0)
		)
		(min_thickness 0.25)
		(keepout
			(tracks not_allowed)
			(vias allowed)
			(pads allowed)
			(copperpour not_allowed)
			(footprints allowed)
		)
		(placement
			(enabled no)
			(sheetname "")
		)
		(fill
			(thermal_gap 0.5)
			(thermal_bridge_width 0.5)
			(island_removal_mode 0)
		)
		(polygon
			(pts
				(arc
					(start 121.501154 -409.649168)
					(mid 121.120154 -410.030168)
					(end 121.501154 -410.411168)
				)
				(arc
					(start 122.364754 -410.411168)
					(mid 122.745754 -410.030168)
					(end 122.364754 -409.649168)
				)
			)
		)
	)
	(zone
		(layers "F.Cu" "B.Cu" "In1.Cu" "In2.Cu" "In3.Cu" "In4.Cu" "In5.Cu" "In6.Cu"
			"In7.Cu" "In8.Cu" "In9.Cu" "In10.Cu" "In11.Cu" "In12.Cu" "In13.Cu" "In14.Cu"
			"In15.Cu" "In16.Cu"
		)
		(hatch none 0.5)
		(connect_pads
			(clearance 0)
		)
		(min_thickness 0.25)
		(keepout
			(tracks not_allowed)
			(vias allowed)
			(pads allowed)
			(copperpour not_allowed)
			(footprints allowed)
		)
		(placement
			(enabled no)
			(sheetname "")
		)
		(fill
			(thermal_gap 0.5)
			(thermal_bridge_width 0.5)
			(island_removal_mode 0)
		)
		(polygon
			(pts
				(arc
					(start 103.511096 -217.878406)
					(mid 102.853236 -217.878406)
					(end 103.511096 -217.878406)
				)
			)
		)
	)
	(zone
		(layers "F.Cu" "B.Cu" "In1.Cu" "In2.Cu" "In3.Cu" "In4.Cu" "In5.Cu" "In6.Cu"
			"In7.Cu" "In8.Cu" "In9.Cu" "In10.Cu" "In11.Cu" "In12.Cu" "In13.Cu" "In14.Cu"
			"In15.Cu" "In16.Cu"
		)
		(hatch none 0.5)
		(connect_pads
			(clearance 0)
		)
		(min_thickness 0.25)
		(keepout
			(tracks not_allowed)
			(vias allowed)
			(pads allowed)
			(copperpour not_allowed)
			(footprints allowed)
		)
		(placement
			(enabled no)
			(sheetname "")
		)
		(fill
			(thermal_gap 0.5)
			(thermal_bridge_width 0.5)
			(island_removal_mode 0)
		)
		(polygon
			(pts
				(arc
					(start 89.148158 -409.649168)
					(mid 88.767158 -410.030168)
					(end 89.148158 -410.411168)
				)
				(arc
					(start 90.011758 -410.411168)
					(mid 90.392758 -410.030168)
					(end 90.011758 -409.649168)
				)
			)
		)
	)
	(zone
		(layers "F.Cu" "B.Cu" "In1.Cu" "In2.Cu" "In3.Cu" "In4.Cu" "In5.Cu" "In6.Cu"
			"In7.Cu" "In8.Cu" "In9.Cu" "In10.Cu" "In11.Cu" "In12.Cu" "In13.Cu" "In14.Cu"
			"In15.Cu" "In16.Cu"
		)
		(hatch none 0.5)
		(connect_pads
			(clearance 0)
		)
		(min_thickness 0.25)
		(keepout
			(tracks not_allowed)
			(vias allowed)
			(pads allowed)
			(copperpour not_allowed)
			(footprints allowed)
		)
		(placement
			(enabled no)
			(sheetname "")
		)
		(fill
			(thermal_gap 0.5)
			(thermal_bridge_width 0.5)
			(island_removal_mode 0)
		)
		(polygon
			(pts
				(arc
					(start 128.055878 -286.475424)
					(mid 127.398018 -286.475424)
					(end 128.055878 -286.475424)
				)
			)
		)
	)
	(zone
		(layers "F.Cu" "B.Cu" "In1.Cu" "In2.Cu" "In3.Cu" "In4.Cu" "In5.Cu" "In6.Cu"
			"In7.Cu" "In8.Cu" "In9.Cu" "In10.Cu" "In11.Cu" "In12.Cu" "In13.Cu" "In14.Cu"
			"In15.Cu" "In16.Cu"
		)
		(hatch none 0.5)
		(connect_pads
			(clearance 0)
		)
		(min_thickness 0.25)
		(keepout
			(tracks not_allowed)
			(vias allowed)
			(pads allowed)
			(copperpour not_allowed)
			(footprints allowed)
		)
		(placement
			(enabled no)
			(sheetname "")
		)
		(fill
			(thermal_gap 0.5)
			(thermal_bridge_width 0.5)
			(island_removal_mode 0)
		)
		(polygon
			(pts
				(arc
					(start 369.25885 -284.74924)
					(mid 369.186861 -284.677081)
					(end 369.088416 -284.650688)
				)
				(arc
					(start 369.088416 -284.650688)
					(mid 368.949222 -284.708344)
					(end 368.891566 -284.847538)
				)
				(arc
					(start 368.891566 -284.847538)
					(mid 368.898323 -284.898419)
					(end 368.917982 -284.945836)
				)
				(arc
					(start 369.387628 -285.759652)
					(mid 369.459617 -285.831811)
					(end 369.558062 -285.858204)
				)
				(arc
					(start 369.558062 -285.858204)
					(mid 369.697256 -285.800548)
					(end 369.754912 -285.661354)
				)
				(arc
					(start 369.754912 -285.661354)
					(mid 369.748155 -285.610473)
					(end 369.728496 -285.563056)
				)
			)
		)
	)
	(zone
		(layers "F.Cu" "B.Cu" "In1.Cu" "In2.Cu" "In3.Cu" "In4.Cu" "In5.Cu" "In6.Cu"
			"In7.Cu" "In8.Cu" "In9.Cu" "In10.Cu" "In11.Cu" "In12.Cu" "In13.Cu" "In14.Cu"
			"In15.Cu" "In16.Cu"
		)
		(hatch none 0.5)
		(connect_pads
			(clearance 0)
		)
		(min_thickness 0.25)
		(keepout
			(tracks not_allowed)
			(vias allowed)
			(pads allowed)
			(copperpour not_allowed)
			(footprints allowed)
		)
		(placement
			(enabled no)
			(sheetname "")
		)
		(fill
			(thermal_gap 0.5)
			(thermal_bridge_width 0.5)
			(island_removal_mode 0)
		)
		(polygon
			(pts
				(arc
					(start 234.792266 -134.258304)
					(mid 234.411266 -133.877304)
					(end 234.030266 -134.258304)
				)
				(arc
					(start 234.030266 -135.121904)
					(mid 234.411266 -135.502904)
					(end 234.792266 -135.121904)
				)
			)
		)
	)
	(zone
		(layers "F.Cu" "B.Cu" "In1.Cu" "In2.Cu" "In3.Cu" "In4.Cu" "In5.Cu" "In6.Cu"
			"In7.Cu" "In8.Cu" "In9.Cu" "In10.Cu" "In11.Cu" "In12.Cu" "In13.Cu" "In14.Cu"
			"In15.Cu" "In16.Cu"
		)
		(hatch none 0.5)
		(connect_pads
			(clearance 0)
		)
		(min_thickness 0.25)
		(keepout
			(tracks not_allowed)
			(vias allowed)
			(pads allowed)
			(copperpour not_allowed)
			(footprints allowed)
		)
		(placement
			(enabled no)
			(sheetname "")
		)
		(fill
			(thermal_gap 0.5)
			(thermal_bridge_width 0.5)
			(island_removal_mode 0)
		)
		(polygon
			(pts
				(arc
					(start 375.885964 -217.878406)
					(mid 375.228104 -217.878406)
					(end 375.885964 -217.878406)
				)
			)
		)
	)
	(zone
		(layers "F.Cu" "B.Cu" "In1.Cu" "In2.Cu" "In3.Cu" "In4.Cu" "In5.Cu" "In6.Cu"
			"In7.Cu" "In8.Cu" "In9.Cu" "In10.Cu" "In11.Cu" "In12.Cu" "In13.Cu" "In14.Cu"
			"In15.Cu" "In16.Cu"
		)
		(hatch none 0.5)
		(connect_pads
			(clearance 0)
		)
		(min_thickness 0.25)
		(keepout
			(tracks not_allowed)
			(vias allowed)
			(pads allowed)
			(copperpour not_allowed)
			(footprints allowed)
		)
		(placement
			(enabled no)
			(sheetname "")
		)
		(fill
			(thermal_gap 0.5)
			(thermal_bridge_width 0.5)
			(island_removal_mode 0)
		)
		(polygon
			(pts
				(arc
					(start 388.08533 -406.62352)
					(mid 387.70433 -407.00452)
					(end 388.08533 -407.38552)
				)
				(arc
					(start 388.94893 -407.38552)
					(mid 389.32993 -407.00452)
					(end 388.94893 -406.62352)
				)
			)
		)
	)
	(zone
		(layers "F.Cu" "B.Cu" "In1.Cu" "In2.Cu" "In3.Cu" "In4.Cu" "In5.Cu" "In6.Cu"
			"In7.Cu" "In8.Cu" "In9.Cu" "In10.Cu" "In11.Cu" "In12.Cu" "In13.Cu" "In14.Cu"
			"In15.Cu" "In16.Cu"
		)
		(hatch none 0.5)
		(connect_pads
			(clearance 0)
		)
		(min_thickness 0.25)
		(keepout
			(tracks not_allowed)
			(vias allowed)
			(pads allowed)
			(copperpour not_allowed)
			(footprints allowed)
		)
		(placement
			(enabled no)
			(sheetname "")
		)
		(fill
			(thermal_gap 0.5)
			(thermal_bridge_width 0.5)
			(island_removal_mode 0)
		)
		(polygon
			(pts
				(arc
					(start 51.043078 -403.502876)
					(mid 50.662078 -403.883876)
					(end 51.043078 -404.264876)
				)
				(arc
					(start 51.906678 -404.264876)
					(mid 52.287678 -403.883876)
					(end 51.906678 -403.502876)
				)
			)
		)
	)
	(zone
		(layers "F.Cu" "B.Cu" "In1.Cu" "In2.Cu" "In3.Cu" "In4.Cu" "In5.Cu" "In6.Cu"
			"In7.Cu" "In8.Cu" "In9.Cu" "In10.Cu" "In11.Cu" "In12.Cu" "In13.Cu" "In14.Cu"
			"In15.Cu" "In16.Cu"
		)
		(hatch none 0.5)
		(connect_pads
			(clearance 0)
		)
		(min_thickness 0.25)
		(keepout
			(tracks not_allowed)
			(vias allowed)
			(pads allowed)
			(copperpour not_allowed)
			(footprints allowed)
		)
		(placement
			(enabled no)
			(sheetname "")
		)
		(fill
			(thermal_gap 0.5)
			(thermal_bridge_width 0.5)
			(island_removal_mode 0)
		)
		(polygon
			(pts
				(arc
					(start 418.71773 -406.62352)
					(mid 418.33673 -407.00452)
					(end 418.71773 -407.38552)
				)
				(arc
					(start 419.58133 -407.38552)
					(mid 419.96233 -407.00452)
					(end 419.58133 -406.62352)
				)
			)
		)
	)
	(zone
		(layers "F.Cu" "B.Cu" "In1.Cu" "In2.Cu" "In3.Cu" "In4.Cu" "In5.Cu" "In6.Cu"
			"In7.Cu" "In8.Cu" "In9.Cu" "In10.Cu" "In11.Cu" "In12.Cu" "In13.Cu" "In14.Cu"
			"In15.Cu" "In16.Cu"
		)
		(hatch none 0.5)
		(connect_pads
			(clearance 0)
		)
		(min_thickness 0.25)
		(keepout
			(tracks not_allowed)
			(vias allowed)
			(pads allowed)
			(copperpour not_allowed)
			(footprints allowed)
		)
		(placement
			(enabled no)
			(sheetname "")
		)
		(fill
			(thermal_gap 0.5)
			(thermal_bridge_width 0.5)
			(island_removal_mode 0)
		)
		(polygon
			(pts
				(arc
					(start 102.681278 -281.59202)
					(mid 102.023418 -281.59202)
					(end 102.681278 -281.59202)
				)
			)
		)
	)
	(zone
		(layers "F.Cu" "B.Cu" "In1.Cu" "In2.Cu" "In3.Cu" "In4.Cu" "In5.Cu" "In6.Cu"
			"In7.Cu" "In8.Cu" "In9.Cu" "In10.Cu" "In11.Cu" "In12.Cu" "In13.Cu" "In14.Cu"
			"In15.Cu" "In16.Cu"
		)
		(hatch none 0.5)
		(connect_pads
			(clearance 0)
		)
		(min_thickness 0.25)
		(keepout
			(tracks not_allowed)
			(vias allowed)
			(pads allowed)
			(copperpour not_allowed)
			(footprints allowed)
		)
		(placement
			(enabled no)
			(sheetname "")
		)
		(fill
			(thermal_gap 0.5)
			(thermal_bridge_width 0.5)
			(island_removal_mode 0)
		)
		(polygon
			(pts
				(arc
					(start 356.150164 -217.878406)
					(mid 355.492304 -217.878406)
					(end 356.150164 -217.878406)
				)
			)
		)
	)
	(zone
		(layers "F.Cu" "B.Cu" "In1.Cu" "In2.Cu" "In3.Cu" "In4.Cu" "In5.Cu" "In6.Cu"
			"In7.Cu" "In8.Cu" "In9.Cu" "In10.Cu" "In11.Cu" "In12.Cu" "In13.Cu" "In14.Cu"
			"In15.Cu" "In16.Cu"
		)
		(hatch none 0.5)
		(connect_pads
			(clearance 0)
		)
		(min_thickness 0.25)
		(keepout
			(tracks not_allowed)
			(vias allowed)
			(pads allowed)
			(copperpour not_allowed)
			(footprints allowed)
		)
		(placement
			(enabled no)
			(sheetname "")
		)
		(fill
			(thermal_gap 0.5)
			(thermal_bridge_width 0.5)
			(island_removal_mode 0)
		)
		(polygon
			(pts
				(arc
					(start 348.271592 -285.661354)
					(mid 347.613732 -285.661354)
					(end 348.271592 -285.661354)
				)
			)
		)
	)
	(zone
		(layers "F.Cu" "B.Cu" "In1.Cu" "In2.Cu" "In3.Cu" "In4.Cu" "In5.Cu" "In6.Cu"
			"In7.Cu" "In8.Cu" "In9.Cu" "In10.Cu" "In11.Cu" "In12.Cu" "In13.Cu" "In14.Cu"
			"In15.Cu" "In16.Cu"
		)
		(hatch none 0.5)
		(connect_pads
			(clearance 0)
		)
		(min_thickness 0.25)
		(keepout
			(tracks not_allowed)
			(vias allowed)
			(pads allowed)
			(copperpour not_allowed)
			(footprints allowed)
		)
		(placement
			(enabled no)
			(sheetname "")
		)
		(fill
			(thermal_gap 0.5)
			(thermal_bridge_width 0.5)
			(island_removal_mode 0)
		)
		(polygon
			(pts
				(arc
					(start 310.106568 -400.477228)
					(mid 309.725568 -400.858228)
					(end 310.106568 -401.239228)
				)
				(arc
					(start 310.970168 -401.239228)
					(mid 311.351168 -400.858228)
					(end 310.970168 -400.477228)
				)
			)
		)
	)
	(zone
		(layers "F.Cu" "B.Cu" "In1.Cu" "In2.Cu" "In3.Cu" "In4.Cu" "In5.Cu" "In6.Cu"
			"In7.Cu" "In8.Cu" "In9.Cu" "In10.Cu" "In11.Cu" "In12.Cu" "In13.Cu" "In14.Cu"
			"In15.Cu" "In16.Cu"
		)
		(hatch none 0.5)
		(connect_pads
			(clearance 0)
		)
		(min_thickness 0.25)
		(keepout
			(tracks not_allowed)
			(vias allowed)
			(pads allowed)
			(copperpour not_allowed)
			(footprints allowed)
		)
		(placement
			(enabled no)
			(sheetname "")
		)
		(fill
			(thermal_gap 0.5)
			(thermal_bridge_width 0.5)
			(island_removal_mode 0)
		)
		(polygon
			(pts
				(arc
					(start 115.100354 -216.966292)
					(mid 115.028365 -216.894133)
					(end 114.92992 -216.86774)
				)
				(arc
					(start 114.92992 -216.86774)
					(mid 114.790726 -216.925396)
					(end 114.73307 -217.06459)
				)
				(arc
					(start 114.73307 -217.06459)
					(mid 114.739827 -217.115471)
					(end 114.759486 -217.162888)
				)
				(arc
					(start 115.229132 -217.976704)
					(mid 115.301121 -218.048863)
					(end 115.399566 -218.075256)
				)
				(arc
					(start 115.399566 -218.075256)
					(mid 115.53876 -218.0176)
					(end 115.596416 -217.878406)
				)
				(arc
					(start 115.596416 -217.878406)
					(mid 115.589659 -217.827525)
					(end 115.57 -217.780108)
				)
			)
		)
	)
	(zone
		(layers "F.Cu" "B.Cu" "In1.Cu" "In2.Cu" "In3.Cu" "In4.Cu" "In5.Cu" "In6.Cu"
			"In7.Cu" "In8.Cu" "In9.Cu" "In10.Cu" "In11.Cu" "In12.Cu" "In13.Cu" "In14.Cu"
			"In15.Cu" "In16.Cu"
		)
		(hatch none 0.5)
		(connect_pads
			(clearance 0)
		)
		(min_thickness 0.25)
		(keepout
			(tracks not_allowed)
			(vias allowed)
			(pads allowed)
			(copperpour not_allowed)
			(footprints allowed)
		)
		(placement
			(enabled no)
			(sheetname "")
		)
		(fill
			(thermal_gap 0.5)
			(thermal_bridge_width 0.5)
			(island_removal_mode 0)
		)
		(polygon
			(pts
				(arc
					(start 126.066296 -224.389442)
					(mid 125.408436 -224.389442)
					(end 126.066296 -224.389442)
				)
			)
		)
	)
	(zone
		(layers "F.Cu" "B.Cu" "In1.Cu" "In2.Cu" "In3.Cu" "In4.Cu" "In5.Cu" "In6.Cu"
			"In7.Cu" "In8.Cu" "In9.Cu" "In10.Cu" "In11.Cu" "In12.Cu" "In13.Cu" "In14.Cu"
			"In15.Cu" "In16.Cu"
		)
		(hatch none 0.5)
		(connect_pads
			(clearance 0)
		)
		(min_thickness 0.25)
		(keepout
			(tracks not_allowed)
			(vias allowed)
			(pads allowed)
			(copperpour not_allowed)
			(footprints allowed)
		)
		(placement
			(enabled no)
			(sheetname "")
		)
		(fill
			(thermal_gap 0.5)
			(thermal_bridge_width 0.5)
			(island_removal_mode 0)
		)
		(polygon
			(pts
				(arc
					(start 89.2556 -221.035626)
					(mid 89.183611 -220.963467)
					(end 89.085166 -220.937074)
				)
				(arc
					(start 89.085166 -220.937074)
					(mid 88.945972 -220.99473)
					(end 88.888316 -221.133924)
				)
				(arc
					(start 88.888316 -221.133924)
					(mid 88.895073 -221.184805)
					(end 88.914732 -221.232222)
				)
				(arc
					(start 89.384378 -222.046038)
					(mid 89.456367 -222.118197)
					(end 89.554812 -222.14459)
				)
				(arc
					(start 89.554812 -222.14459)
					(mid 89.694006 -222.086934)
					(end 89.751662 -221.94774)
				)
				(arc
					(start 89.751662 -221.94774)
					(mid 89.744905 -221.896859)
					(end 89.725246 -221.849442)
				)
			)
		)
	)
	(zone
		(layers "F.Cu" "B.Cu" "In1.Cu" "In2.Cu" "In3.Cu" "In4.Cu" "In5.Cu" "In6.Cu"
			"In7.Cu" "In8.Cu" "In9.Cu" "In10.Cu" "In11.Cu" "In12.Cu" "In13.Cu" "In14.Cu"
			"In15.Cu" "In16.Cu"
		)
		(hatch none 0.5)
		(connect_pads
			(clearance 0)
		)
		(min_thickness 0.25)
		(keepout
			(tracks not_allowed)
			(vias allowed)
			(pads allowed)
			(copperpour not_allowed)
			(footprints allowed)
		)
		(placement
			(enabled no)
			(sheetname "")
		)
		(fill
			(thermal_gap 0.5)
			(thermal_bridge_width 0.5)
			(island_removal_mode 0)
		)
		(polygon
			(pts
				(arc
					(start 369.307364 -217.878406)
					(mid 368.649504 -217.878406)
					(end 369.307364 -217.878406)
				)
			)
		)
	)
	(zone
		(layers "F.Cu" "B.Cu" "In1.Cu" "In2.Cu" "In3.Cu" "In4.Cu" "In5.Cu" "In6.Cu"
			"In7.Cu" "In8.Cu" "In9.Cu" "In10.Cu" "In11.Cu" "In12.Cu" "In13.Cu" "In14.Cu"
			"In15.Cu" "In16.Cu"
		)
		(hatch none 0.5)
		(connect_pads
			(clearance 0)
		)
		(min_thickness 0.25)
		(keepout
			(tracks not_allowed)
			(vias allowed)
			(pads allowed)
			(copperpour not_allowed)
			(footprints allowed)
		)
		(placement
			(enabled no)
			(sheetname "")
		)
		(fill
			(thermal_gap 0.5)
			(thermal_bridge_width 0.5)
			(island_removal_mode 0)
		)
		(polygon
			(pts
				(arc
					(start 47.979838 -400.477228)
					(mid 47.598838 -400.858228)
					(end 47.979838 -401.239228)
				)
				(arc
					(start 48.843438 -401.239228)
					(mid 49.224438 -400.858228)
					(end 48.843438 -400.477228)
				)
			)
		)
	)
	(zone
		(layers "F.Cu" "B.Cu" "In1.Cu" "In2.Cu" "In3.Cu" "In4.Cu" "In5.Cu" "In6.Cu"
			"In7.Cu" "In8.Cu" "In9.Cu" "In10.Cu" "In11.Cu" "In12.Cu" "In13.Cu" "In14.Cu"
			"In15.Cu" "In16.Cu"
		)
		(hatch none 0.5)
		(connect_pads
			(clearance 0)
		)
		(min_thickness 0.25)
		(keepout
			(tracks not_allowed)
			(vias allowed)
			(pads allowed)
			(copperpour not_allowed)
			(footprints allowed)
		)
		(placement
			(enabled no)
			(sheetname "")
		)
		(fill
			(thermal_gap 0.5)
			(thermal_bridge_width 0.5)
			(island_removal_mode 0)
		)
		(polygon
			(pts
				(arc
					(start 105.231692 -221.231968)
					(mid 105.251376 -221.184558)
					(end 105.258108 -221.13367)
				)
				(arc
					(start 105.258108 -221.13367)
					(mid 105.200452 -220.994476)
					(end 105.061258 -220.93682)
				)
				(arc
					(start 105.061258 -220.93682)
					(mid 104.962827 -220.963236)
					(end 104.890824 -221.035372)
				)
				(arc
					(start 104.421178 -221.849442)
					(mid 104.401494 -221.896852)
					(end 104.394762 -221.94774)
				)
				(arc
					(start 104.394762 -221.94774)
					(mid 104.452418 -222.086934)
					(end 104.591612 -222.14459)
				)
				(arc
					(start 104.591612 -222.14459)
					(mid 104.690043 -222.118174)
					(end 104.762046 -222.046038)
				)
			)
		)
	)
	(zone
		(layers "F.Cu" "B.Cu" "In1.Cu" "In2.Cu" "In3.Cu" "In4.Cu" "In5.Cu" "In6.Cu"
			"In7.Cu" "In8.Cu" "In9.Cu" "In10.Cu" "In11.Cu" "In12.Cu" "In13.Cu" "In14.Cu"
			"In15.Cu" "In16.Cu"
		)
		(hatch none 0.5)
		(connect_pads
			(clearance 0)
		)
		(min_thickness 0.25)
		(keepout
			(tracks not_allowed)
			(vias allowed)
			(pads allowed)
			(copperpour not_allowed)
			(footprints allowed)
		)
		(placement
			(enabled no)
			(sheetname "")
		)
		(fill
			(thermal_gap 0.5)
			(thermal_bridge_width 0.5)
			(island_removal_mode 0)
		)
		(polygon
			(pts
				(arc
					(start 248.767346 -2.5908)
					(mid 249.148346 -2.9718)
					(end 249.529346 -2.5908)
				)
				(arc
					(start 249.529346 -1.7272)
					(mid 249.148346 -1.3462)
					(end 248.767346 -1.7272)
				)
			)
		)
	)
	(zone
		(layers "F.Cu" "B.Cu" "In1.Cu" "In2.Cu" "In3.Cu" "In4.Cu" "In5.Cu" "In6.Cu"
			"In7.Cu" "In8.Cu" "In9.Cu" "In10.Cu" "In11.Cu" "In12.Cu" "In13.Cu" "In14.Cu"
			"In15.Cu" "In16.Cu"
		)
		(hatch none 0.5)
		(connect_pads
			(clearance 0)
		)
		(min_thickness 0.25)
		(keepout
			(tracks not_allowed)
			(vias allowed)
			(pads allowed)
			(copperpour not_allowed)
			(footprints allowed)
		)
		(placement
			(enabled no)
			(sheetname "")
		)
		(fill
			(thermal_gap 0.5)
			(thermal_bridge_width 0.5)
			(island_removal_mode 0)
		)
		(polygon
			(pts
				(arc
					(start 348.16161 -217.064336)
					(mid 347.50375 -217.064336)
					(end 348.16161 -217.064336)
				)
			)
		)
	)
	(zone
		(layers "F.Cu" "B.Cu" "In1.Cu" "In2.Cu" "In3.Cu" "In4.Cu" "In5.Cu" "In6.Cu"
			"In7.Cu" "In8.Cu" "In9.Cu" "In10.Cu" "In11.Cu" "In12.Cu" "In13.Cu" "In14.Cu"
			"In15.Cu" "In16.Cu"
		)
		(hatch none 0.5)
		(connect_pads
			(clearance 0)
		)
		(min_thickness 0.25)
		(keepout
			(tracks not_allowed)
			(vias allowed)
			(pads allowed)
			(copperpour not_allowed)
			(footprints allowed)
		)
		(placement
			(enabled no)
			(sheetname "")
		)
		(fill
			(thermal_gap 0.5)
			(thermal_bridge_width 0.5)
			(island_removal_mode 0)
		)
		(polygon
			(pts
				(arc
					(start 372.59641 -220.319854)
					(mid 371.93855 -220.319854)
					(end 372.59641 -220.319854)
				)
			)
		)
	)
	(zone
		(layers "F.Cu" "B.Cu" "In1.Cu" "In2.Cu" "In3.Cu" "In4.Cu" "In5.Cu" "In6.Cu"
			"In7.Cu" "In8.Cu" "In9.Cu" "In10.Cu" "In11.Cu" "In12.Cu" "In13.Cu" "In14.Cu"
			"In15.Cu" "In16.Cu"
		)
		(hatch none 0.5)
		(connect_pads
			(clearance 0)
		)
		(min_thickness 0.25)
		(keepout
			(tracks not_allowed)
			(vias allowed)
			(pads allowed)
			(copperpour not_allowed)
			(footprints allowed)
		)
		(placement
			(enabled no)
			(sheetname "")
		)
		(fill
			(thermal_gap 0.5)
			(thermal_bridge_width 0.5)
			(island_removal_mode 0)
		)
		(polygon
			(pts
				(arc
					(start 102.023418 -279.964134)
					(mid 102.681278 -279.964134)
					(end 102.023418 -279.964134)
				)
			)
		)
	)
	(zone
		(layers "F.Cu" "B.Cu" "In1.Cu" "In2.Cu" "In3.Cu" "In4.Cu" "In5.Cu" "In6.Cu"
			"In7.Cu" "In8.Cu" "In9.Cu" "In10.Cu" "In11.Cu" "In12.Cu" "In13.Cu" "In14.Cu"
			"In15.Cu" "In16.Cu"
		)
		(hatch none 0.5)
		(connect_pads
			(clearance 0)
		)
		(min_thickness 0.25)
		(keepout
			(tracks not_allowed)
			(vias allowed)
			(pads allowed)
			(copperpour not_allowed)
			(footprints allowed)
		)
		(placement
			(enabled no)
			(sheetname "")
		)
		(fill
			(thermal_gap 0.5)
			(thermal_bridge_width 0.5)
			(island_removal_mode 0)
		)
		(polygon
			(pts
				(arc
					(start 100.801678 -281.59202)
					(mid 100.143818 -281.59202)
					(end 100.801678 -281.59202)
				)
			)
		)
	)
	(zone
		(layers "F.Cu" "B.Cu" "In1.Cu" "In2.Cu" "In3.Cu" "In4.Cu" "In5.Cu" "In6.Cu"
			"In7.Cu" "In8.Cu" "In9.Cu" "In10.Cu" "In11.Cu" "In12.Cu" "In13.Cu" "In14.Cu"
			"In15.Cu" "In16.Cu"
		)
		(hatch none 0.5)
		(connect_pads
			(clearance 0)
		)
		(min_thickness 0.25)
		(keepout
			(tracks not_allowed)
			(vias allowed)
			(pads allowed)
			(copperpour not_allowed)
			(footprints allowed)
		)
		(placement
			(enabled no)
			(sheetname "")
		)
		(fill
			(thermal_gap 0.5)
			(thermal_bridge_width 0.5)
			(island_removal_mode 0)
		)
		(polygon
			(pts
				(arc
					(start 349.211392 -280.778204)
					(mid 348.553532 -280.778204)
					(end 349.211392 -280.778204)
				)
			)
		)
	)
	(zone
		(layers "F.Cu" "B.Cu" "In1.Cu" "In2.Cu" "In3.Cu" "In4.Cu" "In5.Cu" "In6.Cu"
			"In7.Cu" "In8.Cu" "In9.Cu" "In10.Cu" "In11.Cu" "In12.Cu" "In13.Cu" "In14.Cu"
			"In15.Cu" "In16.Cu"
		)
		(hatch none 0.5)
		(connect_pads
			(clearance 0)
		)
		(min_thickness 0.25)
		(keepout
			(tracks not_allowed)
			(vias allowed)
			(pads allowed)
			(copperpour not_allowed)
			(footprints allowed)
		)
		(placement
			(enabled no)
			(sheetname "")
		)
		(fill
			(thermal_gap 0.5)
			(thermal_bridge_width 0.5)
			(island_removal_mode 0)
		)
		(polygon
			(pts
				(arc
					(start 349.571564 -221.133924)
					(mid 348.913704 -221.133924)
					(end 349.571564 -221.133924)
				)
			)
		)
	)
	(zone
		(layers "F.Cu" "B.Cu" "In1.Cu" "In2.Cu" "In3.Cu" "In4.Cu" "In5.Cu" "In6.Cu"
			"In7.Cu" "In8.Cu" "In9.Cu" "In10.Cu" "In11.Cu" "In12.Cu" "In13.Cu" "In14.Cu"
			"In15.Cu" "In16.Cu"
		)
		(hatch none 0.5)
		(connect_pads
			(clearance 0)
		)
		(min_thickness 0.25)
		(keepout
			(tracks not_allowed)
			(vias allowed)
			(pads allowed)
			(copperpour not_allowed)
			(footprints allowed)
		)
		(placement
			(enabled no)
			(sheetname "")
		)
		(fill
			(thermal_gap 0.5)
			(thermal_bridge_width 0.5)
			(island_removal_mode 0)
		)
		(polygon
			(pts
				(arc
					(start 341.58301 -215.436704)
					(mid 340.92515 -215.436704)
					(end 341.58301 -215.436704)
				)
			)
		)
	)
	(zone
		(layers "F.Cu" "B.Cu" "In1.Cu" "In2.Cu" "In3.Cu" "In4.Cu" "In5.Cu" "In6.Cu"
			"In7.Cu" "In8.Cu" "In9.Cu" "In10.Cu" "In11.Cu" "In12.Cu" "In13.Cu" "In14.Cu"
			"In15.Cu" "In16.Cu"
		)
		(hatch none 0.5)
		(connect_pads
			(clearance 0)
		)
		(min_thickness 0.25)
		(keepout
			(tracks not_allowed)
			(vias allowed)
			(pads allowed)
			(copperpour not_allowed)
			(footprints allowed)
		)
		(placement
			(enabled no)
			(sheetname "")
		)
		(fill
			(thermal_gap 0.5)
			(thermal_bridge_width 0.5)
			(island_removal_mode 0)
		)
		(polygon
			(pts
				(arc
					(start 116.979954 -220.22181)
					(mid 116.907965 -220.149651)
					(end 116.80952 -220.123258)
				)
				(arc
					(start 116.80952 -220.123258)
					(mid 116.670326 -220.180914)
					(end 116.61267 -220.320108)
				)
				(arc
					(start 116.61267 -220.320108)
					(mid 116.619427 -220.370989)
					(end 116.639086 -220.418406)
				)
				(arc
					(start 117.108732 -221.232222)
					(mid 117.180721 -221.304381)
					(end 117.279166 -221.330774)
				)
				(arc
					(start 117.279166 -221.330774)
					(mid 117.41836 -221.273118)
					(end 117.476016 -221.133924)
				)
				(arc
					(start 117.476016 -221.133924)
					(mid 117.469259 -221.083043)
					(end 117.4496 -221.035626)
				)
			)
		)
	)
	(zone
		(layers "F.Cu" "B.Cu" "In1.Cu" "In2.Cu" "In3.Cu" "In4.Cu" "In5.Cu" "In6.Cu"
			"In7.Cu" "In8.Cu" "In9.Cu" "In10.Cu" "In11.Cu" "In12.Cu" "In13.Cu" "In14.Cu"
			"In15.Cu" "In16.Cu"
		)
		(hatch none 0.5)
		(connect_pads
			(clearance 0)
		)
		(min_thickness 0.25)
		(keepout
			(tracks not_allowed)
			(vias allowed)
			(pads allowed)
			(copperpour not_allowed)
			(footprints allowed)
		)
		(placement
			(enabled no)
			(sheetname "")
		)
		(fill
			(thermal_gap 0.5)
			(thermal_bridge_width 0.5)
			(island_removal_mode 0)
		)
		(polygon
			(pts
				(arc
					(start 313.169808 -400.477228)
					(mid 312.788808 -400.858228)
					(end 313.169808 -401.239228)
				)
				(arc
					(start 314.033408 -401.239228)
					(mid 314.414408 -400.858228)
					(end 314.033408 -400.477228)
				)
			)
		)
	)
	(zone
		(layers "F.Cu" "B.Cu" "In1.Cu" "In2.Cu" "In3.Cu" "In4.Cu" "In5.Cu" "In6.Cu"
			"In7.Cu" "In8.Cu" "In9.Cu" "In10.Cu" "In11.Cu" "In12.Cu" "In13.Cu" "In14.Cu"
			"In15.Cu" "In16.Cu"
		)
		(hatch none 0.5)
		(connect_pads
			(clearance 0)
		)
		(min_thickness 0.25)
		(keepout
			(tracks not_allowed)
			(vias allowed)
			(pads allowed)
			(copperpour not_allowed)
			(footprints allowed)
		)
		(placement
			(enabled no)
			(sheetname "")
		)
		(fill
			(thermal_gap 0.5)
			(thermal_bridge_width 0.5)
			(island_removal_mode 0)
		)
		(polygon
			(pts
				(arc
					(start 363.668564 -224.389442)
					(mid 363.010704 -224.389442)
					(end 363.668564 -224.389442)
				)
			)
		)
	)
	(zone
		(layers "F.Cu" "B.Cu" "In1.Cu" "In2.Cu" "In3.Cu" "In4.Cu" "In5.Cu" "In6.Cu"
			"In7.Cu" "In8.Cu" "In9.Cu" "In10.Cu" "In11.Cu" "In12.Cu" "In13.Cu" "In14.Cu"
			"In15.Cu" "In16.Cu"
		)
		(hatch none 0.5)
		(connect_pads
			(clearance 0)
		)
		(min_thickness 0.25)
		(keepout
			(tracks not_allowed)
			(vias allowed)
			(pads allowed)
			(copperpour not_allowed)
			(footprints allowed)
		)
		(placement
			(enabled no)
			(sheetname "")
		)
		(fill
			(thermal_gap 0.5)
			(thermal_bridge_width 0.5)
			(island_removal_mode 0)
		)
		(polygon
			(pts
				(arc
					(start 374.47601 -223.575626)
					(mid 373.81815 -223.575626)
					(end 374.47601 -223.575626)
				)
			)
		)
	)
	(zone
		(layers "F.Cu" "B.Cu" "In1.Cu" "In2.Cu" "In3.Cu" "In4.Cu" "In5.Cu" "In6.Cu"
			"In7.Cu" "In8.Cu" "In9.Cu" "In10.Cu" "In11.Cu" "In12.Cu" "In13.Cu" "In14.Cu"
			"In15.Cu" "In16.Cu"
		)
		(hatch none 0.5)
		(connect_pads
			(clearance 0)
		)
		(min_thickness 0.25)
		(keepout
			(tracks not_allowed)
			(vias allowed)
			(pads allowed)
			(copperpour not_allowed)
			(footprints allowed)
		)
		(placement
			(enabled no)
			(sheetname "")
		)
		(fill
			(thermal_gap 0.5)
			(thermal_bridge_width 0.5)
			(island_removal_mode 0)
		)
		(polygon
			(pts
				(arc
					(start 402.528786 -4.57073)
					(mid 402.147786 -4.95173)
					(end 402.528786 -5.33273)
				)
				(arc
					(start 403.392386 -5.33273)
					(mid 403.773386 -4.95173)
					(end 403.392386 -4.57073)
				)
			)
		)
	)
	(zone
		(layers "F.Cu" "B.Cu" "In1.Cu" "In2.Cu" "In3.Cu" "In4.Cu" "In5.Cu" "In6.Cu"
			"In7.Cu" "In8.Cu" "In9.Cu" "In10.Cu" "In11.Cu" "In12.Cu" "In13.Cu" "In14.Cu"
			"In15.Cu" "In16.Cu"
		)
		(hatch none 0.5)
		(connect_pads
			(clearance 0)
		)
		(min_thickness 0.25)
		(keepout
			(tracks not_allowed)
			(vias allowed)
			(pads allowed)
			(copperpour not_allowed)
			(footprints allowed)
		)
		(placement
			(enabled no)
			(sheetname "")
		)
		(fill
			(thermal_gap 0.5)
			(thermal_bridge_width 0.5)
			(island_removal_mode 0)
		)
		(polygon
			(pts
				(arc
					(start 340.484714 -217.162634)
					(mid 340.504398 -217.115224)
					(end 340.51113 -217.064336)
				)
				(arc
					(start 340.51113 -217.064336)
					(mid 340.453474 -216.925142)
					(end 340.31428 -216.867486)
				)
				(arc
					(start 340.31428 -216.867486)
					(mid 340.215849 -216.893902)
					(end 340.143846 -216.966038)
				)
				(arc
					(start 339.6742 -217.780108)
					(mid 339.654516 -217.827518)
					(end 339.647784 -217.878406)
				)
				(arc
					(start 339.647784 -217.878406)
					(mid 339.70544 -218.0176)
					(end 339.844634 -218.075256)
				)
				(arc
					(start 339.844634 -218.075256)
					(mid 339.943065 -218.04884)
					(end 340.015068 -217.976704)
				)
			)
		)
	)
	(zone
		(layers "F.Cu" "B.Cu" "In1.Cu" "In2.Cu" "In3.Cu" "In4.Cu" "In5.Cu" "In6.Cu"
			"In7.Cu" "In8.Cu" "In9.Cu" "In10.Cu" "In11.Cu" "In12.Cu" "In13.Cu" "In14.Cu"
			"In15.Cu" "In16.Cu"
		)
		(hatch none 0.5)
		(connect_pads
			(clearance 0)
		)
		(min_thickness 0.25)
		(keepout
			(tracks not_allowed)
			(vias allowed)
			(pads allowed)
			(copperpour not_allowed)
			(footprints allowed)
		)
		(placement
			(enabled no)
			(sheetname "")
		)
		(fill
			(thermal_gap 0.5)
			(thermal_bridge_width 0.5)
			(island_removal_mode 0)
		)
		(polygon
			(pts
				(arc
					(start 108.0516 -224.291144)
					(mid 107.979611 -224.218985)
					(end 107.881166 -224.192592)
				)
				(arc
					(start 107.881166 -224.192592)
					(mid 107.741972 -224.250248)
					(end 107.684316 -224.389442)
				)
				(arc
					(start 107.684316 -224.389442)
					(mid 107.691073 -224.440323)
					(end 107.710732 -224.48774)
				)
				(arc
					(start 108.180378 -225.301556)
					(mid 108.252367 -225.373715)
					(end 108.350812 -225.400108)
				)
				(arc
					(start 108.350812 -225.400108)
					(mid 108.490006 -225.342452)
					(end 108.547662 -225.203258)
				)
				(arc
					(start 108.547662 -225.203258)
					(mid 108.540905 -225.152377)
					(end 108.521246 -225.10496)
				)
			)
		)
	)
	(zone
		(layers "F.Cu" "B.Cu" "In1.Cu" "In2.Cu" "In3.Cu" "In4.Cu" "In5.Cu" "In6.Cu"
			"In7.Cu" "In8.Cu" "In9.Cu" "In10.Cu" "In11.Cu" "In12.Cu" "In13.Cu" "In14.Cu"
			"In15.Cu" "In16.Cu"
		)
		(hatch none 0.5)
		(connect_pads
			(clearance 0)
		)
		(min_thickness 0.25)
		(keepout
			(tracks not_allowed)
			(vias allowed)
			(pads allowed)
			(copperpour not_allowed)
			(footprints allowed)
		)
		(placement
			(enabled no)
			(sheetname "")
		)
		(fill
			(thermal_gap 0.5)
			(thermal_bridge_width 0.5)
			(island_removal_mode 0)
		)
		(polygon
			(pts
				(arc
					(start 355.320346 -276.708616)
					(mid 354.662486 -276.708616)
					(end 355.320346 -276.708616)
				)
			)
		)
	)
	(zone
		(layers "F.Cu" "B.Cu" "In1.Cu" "In2.Cu" "In3.Cu" "In4.Cu" "In5.Cu" "In6.Cu"
			"In7.Cu" "In8.Cu" "In9.Cu" "In10.Cu" "In11.Cu" "In12.Cu" "In13.Cu" "In14.Cu"
			"In15.Cu" "In16.Cu"
		)
		(hatch none 0.5)
		(connect_pads
			(clearance 0)
		)
		(min_thickness 0.25)
		(keepout
			(tracks not_allowed)
			(vias allowed)
			(pads allowed)
			(copperpour not_allowed)
			(footprints allowed)
		)
		(placement
			(enabled no)
			(sheetname "")
		)
		(fill
			(thermal_gap 0.5)
			(thermal_bridge_width 0.5)
			(island_removal_mode 0)
		)
		(polygon
			(pts
				(arc
					(start 93.642942 -218.692222)
					(mid 92.985082 -218.692222)
					(end 93.642942 -218.692222)
				)
			)
		)
	)
	(zone
		(layers "F.Cu" "B.Cu" "In1.Cu" "In2.Cu" "In3.Cu" "In4.Cu" "In5.Cu" "In6.Cu"
			"In7.Cu" "In8.Cu" "In9.Cu" "In10.Cu" "In11.Cu" "In12.Cu" "In13.Cu" "In14.Cu"
			"In15.Cu" "In16.Cu"
		)
		(hatch none 0.5)
		(connect_pads
			(clearance 0)
		)
		(min_thickness 0.25)
		(keepout
			(tracks not_allowed)
			(vias allowed)
			(pads allowed)
			(copperpour not_allowed)
			(footprints allowed)
		)
		(placement
			(enabled no)
			(sheetname "")
		)
		(fill
			(thermal_gap 0.5)
			(thermal_bridge_width 0.5)
			(island_removal_mode 0)
		)
		(polygon
			(pts
				(arc
					(start 108.0516 -217.780108)
					(mid 107.979611 -217.707949)
					(end 107.881166 -217.681556)
				)
				(arc
					(start 107.881166 -217.681556)
					(mid 107.741972 -217.739212)
					(end 107.684316 -217.878406)
				)
				(arc
					(start 107.684316 -217.878406)
					(mid 107.691073 -217.929287)
					(end 107.710732 -217.976704)
				)
				(arc
					(start 108.180378 -218.79052)
					(mid 108.252367 -218.862679)
					(end 108.350812 -218.889072)
				)
				(arc
					(start 108.350812 -218.889072)
					(mid 108.490006 -218.831416)
					(end 108.547662 -218.692222)
				)
				(arc
					(start 108.547662 -218.692222)
					(mid 108.540905 -218.641341)
					(end 108.521246 -218.593924)
				)
			)
		)
	)
	(zone
		(layers "F.Cu" "B.Cu" "In1.Cu" "In2.Cu" "In3.Cu" "In4.Cu" "In5.Cu" "In6.Cu"
			"In7.Cu" "In8.Cu" "In9.Cu" "In10.Cu" "In11.Cu" "In12.Cu" "In13.Cu" "In14.Cu"
			"In15.Cu" "In16.Cu"
		)
		(hatch none 0.5)
		(connect_pads
			(clearance 0)
		)
		(min_thickness 0.25)
		(keepout
			(tracks not_allowed)
			(vias allowed)
			(pads allowed)
			(copperpour not_allowed)
			(footprints allowed)
		)
		(placement
			(enabled no)
			(sheetname "")
		)
		(fill
			(thermal_gap 0.5)
			(thermal_bridge_width 0.5)
			(island_removal_mode 0)
		)
		(polygon
			(pts
				(arc
					(start 87.801958 -403.502876)
					(mid 87.420958 -403.883876)
					(end 87.801958 -404.264876)
				)
				(arc
					(start 88.665558 -404.264876)
					(mid 89.046558 -403.883876)
					(end 88.665558 -403.502876)
				)
			)
		)
	)
	(zone
		(layers "F.Cu" "B.Cu" "In1.Cu" "In2.Cu" "In3.Cu" "In4.Cu" "In5.Cu" "In6.Cu"
			"In7.Cu" "In8.Cu" "In9.Cu" "In10.Cu" "In11.Cu" "In12.Cu" "In13.Cu" "In14.Cu"
			"In15.Cu" "In16.Cu"
		)
		(hatch none 0.5)
		(connect_pads
			(clearance 0)
		)
		(min_thickness 0.25)
		(keepout
			(tracks not_allowed)
			(vias allowed)
			(pads allowed)
			(copperpour not_allowed)
			(footprints allowed)
		)
		(placement
			(enabled no)
			(sheetname "")
		)
		(fill
			(thermal_gap 0.5)
			(thermal_bridge_width 0.5)
			(island_removal_mode 0)
		)
		(polygon
			(pts
				(arc
					(start 58.515758 -406.62352)
					(mid 58.134758 -407.00452)
					(end 58.515758 -407.38552)
				)
				(arc
					(start 59.379358 -407.38552)
					(mid 59.760358 -407.00452)
					(end 59.379358 -406.62352)
				)
			)
		)
	)
	(zone
		(layers "F.Cu" "B.Cu" "In1.Cu" "In2.Cu" "In3.Cu" "In4.Cu" "In5.Cu" "In6.Cu"
			"In7.Cu" "In8.Cu" "In9.Cu" "In10.Cu" "In11.Cu" "In12.Cu" "In13.Cu" "In14.Cu"
			"In15.Cu" "In16.Cu"
		)
		(hatch none 0.5)
		(connect_pads
			(clearance 0)
		)
		(min_thickness 0.25)
		(keepout
			(tracks not_allowed)
			(vias allowed)
			(pads allowed)
			(copperpour not_allowed)
			(footprints allowed)
		)
		(placement
			(enabled no)
			(sheetname "")
		)
		(fill
			(thermal_gap 0.5)
			(thermal_bridge_width 0.5)
			(island_removal_mode 0)
		)
		(polygon
			(pts
				(arc
					(start 339.70341 -221.94774)
					(mid 339.04555 -221.94774)
					(end 339.70341 -221.94774)
				)
			)
		)
	)
	(zone
		(layers "F.Cu" "B.Cu" "In1.Cu" "In2.Cu" "In3.Cu" "In4.Cu" "In5.Cu" "In6.Cu"
			"In7.Cu" "In8.Cu" "In9.Cu" "In10.Cu" "In11.Cu" "In12.Cu" "In13.Cu" "In14.Cu"
			"In15.Cu" "In16.Cu"
		)
		(hatch none 0.5)
		(connect_pads
			(clearance 0)
		)
		(min_thickness 0.25)
		(keepout
			(tracks not_allowed)
			(vias allowed)
			(pads allowed)
			(copperpour not_allowed)
			(footprints allowed)
		)
		(placement
			(enabled no)
			(sheetname "")
		)
		(fill
			(thermal_gap 0.5)
			(thermal_bridge_width 0.5)
			(island_removal_mode 0)
		)
		(polygon
			(pts
				(arc
					(start 404.324312 -6.332474)
					(mid 403.943312 -6.713474)
					(end 404.324312 -7.094474)
				)
				(arc
					(start 405.187912 -7.094474)
					(mid 405.568912 -6.713474)
					(end 405.187912 -6.332474)
				)
			)
		)
	)
	(zone
		(layers "F.Cu" "B.Cu" "In1.Cu" "In2.Cu" "In3.Cu" "In4.Cu" "In5.Cu" "In6.Cu"
			"In7.Cu" "In8.Cu" "In9.Cu" "In10.Cu" "In11.Cu" "In12.Cu" "In13.Cu" "In14.Cu"
			"In15.Cu" "In16.Cu"
		)
		(hatch none 0.5)
		(connect_pads
			(clearance 0)
		)
		(min_thickness 0.25)
		(keepout
			(tracks not_allowed)
			(vias allowed)
			(pads allowed)
			(copperpour not_allowed)
			(footprints allowed)
		)
		(placement
			(enabled no)
			(sheetname "")
		)
		(fill
			(thermal_gap 0.5)
			(thermal_bridge_width 0.5)
			(island_removal_mode 0)
		)
		(polygon
			(pts
				(arc
					(start 351.29216 -214.720932)
					(mid 351.311844 -214.673522)
					(end 351.318576 -214.622634)
				)
				(arc
					(start 351.318576 -214.622634)
					(mid 351.26092 -214.48344)
					(end 351.121726 -214.425784)
				)
				(arc
					(start 351.121726 -214.425784)
					(mid 351.023295 -214.4522)
					(end 350.951292 -214.524336)
				)
				(arc
					(start 350.481646 -215.338406)
					(mid 350.461962 -215.385816)
					(end 350.45523 -215.436704)
				)
				(arc
					(start 350.45523 -215.436704)
					(mid 350.512886 -215.575898)
					(end 350.65208 -215.633554)
				)
				(arc
					(start 350.65208 -215.633554)
					(mid 350.750511 -215.607138)
					(end 350.822514 -215.535002)
				)
			)
		)
	)
	(zone
		(layers "F.Cu" "B.Cu" "In1.Cu" "In2.Cu" "In3.Cu" "In4.Cu" "In5.Cu" "In6.Cu"
			"In7.Cu" "In8.Cu" "In9.Cu" "In10.Cu" "In11.Cu" "In12.Cu" "In13.Cu" "In14.Cu"
			"In15.Cu" "In16.Cu"
		)
		(hatch none 0.5)
		(connect_pads
			(clearance 0)
		)
		(min_thickness 0.25)
		(keepout
			(tracks not_allowed)
			(vias allowed)
			(pads allowed)
			(copperpour not_allowed)
			(footprints allowed)
		)
		(placement
			(enabled no)
			(sheetname "")
		)
		(fill
			(thermal_gap 0.5)
			(thermal_bridge_width 0.5)
			(island_removal_mode 0)
		)
		(polygon
			(pts
				(arc
					(start 79.958438 -406.62352)
					(mid 79.577438 -407.00452)
					(end 79.958438 -407.38552)
				)
				(arc
					(start 80.822038 -407.38552)
					(mid 81.203038 -407.00452)
					(end 80.822038 -406.62352)
				)
			)
		)
	)
	(zone
		(layers "F.Cu" "B.Cu" "In1.Cu" "In2.Cu" "In3.Cu" "In4.Cu" "In5.Cu" "In6.Cu"
			"In7.Cu" "In8.Cu" "In9.Cu" "In10.Cu" "In11.Cu" "In12.Cu" "In13.Cu" "In14.Cu"
			"In15.Cu" "In16.Cu"
		)
		(hatch none 0.5)
		(connect_pads
			(clearance 0)
		)
		(min_thickness 0.25)
		(keepout
			(tracks not_allowed)
			(vias allowed)
			(pads allowed)
			(copperpour not_allowed)
			(footprints allowed)
		)
		(placement
			(enabled no)
			(sheetname "")
		)
		(fill
			(thermal_gap 0.5)
			(thermal_bridge_width 0.5)
			(island_removal_mode 0)
		)
		(polygon
			(pts
				(arc
					(start 114.318796 -221.94774)
					(mid 113.660936 -221.94774)
					(end 114.318796 -221.94774)
				)
			)
		)
	)
	(zone
		(layers "F.Cu" "B.Cu" "In1.Cu" "In2.Cu" "In3.Cu" "In4.Cu" "In5.Cu" "In6.Cu"
			"In7.Cu" "In8.Cu" "In9.Cu" "In10.Cu" "In11.Cu" "In12.Cu" "In13.Cu" "In14.Cu"
			"In15.Cu" "In16.Cu"
		)
		(hatch none 0.5)
		(connect_pads
			(clearance 0)
		)
		(min_thickness 0.25)
		(keepout
			(tracks not_allowed)
			(vias allowed)
			(pads allowed)
			(copperpour not_allowed)
			(footprints allowed)
		)
		(placement
			(enabled no)
			(sheetname "")
		)
		(fill
			(thermal_gap 0.5)
			(thermal_bridge_width 0.5)
			(island_removal_mode 0)
		)
		(polygon
			(pts
				(arc
					(start 16.74114 -406.171908)
					(mid 16.36014 -405.790908)
					(end 15.97914 -406.171908)
				)
				(arc
					(start 15.97914 -407.035508)
					(mid 16.36014 -407.416508)
					(end 16.74114 -407.035508)
				)
			)
		)
	)
	(zone
		(layers "F.Cu" "B.Cu" "In1.Cu" "In2.Cu" "In3.Cu" "In4.Cu" "In5.Cu" "In6.Cu"
			"In7.Cu" "In8.Cu" "In9.Cu" "In10.Cu" "In11.Cu" "In12.Cu" "In13.Cu" "In14.Cu"
			"In15.Cu" "In16.Cu"
		)
		(hatch none 0.5)
		(connect_pads
			(clearance 0)
		)
		(min_thickness 0.25)
		(keepout
			(tracks not_allowed)
			(vias allowed)
			(pads allowed)
			(copperpour not_allowed)
			(footprints allowed)
		)
		(placement
			(enabled no)
			(sheetname "")
		)
		(fill
			(thermal_gap 0.5)
			(thermal_bridge_width 0.5)
			(island_removal_mode 0)
		)
		(polygon
			(pts
				(arc
					(start 130.765296 -221.133924)
					(mid 130.107436 -221.133924)
					(end 130.765296 -221.133924)
				)
			)
		)
	)
	(zone
		(layers "F.Cu" "B.Cu" "In1.Cu" "In2.Cu" "In3.Cu" "In4.Cu" "In5.Cu" "In6.Cu"
			"In7.Cu" "In8.Cu" "In9.Cu" "In10.Cu" "In11.Cu" "In12.Cu" "In13.Cu" "In14.Cu"
			"In15.Cu" "In16.Cu"
		)
		(hatch none 0.5)
		(connect_pads
			(clearance 0)
		)
		(min_thickness 0.25)
		(keepout
			(tracks not_allowed)
			(vias allowed)
			(pads allowed)
			(copperpour not_allowed)
			(footprints allowed)
		)
		(placement
			(enabled no)
			(sheetname "")
		)
		(fill
			(thermal_gap 0.5)
			(thermal_bridge_width 0.5)
			(island_removal_mode 0)
		)
		(polygon
			(pts
				(arc
					(start 186.129422 -17.763744)
					(mid 185.748422 -18.144744)
					(end 186.129422 -18.525744)
				)
				(arc
					(start 186.993022 -18.525744)
					(mid 187.374022 -18.144744)
					(end 186.993022 -17.763744)
				)
			)
		)
	)
	(zone
		(layers "F.Cu" "B.Cu" "In1.Cu" "In2.Cu" "In3.Cu" "In4.Cu" "In5.Cu" "In6.Cu"
			"In7.Cu" "In8.Cu" "In9.Cu" "In10.Cu" "In11.Cu" "In12.Cu" "In13.Cu" "In14.Cu"
			"In15.Cu" "In16.Cu"
		)
		(hatch none 0.5)
		(connect_pads
			(clearance 0)
		)
		(min_thickness 0.25)
		(keepout
			(tracks not_allowed)
			(vias allowed)
			(pads allowed)
			(copperpour not_allowed)
			(footprints allowed)
		)
		(placement
			(enabled no)
			(sheetname "")
		)
		(fill
			(thermal_gap 0.5)
			(thermal_bridge_width 0.5)
			(island_removal_mode 0)
		)
		(polygon
			(pts
				(arc
					(start 359.280714 -223.67367)
					(mid 359.300398 -223.62626)
					(end 359.30713 -223.575372)
				)
				(arc
					(start 359.30713 -223.575372)
					(mid 359.249474 -223.436178)
					(end 359.11028 -223.378522)
				)
				(arc
					(start 359.11028 -223.378522)
					(mid 359.011849 -223.404938)
					(end 358.939846 -223.477074)
				)
				(arc
					(start 358.4702 -224.291144)
					(mid 358.450516 -224.338554)
					(end 358.443784 -224.389442)
				)
				(arc
					(start 358.443784 -224.389442)
					(mid 358.50144 -224.528636)
					(end 358.640634 -224.586292)
				)
				(arc
					(start 358.640634 -224.586292)
					(mid 358.739065 -224.559876)
					(end 358.811068 -224.48774)
				)
			)
		)
	)
	(zone
		(layers "F.Cu" "B.Cu" "In1.Cu" "In2.Cu" "In3.Cu" "In4.Cu" "In5.Cu" "In6.Cu"
			"In7.Cu" "In8.Cu" "In9.Cu" "In10.Cu" "In11.Cu" "In12.Cu" "In13.Cu" "In14.Cu"
			"In15.Cu" "In16.Cu"
		)
		(hatch none 0.5)
		(connect_pads
			(clearance 0)
		)
		(min_thickness 0.25)
		(keepout
			(tracks not_allowed)
			(vias allowed)
			(pads allowed)
			(copperpour not_allowed)
			(footprints allowed)
		)
		(placement
			(enabled no)
			(sheetname "")
		)
		(fill
			(thermal_gap 0.5)
			(thermal_bridge_width 0.5)
			(island_removal_mode 0)
		)
		(polygon
			(pts
				(arc
					(start 353.330764 -221.133924)
					(mid 352.672904 -221.133924)
					(end 353.330764 -221.133924)
				)
			)
		)
	)
	(zone
		(layers "F.Cu" "B.Cu" "In1.Cu" "In2.Cu" "In3.Cu" "In4.Cu" "In5.Cu" "In6.Cu"
			"In7.Cu" "In8.Cu" "In9.Cu" "In10.Cu" "In11.Cu" "In12.Cu" "In13.Cu" "In14.Cu"
			"In15.Cu" "In16.Cu"
		)
		(hatch none 0.5)
		(connect_pads
			(clearance 0)
		)
		(min_thickness 0.25)
		(keepout
			(tracks not_allowed)
			(vias allowed)
			(pads allowed)
			(copperpour not_allowed)
			(footprints allowed)
		)
		(placement
			(enabled no)
			(sheetname "")
		)
		(fill
			(thermal_gap 0.5)
			(thermal_bridge_width 0.5)
			(island_removal_mode 0)
		)
		(polygon
			(pts
				(arc
					(start 358.969564 -221.133924)
					(mid 358.311704 -221.133924)
					(end 358.969564 -221.133924)
				)
			)
		)
	)
	(zone
		(layers "F.Cu" "B.Cu" "In1.Cu" "In2.Cu" "In3.Cu" "In4.Cu" "In5.Cu" "In6.Cu"
			"In7.Cu" "In8.Cu" "In9.Cu" "In10.Cu" "In11.Cu" "In12.Cu" "In13.Cu" "In14.Cu"
			"In15.Cu" "In16.Cu"
		)
		(hatch none 0.5)
		(connect_pads
			(clearance 0)
		)
		(min_thickness 0.25)
		(keepout
			(tracks not_allowed)
			(vias allowed)
			(pads allowed)
			(copperpour not_allowed)
			(footprints allowed)
		)
		(placement
			(enabled no)
			(sheetname "")
		)
		(fill
			(thermal_gap 0.5)
			(thermal_bridge_width 0.5)
			(island_removal_mode 0)
		)
		(polygon
			(pts
				(arc
					(start 345.892882 -288.818828)
					(mid 345.873198 -288.866238)
					(end 345.866466 -288.917126)
				)
				(arc
					(start 345.866466 -288.917126)
					(mid 345.924122 -289.05632)
					(end 346.063316 -289.113976)
				)
				(arc
					(start 346.063316 -289.113976)
					(mid 346.161747 -289.08756)
					(end 346.23375 -289.015424)
				)
				(arc
					(start 346.70365 -288.201354)
					(mid 346.723334 -288.153944)
					(end 346.730066 -288.103056)
				)
				(arc
					(start 346.730066 -288.103056)
					(mid 346.67241 -287.963862)
					(end 346.533216 -287.906206)
				)
				(arc
					(start 346.533216 -287.906206)
					(mid 346.434785 -287.932622)
					(end 346.362782 -288.004758)
				)
			)
		)
	)
	(zone
		(layers "F.Cu" "B.Cu" "In1.Cu" "In2.Cu" "In3.Cu" "In4.Cu" "In5.Cu" "In6.Cu"
			"In7.Cu" "In8.Cu" "In9.Cu" "In10.Cu" "In11.Cu" "In12.Cu" "In13.Cu" "In14.Cu"
			"In15.Cu" "In16.Cu"
		)
		(hatch none 0.5)
		(connect_pads
			(clearance 0)
		)
		(min_thickness 0.25)
		(keepout
			(tracks not_allowed)
			(vias allowed)
			(pads allowed)
			(copperpour not_allowed)
			(footprints allowed)
		)
		(placement
			(enabled no)
			(sheetname "")
		)
		(fill
			(thermal_gap 0.5)
			(thermal_bridge_width 0.5)
			(island_removal_mode 0)
		)
		(polygon
			(pts
				(arc
					(start 365.548164 -221.133924)
					(mid 364.890304 -221.133924)
					(end 365.548164 -221.133924)
				)
			)
		)
	)
	(zone
		(layers "F.Cu" "B.Cu" "In1.Cu" "In2.Cu" "In3.Cu" "In4.Cu" "In5.Cu" "In6.Cu"
			"In7.Cu" "In8.Cu" "In9.Cu" "In10.Cu" "In11.Cu" "In12.Cu" "In13.Cu" "In14.Cu"
			"In15.Cu" "In16.Cu"
		)
		(hatch none 0.5)
		(connect_pads
			(clearance 0)
		)
		(min_thickness 0.25)
		(keepout
			(tracks not_allowed)
			(vias allowed)
			(pads allowed)
			(copperpour not_allowed)
			(footprints allowed)
		)
		(placement
			(enabled no)
			(sheetname "")
		)
		(fill
			(thermal_gap 0.5)
			(thermal_bridge_width 0.5)
			(island_removal_mode 0)
		)
		(polygon
			(pts
				(arc
					(start 345.34221 -218.692222)
					(mid 344.68435 -218.692222)
					(end 345.34221 -218.692222)
				)
			)
		)
	)
	(zone
		(layers "F.Cu" "B.Cu" "In1.Cu" "In2.Cu" "In3.Cu" "In4.Cu" "In5.Cu" "In6.Cu"
			"In7.Cu" "In8.Cu" "In9.Cu" "In10.Cu" "In11.Cu" "In12.Cu" "In13.Cu" "In14.Cu"
			"In15.Cu" "In16.Cu"
		)
		(hatch none 0.5)
		(connect_pads
			(clearance 0)
		)
		(min_thickness 0.25)
		(keepout
			(tracks not_allowed)
			(vias allowed)
			(pads allowed)
			(copperpour not_allowed)
			(footprints allowed)
		)
		(placement
			(enabled no)
			(sheetname "")
		)
		(fill
			(thermal_gap 0.5)
			(thermal_bridge_width 0.5)
			(island_removal_mode 0)
		)
		(polygon
			(pts
				(arc
					(start 377.60656 -221.231968)
					(mid 377.626244 -221.184558)
					(end 377.632976 -221.13367)
				)
				(arc
					(start 377.632976 -221.13367)
					(mid 377.57532 -220.994476)
					(end 377.436126 -220.93682)
				)
				(arc
					(start 377.436126 -220.93682)
					(mid 377.337695 -220.963236)
					(end 377.265692 -221.035372)
				)
				(arc
					(start 376.796046 -221.849442)
					(mid 376.776362 -221.896852)
					(end 376.76963 -221.94774)
				)
				(arc
					(start 376.76963 -221.94774)
					(mid 376.827286 -222.086934)
					(end 376.96648 -222.14459)
				)
				(arc
					(start 376.96648 -222.14459)
					(mid 377.064911 -222.118174)
					(end 377.136914 -222.046038)
				)
			)
		)
	)
	(zone
		(layers "F.Cu" "B.Cu" "In1.Cu" "In2.Cu" "In3.Cu" "In4.Cu" "In5.Cu" "In6.Cu"
			"In7.Cu" "In8.Cu" "In9.Cu" "In10.Cu" "In11.Cu" "In12.Cu" "In13.Cu" "In14.Cu"
			"In15.Cu" "In16.Cu"
		)
		(hatch none 0.5)
		(connect_pads
			(clearance 0)
		)
		(min_thickness 0.25)
		(keepout
			(tracks not_allowed)
			(vias allowed)
			(pads allowed)
			(copperpour not_allowed)
			(footprints allowed)
		)
		(placement
			(enabled no)
			(sheetname "")
		)
		(fill
			(thermal_gap 0.5)
			(thermal_bridge_width 0.5)
			(island_removal_mode 0)
		)
		(polygon
			(pts
				(arc
					(start 113.848896 -224.389442)
					(mid 113.191036 -224.389442)
					(end 113.848896 -224.389442)
				)
			)
		)
	)
	(zone
		(layers "F.Cu" "B.Cu" "In1.Cu" "In2.Cu" "In3.Cu" "In4.Cu" "In5.Cu" "In6.Cu"
			"In7.Cu" "In8.Cu" "In9.Cu" "In10.Cu" "In11.Cu" "In12.Cu" "In13.Cu" "In14.Cu"
			"In15.Cu" "In16.Cu"
		)
		(hatch none 0.5)
		(connect_pads
			(clearance 0)
		)
		(min_thickness 0.25)
		(keepout
			(tracks not_allowed)
			(vias allowed)
			(pads allowed)
			(copperpour not_allowed)
			(footprints allowed)
		)
		(placement
			(enabled no)
			(sheetname "")
		)
		(fill
			(thermal_gap 0.5)
			(thermal_bridge_width 0.5)
			(island_removal_mode 0)
		)
		(polygon
			(pts
				(arc
					(start 120.537478 -286.475424)
					(mid 119.879618 -286.475424)
					(end 120.537478 -286.475424)
				)
			)
		)
	)
	(zone
		(layers "F.Cu" "B.Cu" "In1.Cu" "In2.Cu" "In3.Cu" "In4.Cu" "In5.Cu" "In6.Cu"
			"In7.Cu" "In8.Cu" "In9.Cu" "In10.Cu" "In11.Cu" "In12.Cu" "In13.Cu" "In14.Cu"
			"In15.Cu" "In16.Cu"
		)
		(hatch none 0.5)
		(connect_pads
			(clearance 0)
		)
		(min_thickness 0.25)
		(keepout
			(tracks not_allowed)
			(vias allowed)
			(pads allowed)
			(copperpour not_allowed)
			(footprints allowed)
		)
		(placement
			(enabled no)
			(sheetname "")
		)
		(fill
			(thermal_gap 0.5)
			(thermal_bridge_width 0.5)
			(island_removal_mode 0)
		)
		(polygon
			(pts
				(arc
					(start 119.879364 -289.807142)
					(mid 120.537224 -289.807142)
					(end 119.879364 -289.807142)
				)
			)
		)
	)
	(zone
		(layers "F.Cu" "B.Cu" "In1.Cu" "In2.Cu" "In3.Cu" "In4.Cu" "In5.Cu" "In6.Cu"
			"In7.Cu" "In8.Cu" "In9.Cu" "In10.Cu" "In11.Cu" "In12.Cu" "In13.Cu" "In14.Cu"
			"In15.Cu" "In16.Cu"
		)
		(hatch none 0.5)
		(connect_pads
			(clearance 0)
		)
		(min_thickness 0.25)
		(keepout
			(tracks not_allowed)
			(vias allowed)
			(pads allowed)
			(copperpour not_allowed)
			(footprints allowed)
		)
		(placement
			(enabled no)
			(sheetname "")
		)
		(fill
			(thermal_gap 0.5)
			(thermal_bridge_width 0.5)
			(island_removal_mode 0)
		)
		(polygon
			(pts
				(arc
					(start 132.644896 -224.389442)
					(mid 131.987036 -224.389442)
					(end 132.644896 -224.389442)
				)
			)
		)
	)
	(zone
		(layers "F.Cu" "B.Cu" "In1.Cu" "In2.Cu" "In3.Cu" "In4.Cu" "In5.Cu" "In6.Cu"
			"In7.Cu" "In8.Cu" "In9.Cu" "In10.Cu" "In11.Cu" "In12.Cu" "In13.Cu" "In14.Cu"
			"In15.Cu" "In16.Cu"
		)
		(hatch none 0.5)
		(connect_pads
			(clearance 0)
		)
		(min_thickness 0.25)
		(keepout
			(tracks not_allowed)
			(vias allowed)
			(pads allowed)
			(copperpour not_allowed)
			(footprints allowed)
		)
		(placement
			(enabled no)
			(sheetname "")
		)
		(fill
			(thermal_gap 0.5)
			(thermal_bridge_width 0.5)
			(island_removal_mode 0)
		)
		(polygon
			(pts
				(arc
					(start 93.095318 -288.917126)
					(mid 93.753178 -288.917126)
					(end 93.095318 -288.917126)
				)
			)
		)
	)
	(zone
		(layers "F.Cu" "B.Cu" "In1.Cu" "In2.Cu" "In3.Cu" "In4.Cu" "In5.Cu" "In6.Cu"
			"In7.Cu" "In8.Cu" "In9.Cu" "In10.Cu" "In11.Cu" "In12.Cu" "In13.Cu" "In14.Cu"
			"In15.Cu" "In16.Cu"
		)
		(hatch none 0.5)
		(connect_pads
			(clearance 0)
		)
		(min_thickness 0.25)
		(keepout
			(tracks not_allowed)
			(vias allowed)
			(pads allowed)
			(copperpour not_allowed)
			(footprints allowed)
		)
		(placement
			(enabled no)
			(sheetname "")
		)
		(fill
			(thermal_gap 0.5)
			(thermal_bridge_width 0.5)
			(island_removal_mode 0)
		)
		(polygon
			(pts
				(arc
					(start 343.802208 -403.502876)
					(mid 343.421208 -403.883876)
					(end 343.802208 -404.264876)
				)
				(arc
					(start 344.665808 -404.264876)
					(mid 345.046808 -403.883876)
					(end 344.665808 -403.502876)
				)
			)
		)
	)
	(zone
		(layers "F.Cu" "B.Cu" "In1.Cu" "In2.Cu" "In3.Cu" "In4.Cu" "In5.Cu" "In6.Cu"
			"In7.Cu" "In8.Cu" "In9.Cu" "In10.Cu" "In11.Cu" "In12.Cu" "In13.Cu" "In14.Cu"
			"In15.Cu" "In16.Cu"
		)
		(hatch none 0.5)
		(connect_pads
			(clearance 0)
		)
		(min_thickness 0.25)
		(keepout
			(tracks not_allowed)
			(vias allowed)
			(pads allowed)
			(copperpour not_allowed)
			(footprints allowed)
		)
		(placement
			(enabled no)
			(sheetname "")
		)
		(fill
			(thermal_gap 0.5)
			(thermal_bridge_width 0.5)
			(island_removal_mode 0)
		)
		(polygon
			(pts
				(arc
					(start 120.897142 -217.064336)
					(mid 120.239282 -217.064336)
					(end 120.897142 -217.064336)
				)
			)
		)
	)
	(zone
		(layers "F.Cu" "B.Cu" "In1.Cu" "In2.Cu" "In3.Cu" "In4.Cu" "In5.Cu" "In6.Cu"
			"In7.Cu" "In8.Cu" "In9.Cu" "In10.Cu" "In11.Cu" "In12.Cu" "In13.Cu" "In14.Cu"
			"In15.Cu" "In16.Cu"
		)
		(hatch none 0.5)
		(connect_pads
			(clearance 0)
		)
		(min_thickness 0.25)
		(keepout
			(tracks not_allowed)
			(vias allowed)
			(pads allowed)
			(copperpour not_allowed)
			(footprints allowed)
		)
		(placement
			(enabled no)
			(sheetname "")
		)
		(fill
			(thermal_gap 0.5)
			(thermal_bridge_width 0.5)
			(island_removal_mode 0)
		)
		(polygon
			(pts
				(arc
					(start 344.40241 -220.319854)
					(mid 343.74455 -220.319854)
					(end 344.40241 -220.319854)
				)
			)
		)
	)
	(zone
		(layers "F.Cu" "B.Cu" "In1.Cu" "In2.Cu" "In3.Cu" "In4.Cu" "In5.Cu" "In6.Cu"
			"In7.Cu" "In8.Cu" "In9.Cu" "In10.Cu" "In11.Cu" "In12.Cu" "In13.Cu" "In14.Cu"
			"In15.Cu" "In16.Cu"
		)
		(hatch none 0.5)
		(connect_pads
			(clearance 0)
		)
		(min_thickness 0.25)
		(keepout
			(tracks not_allowed)
			(vias allowed)
			(pads allowed)
			(copperpour not_allowed)
			(footprints allowed)
		)
		(placement
			(enabled no)
			(sheetname "")
		)
		(fill
			(thermal_gap 0.5)
			(thermal_bridge_width 0.5)
			(island_removal_mode 0)
		)
		(polygon
			(pts
				(arc
					(start 227.03536 -127.325628)
					(mid 227.41636 -127.706628)
					(end 227.79736 -127.325628)
				)
				(arc
					(start 227.79736 -126.462028)
					(mid 227.41636 -126.081028)
					(end 227.03536 -126.462028)
				)
			)
		)
	)
	(zone
		(layers "F.Cu" "B.Cu" "In1.Cu" "In2.Cu" "In3.Cu" "In4.Cu" "In5.Cu" "In6.Cu"
			"In7.Cu" "In8.Cu" "In9.Cu" "In10.Cu" "In11.Cu" "In12.Cu" "In13.Cu" "In14.Cu"
			"In15.Cu" "In16.Cu"
		)
		(hatch none 0.5)
		(connect_pads
			(clearance 0)
		)
		(min_thickness 0.25)
		(keepout
			(tracks not_allowed)
			(vias allowed)
			(pads allowed)
			(copperpour not_allowed)
			(footprints allowed)
		)
		(placement
			(enabled no)
			(sheetname "")
		)
		(fill
			(thermal_gap 0.5)
			(thermal_bridge_width 0.5)
			(island_removal_mode 0)
		)
		(polygon
			(pts
				(arc
					(start 344.35415 -282.307538)
					(mid 344.282161 -282.235379)
					(end 344.183716 -282.208986)
				)
				(arc
					(start 344.183716 -282.208986)
					(mid 344.044522 -282.266642)
					(end 343.986866 -282.405836)
				)
				(arc
					(start 343.986866 -282.405836)
					(mid 343.993623 -282.456717)
					(end 344.013282 -282.504134)
				)
				(arc
					(start 344.483182 -283.318204)
					(mid 344.555171 -283.390363)
					(end 344.653616 -283.416756)
				)
				(arc
					(start 344.653616 -283.416756)
					(mid 344.79281 -283.3591)
					(end 344.850466 -283.219906)
				)
				(arc
					(start 344.850466 -283.219906)
					(mid 344.843709 -283.169025)
					(end 344.82405 -283.121608)
				)
			)
		)
	)
	(zone
		(layers "F.Cu" "B.Cu" "In1.Cu" "In2.Cu" "In3.Cu" "In4.Cu" "In5.Cu" "In6.Cu"
			"In7.Cu" "In8.Cu" "In9.Cu" "In10.Cu" "In11.Cu" "In12.Cu" "In13.Cu" "In14.Cu"
			"In15.Cu" "In16.Cu"
		)
		(hatch none 0.5)
		(connect_pads
			(clearance 0)
		)
		(min_thickness 0.25)
		(keepout
			(tracks not_allowed)
			(vias allowed)
			(pads allowed)
			(copperpour not_allowed)
			(footprints allowed)
		)
		(placement
			(enabled no)
			(sheetname "")
		)
		(fill
			(thermal_gap 0.5)
			(thermal_bridge_width 0.5)
			(island_removal_mode 0)
		)
		(polygon
			(pts
				(arc
					(start 89.523824 -288.103056)
					(mid 88.865964 -288.103056)
					(end 89.523824 -288.103056)
				)
			)
		)
	)
	(zone
		(layers "F.Cu" "B.Cu" "In1.Cu" "In2.Cu" "In3.Cu" "In4.Cu" "In5.Cu" "In6.Cu"
			"In7.Cu" "In8.Cu" "In9.Cu" "In10.Cu" "In11.Cu" "In12.Cu" "In13.Cu" "In14.Cu"
			"In15.Cu" "In16.Cu"
		)
		(hatch none 0.5)
		(connect_pads
			(clearance 0)
		)
		(min_thickness 0.25)
		(keepout
			(tracks not_allowed)
			(vias allowed)
			(pads allowed)
			(copperpour not_allowed)
			(footprints allowed)
		)
		(placement
			(enabled no)
			(sheetname "")
		)
		(fill
			(thermal_gap 0.5)
			(thermal_bridge_width 0.5)
			(island_removal_mode 0)
		)
		(polygon
			(pts
				(arc
					(start 405.11857 -400.477228)
					(mid 404.73757 -400.858228)
					(end 405.11857 -401.239228)
				)
				(arc
					(start 405.98217 -401.239228)
					(mid 406.36317 -400.858228)
					(end 405.98217 -400.477228)
				)
			)
		)
	)
	(zone
		(layers "F.Cu" "B.Cu" "In1.Cu" "In2.Cu" "In3.Cu" "In4.Cu" "In5.Cu" "In6.Cu"
			"In7.Cu" "In8.Cu" "In9.Cu" "In10.Cu" "In11.Cu" "In12.Cu" "In13.Cu" "In14.Cu"
			"In15.Cu" "In16.Cu"
		)
		(hatch none 0.5)
		(connect_pads
			(clearance 0)
		)
		(min_thickness 0.25)
		(keepout
			(tracks not_allowed)
			(vias allowed)
			(pads allowed)
			(copperpour not_allowed)
			(footprints allowed)
		)
		(placement
			(enabled no)
			(sheetname "")
		)
		(fill
			(thermal_gap 0.5)
			(thermal_bridge_width 0.5)
			(island_removal_mode 0)
		)
		(polygon
			(pts
				(arc
					(start 354.380546 -281.59202)
					(mid 353.722686 -281.59202)
					(end 354.380546 -281.59202)
				)
			)
		)
	)
	(zone
		(layers "F.Cu" "B.Cu" "In1.Cu" "In2.Cu" "In3.Cu" "In4.Cu" "In5.Cu" "In6.Cu"
			"In7.Cu" "In8.Cu" "In9.Cu" "In10.Cu" "In11.Cu" "In12.Cu" "In13.Cu" "In14.Cu"
			"In15.Cu" "In16.Cu"
		)
		(hatch none 0.5)
		(connect_pads
			(clearance 0)
		)
		(min_thickness 0.25)
		(keepout
			(tracks not_allowed)
			(vias allowed)
			(pads allowed)
			(copperpour not_allowed)
			(footprints allowed)
		)
		(placement
			(enabled no)
			(sheetname "")
		)
		(fill
			(thermal_gap 0.5)
			(thermal_bridge_width 0.5)
			(island_removal_mode 0)
		)
		(polygon
			(pts
				(arc
					(start 339.233764 -221.133924)
					(mid 338.575904 -221.133924)
					(end 339.233764 -221.133924)
				)
			)
		)
	)
	(zone
		(layers "F.Cu" "B.Cu" "In1.Cu" "In2.Cu" "In3.Cu" "In4.Cu" "In5.Cu" "In6.Cu"
			"In7.Cu" "In8.Cu" "In9.Cu" "In10.Cu" "In11.Cu" "In12.Cu" "In13.Cu" "In14.Cu"
			"In15.Cu" "In16.Cu"
		)
		(hatch none 0.5)
		(connect_pads
			(clearance 0)
		)
		(min_thickness 0.25)
		(keepout
			(tracks not_allowed)
			(vias allowed)
			(pads allowed)
			(copperpour not_allowed)
			(footprints allowed)
		)
		(placement
			(enabled no)
			(sheetname "")
		)
		(fill
			(thermal_gap 0.5)
			(thermal_bridge_width 0.5)
			(island_removal_mode 0)
		)
		(polygon
			(pts
				(arc
					(start 350.292416 -274.88388)
					(mid 350.095566 -275.08073)
					(end 350.292416 -275.27758)
				)
				(arc
					(start 351.232216 -275.27758)
					(mid 351.429066 -275.08073)
					(end 351.232216 -274.88388)
				)
			)
		)
	)
	(zone
		(layers "F.Cu" "B.Cu" "In1.Cu" "In2.Cu" "In3.Cu" "In4.Cu" "In5.Cu" "In6.Cu"
			"In7.Cu" "In8.Cu" "In9.Cu" "In10.Cu" "In11.Cu" "In12.Cu" "In13.Cu" "In14.Cu"
			"In15.Cu" "In16.Cu"
		)
		(hatch none 0.5)
		(connect_pads
			(clearance 0)
		)
		(min_thickness 0.25)
		(keepout
			(tracks not_allowed)
			(vias allowed)
			(pads allowed)
			(copperpour not_allowed)
			(footprints allowed)
		)
		(placement
			(enabled no)
			(sheetname "")
		)
		(fill
			(thermal_gap 0.5)
			(thermal_bridge_width 0.5)
			(island_removal_mode 0)
		)
		(polygon
			(pts
				(arc
					(start 103.432864 -280.778204)
					(mid 104.090724 -280.778204)
					(end 103.432864 -280.778204)
				)
			)
		)
	)
	(zone
		(layers "F.Cu" "B.Cu" "In1.Cu" "In2.Cu" "In3.Cu" "In4.Cu" "In5.Cu" "In6.Cu"
			"In7.Cu" "In8.Cu" "In9.Cu" "In10.Cu" "In11.Cu" "In12.Cu" "In13.Cu" "In14.Cu"
			"In15.Cu" "In16.Cu"
		)
		(hatch none 0.5)
		(connect_pads
			(clearance 0)
		)
		(min_thickness 0.25)
		(keepout
			(tracks not_allowed)
			(vias allowed)
			(pads allowed)
			(copperpour not_allowed)
			(footprints allowed)
		)
		(placement
			(enabled no)
			(sheetname "")
		)
		(fill
			(thermal_gap 0.5)
			(thermal_bridge_width 0.5)
			(island_removal_mode 0)
		)
		(polygon
			(pts
				(arc
					(start 343.46261 -221.94774)
					(mid 342.80475 -221.94774)
					(end 343.46261 -221.94774)
				)
			)
		)
	)
	(zone
		(layers "F.Cu" "B.Cu" "In1.Cu" "In2.Cu" "In3.Cu" "In4.Cu" "In5.Cu" "In6.Cu"
			"In7.Cu" "In8.Cu" "In9.Cu" "In10.Cu" "In11.Cu" "In12.Cu" "In13.Cu" "In14.Cu"
			"In15.Cu" "In16.Cu"
		)
		(hatch none 0.5)
		(connect_pads
			(clearance 0)
		)
		(min_thickness 0.25)
		(keepout
			(tracks not_allowed)
			(vias allowed)
			(pads allowed)
			(copperpour not_allowed)
			(footprints allowed)
		)
		(placement
			(enabled no)
			(sheetname "")
		)
		(fill
			(thermal_gap 0.5)
			(thermal_bridge_width 0.5)
			(island_removal_mode 0)
		)
		(polygon
			(pts
				(arc
					(start 90.353896 -217.878406)
					(mid 89.696036 -217.878406)
					(end 90.353896 -217.878406)
				)
			)
		)
	)
	(zone
		(layers "F.Cu" "B.Cu" "In1.Cu" "In2.Cu" "In3.Cu" "In4.Cu" "In5.Cu" "In6.Cu"
			"In7.Cu" "In8.Cu" "In9.Cu" "In10.Cu" "In11.Cu" "In12.Cu" "In13.Cu" "In14.Cu"
			"In15.Cu" "In16.Cu"
		)
		(hatch none 0.5)
		(connect_pads
			(clearance 0)
		)
		(min_thickness 0.25)
		(keepout
			(tracks not_allowed)
			(vias allowed)
			(pads allowed)
			(copperpour not_allowed)
			(footprints allowed)
		)
		(placement
			(enabled no)
			(sheetname "")
		)
		(fill
			(thermal_gap 0.5)
			(thermal_bridge_width 0.5)
			(island_removal_mode 0)
		)
		(polygon
			(pts
				(arc
					(start 339.021928 -409.649168)
					(mid 338.640928 -410.030168)
					(end 339.021928 -410.411168)
				)
				(arc
					(start 339.885528 -410.411168)
					(mid 340.266528 -410.030168)
					(end 339.885528 -409.649168)
				)
			)
		)
	)
	(zone
		(layers "F.Cu" "B.Cu" "In1.Cu" "In2.Cu" "In3.Cu" "In4.Cu" "In5.Cu" "In6.Cu"
			"In7.Cu" "In8.Cu" "In9.Cu" "In10.Cu" "In11.Cu" "In12.Cu" "In13.Cu" "In14.Cu"
			"In15.Cu" "In16.Cu"
		)
		(hatch none 0.5)
		(connect_pads
			(clearance 0)
		)
		(min_thickness 0.25)
		(keepout
			(tracks not_allowed)
			(vias allowed)
			(pads allowed)
			(copperpour not_allowed)
			(footprints allowed)
		)
		(placement
			(enabled no)
			(sheetname "")
		)
		(fill
			(thermal_gap 0.5)
			(thermal_bridge_width 0.5)
			(island_removal_mode 0)
		)
		(polygon
			(pts
				(arc
					(start 38.92677 -6.343396)
					(mid 38.54577 -6.724396)
					(end 38.92677 -7.105396)
				)
				(arc
					(start 39.79037 -7.105396)
					(mid 40.17137 -6.724396)
					(end 39.79037 -6.343396)
				)
			)
		)
	)
	(zone
		(layers "F.Cu" "B.Cu" "In1.Cu" "In2.Cu" "In3.Cu" "In4.Cu" "In5.Cu" "In6.Cu"
			"In7.Cu" "In8.Cu" "In9.Cu" "In10.Cu" "In11.Cu" "In12.Cu" "In13.Cu" "In14.Cu"
			"In15.Cu" "In16.Cu"
		)
		(hatch none 0.5)
		(connect_pads
			(clearance 0)
		)
		(min_thickness 0.25)
		(keepout
			(tracks not_allowed)
			(vias allowed)
			(pads allowed)
			(copperpour not_allowed)
			(footprints allowed)
		)
		(placement
			(enabled no)
			(sheetname "")
		)
		(fill
			(thermal_gap 0.5)
			(thermal_bridge_width 0.5)
			(island_removal_mode 0)
		)
		(polygon
			(pts
				(arc
					(start 91.244928 -288.201354)
					(mid 91.264612 -288.153944)
					(end 91.271344 -288.103056)
				)
				(arc
					(start 91.271344 -288.103056)
					(mid 91.213688 -287.963862)
					(end 91.074494 -287.906206)
				)
				(arc
					(start 91.074494 -287.906206)
					(mid 90.976063 -287.932622)
					(end 90.90406 -288.004758)
				)
				(arc
					(start 90.434414 -288.818828)
					(mid 90.41473 -288.866238)
					(end 90.407998 -288.917126)
				)
				(arc
					(start 90.407998 -288.917126)
					(mid 90.465654 -289.05632)
					(end 90.604848 -289.113976)
				)
				(arc
					(start 90.604848 -289.113976)
					(mid 90.703279 -289.08756)
					(end 90.775282 -289.015424)
				)
			)
		)
	)
	(zone
		(layers "F.Cu" "B.Cu" "In1.Cu" "In2.Cu" "In3.Cu" "In4.Cu" "In5.Cu" "In6.Cu"
			"In7.Cu" "In8.Cu" "In9.Cu" "In10.Cu" "In11.Cu" "In12.Cu" "In13.Cu" "In14.Cu"
			"In15.Cu" "In16.Cu"
		)
		(hatch none 0.5)
		(connect_pads
			(clearance 0)
		)
		(min_thickness 0.25)
		(keepout
			(tracks not_allowed)
			(vias allowed)
			(pads allowed)
			(copperpour not_allowed)
			(footprints allowed)
		)
		(placement
			(enabled no)
			(sheetname "")
		)
		(fill
			(thermal_gap 0.5)
			(thermal_bridge_width 0.5)
			(island_removal_mode 0)
		)
		(polygon
			(pts
				(arc
					(start 132.754878 -288.103056)
					(mid 132.097018 -288.103056)
					(end 132.754878 -288.103056)
				)
			)
		)
	)
	(zone
		(layers "F.Cu" "B.Cu" "In1.Cu" "In2.Cu" "In3.Cu" "In4.Cu" "In5.Cu" "In6.Cu"
			"In7.Cu" "In8.Cu" "In9.Cu" "In10.Cu" "In11.Cu" "In12.Cu" "In13.Cu" "In14.Cu"
			"In15.Cu" "In16.Cu"
		)
		(hatch none 0.5)
		(connect_pads
			(clearance 0)
		)
		(min_thickness 0.25)
		(keepout
			(tracks not_allowed)
			(vias allowed)
			(pads allowed)
			(copperpour not_allowed)
			(footprints allowed)
		)
		(placement
			(enabled no)
			(sheetname "")
		)
		(fill
			(thermal_gap 0.5)
			(thermal_bridge_width 0.5)
			(island_removal_mode 0)
		)
		(polygon
			(pts
				(arc
					(start 127.006096 -217.878406)
					(mid 126.348236 -217.878406)
					(end 127.006096 -217.878406)
				)
			)
		)
	)
	(zone
		(layers "F.Cu" "B.Cu" "In1.Cu" "In2.Cu" "In3.Cu" "In4.Cu" "In5.Cu" "In6.Cu"
			"In7.Cu" "In8.Cu" "In9.Cu" "In10.Cu" "In11.Cu" "In12.Cu" "In13.Cu" "In14.Cu"
			"In15.Cu" "In16.Cu"
		)
		(hatch none 0.5)
		(connect_pads
			(clearance 0)
		)
		(min_thickness 0.25)
		(keepout
			(tracks not_allowed)
			(vias allowed)
			(pads allowed)
			(copperpour not_allowed)
			(footprints allowed)
		)
		(placement
			(enabled no)
			(sheetname "")
		)
		(fill
			(thermal_gap 0.5)
			(thermal_bridge_width 0.5)
			(island_removal_mode 0)
		)
		(polygon
			(pts
				(arc
					(start 23.915878 -18.75536)
					(mid 23.534878 -19.13636)
					(end 23.915878 -19.51736)
				)
				(arc
					(start 24.779478 -19.51736)
					(mid 25.160478 -19.13636)
					(end 24.779478 -18.75536)
				)
			)
		)
	)
	(zone
		(layers "F.Cu" "B.Cu" "In1.Cu" "In2.Cu" "In3.Cu" "In4.Cu" "In5.Cu" "In6.Cu"
			"In7.Cu" "In8.Cu" "In9.Cu" "In10.Cu" "In11.Cu" "In12.Cu" "In13.Cu" "In14.Cu"
			"In15.Cu" "In16.Cu"
		)
		(hatch none 0.5)
		(connect_pads
			(clearance 0)
		)
		(min_thickness 0.25)
		(keepout
			(tracks not_allowed)
			(vias allowed)
			(pads allowed)
			(copperpour not_allowed)
			(footprints allowed)
		)
		(placement
			(enabled no)
			(sheetname "")
		)
		(fill
			(thermal_gap 0.5)
			(thermal_bridge_width 0.5)
			(island_removal_mode 0)
		)
		(polygon
			(pts
				(arc
					(start 182.422292 -50.085498)
					(mid 182.041292 -49.704498)
					(end 181.660292 -50.085498)
				)
				(arc
					(start 181.660292 -50.949098)
					(mid 182.041292 -51.330098)
					(end 182.422292 -50.949098)
				)
			)
		)
	)
	(zone
		(layers "F.Cu" "B.Cu" "In1.Cu" "In2.Cu" "In3.Cu" "In4.Cu" "In5.Cu" "In6.Cu"
			"In7.Cu" "In8.Cu" "In9.Cu" "In10.Cu" "In11.Cu" "In12.Cu" "In13.Cu" "In14.Cu"
			"In15.Cu" "In16.Cu"
		)
		(hatch none 0.5)
		(connect_pads
			(clearance 0)
		)
		(min_thickness 0.25)
		(keepout
			(tracks not_allowed)
			(vias allowed)
			(pads allowed)
			(copperpour not_allowed)
			(footprints allowed)
		)
		(placement
			(enabled no)
			(sheetname "")
		)
		(fill
			(thermal_gap 0.5)
			(thermal_bridge_width 0.5)
			(island_removal_mode 0)
		)
		(polygon
			(pts
				(arc
					(start 355.209856 -214.622634)
					(mid 354.551996 -214.622634)
					(end 355.209856 -214.622634)
				)
			)
		)
	)
	(zone
		(layers "F.Cu" "B.Cu" "In1.Cu" "In2.Cu" "In3.Cu" "In4.Cu" "In5.Cu" "In6.Cu"
			"In7.Cu" "In8.Cu" "In9.Cu" "In10.Cu" "In11.Cu" "In12.Cu" "In13.Cu" "In14.Cu"
			"In15.Cu" "In16.Cu"
		)
		(hatch none 0.5)
		(connect_pads
			(clearance 0)
		)
		(min_thickness 0.25)
		(keepout
			(tracks not_allowed)
			(vias allowed)
			(pads allowed)
			(copperpour not_allowed)
			(footprints allowed)
		)
		(placement
			(enabled no)
			(sheetname "")
		)
		(fill
			(thermal_gap 0.5)
			(thermal_bridge_width 0.5)
			(island_removal_mode 0)
		)
		(polygon
			(pts
				(arc
					(start 110.089696 -217.878406)
					(mid 109.431836 -217.878406)
					(end 110.089696 -217.878406)
				)
			)
		)
	)
	(zone
		(layers "F.Cu" "B.Cu" "In1.Cu" "In2.Cu" "In3.Cu" "In4.Cu" "In5.Cu" "In6.Cu"
			"In7.Cu" "In8.Cu" "In9.Cu" "In10.Cu" "In11.Cu" "In12.Cu" "In13.Cu" "In14.Cu"
			"In15.Cu" "In16.Cu"
		)
		(hatch none 0.5)
		(connect_pads
			(clearance 0)
		)
		(min_thickness 0.25)
		(keepout
			(tracks not_allowed)
			(vias allowed)
			(pads allowed)
			(copperpour not_allowed)
			(footprints allowed)
		)
		(placement
			(enabled no)
			(sheetname "")
		)
		(fill
			(thermal_gap 0.5)
			(thermal_bridge_width 0.5)
			(island_removal_mode 0)
		)
		(polygon
			(pts
				(arc
					(start 352.500946 -288.103056)
					(mid 351.843086 -288.103056)
					(end 352.500946 -288.103056)
				)
			)
		)
	)
	(zone
		(layers "F.Cu" "B.Cu" "In1.Cu" "In2.Cu" "In3.Cu" "In4.Cu" "In5.Cu" "In6.Cu"
			"In7.Cu" "In8.Cu" "In9.Cu" "In10.Cu" "In11.Cu" "In12.Cu" "In13.Cu" "In14.Cu"
			"In15.Cu" "In16.Cu"
		)
		(hatch none 0.5)
		(connect_pads
			(clearance 0)
		)
		(min_thickness 0.25)
		(keepout
			(tracks not_allowed)
			(vias allowed)
			(pads allowed)
			(copperpour not_allowed)
			(footprints allowed)
		)
		(placement
			(enabled no)
			(sheetname "")
		)
		(fill
			(thermal_gap 0.5)
			(thermal_bridge_width 0.5)
			(island_removal_mode 0)
		)
		(polygon
			(pts
				(arc
					(start 417.034218 -6.332474)
					(mid 416.653218 -6.713474)
					(end 417.034218 -7.094474)
				)
				(arc
					(start 417.897818 -7.094474)
					(mid 418.278818 -6.713474)
					(end 417.897818 -6.332474)
				)
			)
		)
	)
	(zone
		(layers "F.Cu" "B.Cu" "In1.Cu" "In2.Cu" "In3.Cu" "In4.Cu" "In5.Cu" "In6.Cu"
			"In7.Cu" "In8.Cu" "In9.Cu" "In10.Cu" "In11.Cu" "In12.Cu" "In13.Cu" "In14.Cu"
			"In15.Cu" "In16.Cu"
		)
		(hatch none 0.5)
		(connect_pads
			(clearance 0)
		)
		(min_thickness 0.25)
		(keepout
			(tracks not_allowed)
			(vias allowed)
			(pads allowed)
			(copperpour not_allowed)
			(footprints allowed)
		)
		(placement
			(enabled no)
			(sheetname "")
		)
		(fill
			(thermal_gap 0.5)
			(thermal_bridge_width 0.5)
			(island_removal_mode 0)
		)
		(polygon
			(pts
				(arc
					(start 361.788964 -217.878406)
					(mid 361.131104 -217.878406)
					(end 361.788964 -217.878406)
				)
			)
		)
	)
	(zone
		(layers "F.Cu" "B.Cu" "In1.Cu" "In2.Cu" "In3.Cu" "In4.Cu" "In5.Cu" "In6.Cu"
			"In7.Cu" "In8.Cu" "In9.Cu" "In10.Cu" "In11.Cu" "In12.Cu" "In13.Cu" "In14.Cu"
			"In15.Cu" "In16.Cu"
		)
		(hatch none 0.5)
		(connect_pads
			(clearance 0)
		)
		(min_thickness 0.25)
		(keepout
			(tracks not_allowed)
			(vias allowed)
			(pads allowed)
			(copperpour not_allowed)
			(footprints allowed)
		)
		(placement
			(enabled no)
			(sheetname "")
		)
		(fill
			(thermal_gap 0.5)
			(thermal_bridge_width 0.5)
			(island_removal_mode 0)
		)
		(polygon
			(pts
				(arc
					(start 228.93782 -246.756936)
					(mid 228.55682 -246.375936)
					(end 228.17582 -246.756936)
				)
				(arc
					(start 228.17582 -247.620536)
					(mid 228.55682 -248.001536)
					(end 228.93782 -247.620536)
				)
			)
		)
	)
	(zone
		(layers "F.Cu" "B.Cu" "In1.Cu" "In2.Cu" "In3.Cu" "In4.Cu" "In5.Cu" "In6.Cu"
			"In7.Cu" "In8.Cu" "In9.Cu" "In10.Cu" "In11.Cu" "In12.Cu" "In13.Cu" "In14.Cu"
			"In15.Cu" "In16.Cu"
		)
		(hatch none 0.5)
		(connect_pads
			(clearance 0)
		)
		(min_thickness 0.25)
		(keepout
			(tracks not_allowed)
			(vias allowed)
			(pads allowed)
			(copperpour not_allowed)
			(footprints allowed)
		)
		(placement
			(enabled no)
			(sheetname "")
		)
		(fill
			(thermal_gap 0.5)
			(thermal_bridge_width 0.5)
			(island_removal_mode 0)
		)
		(polygon
			(pts
				(arc
					(start 349.651828 -285.563056)
					(mid 349.632144 -285.610466)
					(end 349.625412 -285.661354)
				)
				(arc
					(start 349.625412 -285.661354)
					(mid 349.683068 -285.800548)
					(end 349.822262 -285.858204)
				)
				(arc
					(start 349.822262 -285.858204)
					(mid 349.920693 -285.831788)
					(end 349.992696 -285.759652)
				)
				(arc
					(start 350.462596 -284.945582)
					(mid 350.48228 -284.898172)
					(end 350.489012 -284.847284)
				)
				(arc
					(start 350.489012 -284.847284)
					(mid 350.431356 -284.70809)
					(end 350.292162 -284.650434)
				)
				(arc
					(start 350.292162 -284.650434)
					(mid 350.193731 -284.67685)
					(end 350.121728 -284.748986)
				)
			)
		)
	)
	(zone
		(layers "F.Cu" "B.Cu" "In1.Cu" "In2.Cu" "In3.Cu" "In4.Cu" "In5.Cu" "In6.Cu"
			"In7.Cu" "In8.Cu" "In9.Cu" "In10.Cu" "In11.Cu" "In12.Cu" "In13.Cu" "In14.Cu"
			"In15.Cu" "In16.Cu"
		)
		(hatch none 0.5)
		(connect_pads
			(clearance 0)
		)
		(min_thickness 0.25)
		(keepout
			(tracks not_allowed)
			(vias allowed)
			(pads allowed)
			(copperpour not_allowed)
			(footprints allowed)
		)
		(placement
			(enabled no)
			(sheetname "")
		)
		(fill
			(thermal_gap 0.5)
			(thermal_bridge_width 0.5)
			(island_removal_mode 0)
		)
		(polygon
			(pts
				(arc
					(start 107.662218 -278.336502)
					(mid 108.320078 -278.336502)
					(end 107.662218 -278.336502)
				)
			)
		)
	)
	(zone
		(layers "F.Cu" "B.Cu" "In1.Cu" "In2.Cu" "In3.Cu" "In4.Cu" "In5.Cu" "In6.Cu"
			"In7.Cu" "In8.Cu" "In9.Cu" "In10.Cu" "In11.Cu" "In12.Cu" "In13.Cu" "In14.Cu"
			"In15.Cu" "In16.Cu"
		)
		(hatch none 0.5)
		(connect_pads
			(clearance 0)
		)
		(min_thickness 0.25)
		(keepout
			(tracks not_allowed)
			(vias allowed)
			(pads allowed)
			(copperpour not_allowed)
			(footprints allowed)
		)
		(placement
			(enabled no)
			(sheetname "")
		)
		(fill
			(thermal_gap 0.5)
			(thermal_bridge_width 0.5)
			(island_removal_mode 0)
		)
		(polygon
			(pts
				(arc
					(start 346.28201 -223.575626)
					(mid 345.62415 -223.575626)
					(end 346.28201 -223.575626)
				)
			)
		)
	)
	(zone
		(layers "F.Cu" "B.Cu" "In1.Cu" "In2.Cu" "In3.Cu" "In4.Cu" "In5.Cu" "In6.Cu"
			"In7.Cu" "In8.Cu" "In9.Cu" "In10.Cu" "In11.Cu" "In12.Cu" "In13.Cu" "In14.Cu"
			"In15.Cu" "In16.Cu"
		)
		(hatch none 0.5)
		(connect_pads
			(clearance 0)
		)
		(min_thickness 0.25)
		(keepout
			(tracks not_allowed)
			(vias allowed)
			(pads allowed)
			(copperpour not_allowed)
			(footprints allowed)
		)
		(placement
			(enabled no)
			(sheetname "")
		)
		(fill
			(thermal_gap 0.5)
			(thermal_bridge_width 0.5)
			(island_removal_mode 0)
		)
		(polygon
			(pts
				(arc
					(start 348.657672 -170.613832)
					(mid 348.806462 -170.973042)
					(end 349.165672 -171.121832)
				)
				(arc
					(start 349.16618 -171.121832)
					(mid 349.297389 -171.104595)
					(end 349.419672 -171.054014)
				)
				(arc
					(start 350.343724 -170.52036)
					(mid 350.529657 -170.334424)
					(end 350.597724 -170.080432)
				)
				(arc
					(start 350.597724 -170.080432)
					(mid 350.448934 -169.721222)
					(end 350.089724 -169.572432)
				)
				(arc
					(start 350.089216 -169.572432)
					(mid 349.958007 -169.589669)
					(end 349.835724 -169.64025)
				)
				(arc
					(start 348.911672 -170.173904)
					(mid 348.725739 -170.35984)
					(end 348.657672 -170.613832)
				)
			)
		)
	)
	(zone
		(layers "F.Cu" "B.Cu" "In1.Cu" "In2.Cu" "In3.Cu" "In4.Cu" "In5.Cu" "In6.Cu"
			"In7.Cu" "In8.Cu" "In9.Cu" "In10.Cu" "In11.Cu" "In12.Cu" "In13.Cu" "In14.Cu"
			"In15.Cu" "In16.Cu"
		)
		(hatch none 0.5)
		(connect_pads
			(clearance 0)
		)
		(min_thickness 0.25)
		(keepout
			(tracks not_allowed)
			(vias allowed)
			(pads allowed)
			(copperpour not_allowed)
			(footprints allowed)
		)
		(placement
			(enabled no)
			(sheetname "")
		)
		(fill
			(thermal_gap 0.5)
			(thermal_bridge_width 0.5)
			(island_removal_mode 0)
		)
		(polygon
			(pts
				(arc
					(start 349.04553 -288.831274)
					(mid 348.977822 -288.759423)
					(end 348.882716 -288.732976)
				)
				(arc
					(start 348.882716 -288.732976)
					(mid 348.752502 -288.786912)
					(end 348.698566 -288.917126)
				)
				(arc
					(start 348.698566 -288.917126)
					(mid 348.704017 -288.961347)
					(end 348.719902 -289.002978)
				)
				(arc
					(start 349.189548 -289.892994)
					(mid 349.257256 -289.964845)
					(end 349.352362 -289.991292)
				)
				(arc
					(start 349.352362 -289.991292)
					(mid 349.482576 -289.937356)
					(end 349.536512 -289.807142)
				)
				(arc
					(start 349.536512 -289.807142)
					(mid 349.531061 -289.762921)
					(end 349.515176 -289.72129)
				)
			)
		)
	)
	(zone
		(layers "F.Cu" "B.Cu" "In1.Cu" "In2.Cu" "In3.Cu" "In4.Cu" "In5.Cu" "In6.Cu"
			"In7.Cu" "In8.Cu" "In9.Cu" "In10.Cu" "In11.Cu" "In12.Cu" "In13.Cu" "In14.Cu"
			"In15.Cu" "In16.Cu"
		)
		(hatch none 0.5)
		(connect_pads
			(clearance 0)
		)
		(min_thickness 0.25)
		(keepout
			(tracks not_allowed)
			(vias allowed)
			(pads allowed)
			(copperpour not_allowed)
			(footprints allowed)
		)
		(placement
			(enabled no)
			(sheetname "")
		)
		(fill
			(thermal_gap 0.5)
			(thermal_bridge_width 0.5)
			(island_removal_mode 0)
		)
		(polygon
			(pts
				(arc
					(start 350.511364 -217.878406)
					(mid 349.853504 -217.878406)
					(end 350.511364 -217.878406)
				)
			)
		)
	)
	(zone
		(layers "F.Cu" "B.Cu" "In1.Cu" "In2.Cu" "In3.Cu" "In4.Cu" "In5.Cu" "In6.Cu"
			"In7.Cu" "In8.Cu" "In9.Cu" "In10.Cu" "In11.Cu" "In12.Cu" "In13.Cu" "In14.Cu"
			"In15.Cu" "In16.Cu"
		)
		(hatch none 0.5)
		(connect_pads
			(clearance 0)
		)
		(min_thickness 0.25)
		(keepout
			(tracks not_allowed)
			(vias allowed)
			(pads allowed)
			(copperpour not_allowed)
			(footprints allowed)
		)
		(placement
			(enabled no)
			(sheetname "")
		)
		(fill
			(thermal_gap 0.5)
			(thermal_bridge_width 0.5)
			(island_removal_mode 0)
		)
		(polygon
			(pts
				(arc
					(start 376.35561 -220.319854)
					(mid 375.69775 -220.319854)
					(end 376.35561 -220.319854)
				)
			)
		)
	)
	(zone
		(layers "F.Cu" "B.Cu" "In1.Cu" "In2.Cu" "In3.Cu" "In4.Cu" "In5.Cu" "In6.Cu"
			"In7.Cu" "In8.Cu" "In9.Cu" "In10.Cu" "In11.Cu" "In12.Cu" "In13.Cu" "In14.Cu"
			"In15.Cu" "In16.Cu"
		)
		(hatch none 0.5)
		(connect_pads
			(clearance 0)
		)
		(min_thickness 0.25)
		(keepout
			(tracks not_allowed)
			(vias allowed)
			(pads allowed)
			(copperpour not_allowed)
			(footprints allowed)
		)
		(placement
			(enabled no)
			(sheetname "")
		)
		(fill
			(thermal_gap 0.5)
			(thermal_bridge_width 0.5)
			(island_removal_mode 0)
		)
		(polygon
			(pts
				(arc
					(start 365.548164 -217.878406)
					(mid 364.890304 -217.878406)
					(end 365.548164 -217.878406)
				)
			)
		)
	)
	(zone
		(layers "F.Cu" "B.Cu" "In1.Cu" "In2.Cu" "In3.Cu" "In4.Cu" "In5.Cu" "In6.Cu"
			"In7.Cu" "In8.Cu" "In9.Cu" "In10.Cu" "In11.Cu" "In12.Cu" "In13.Cu" "In14.Cu"
			"In15.Cu" "In16.Cu"
		)
		(hatch none 0.5)
		(connect_pads
			(clearance 0)
		)
		(min_thickness 0.25)
		(keepout
			(tracks not_allowed)
			(vias allowed)
			(pads allowed)
			(copperpour not_allowed)
			(footprints allowed)
		)
		(placement
			(enabled no)
			(sheetname "")
		)
		(fill
			(thermal_gap 0.5)
			(thermal_bridge_width 0.5)
			(island_removal_mode 0)
		)
		(polygon
			(pts
				(arc
					(start 314.516008 -406.62352)
					(mid 314.135008 -407.00452)
					(end 314.516008 -407.38552)
				)
				(arc
					(start 315.379608 -407.38552)
					(mid 315.760608 -407.00452)
					(end 315.379608 -406.62352)
				)
			)
		)
	)
	(zone
		(layers "F.Cu" "B.Cu" "In1.Cu" "In2.Cu" "In3.Cu" "In4.Cu" "In5.Cu" "In6.Cu"
			"In7.Cu" "In8.Cu" "In9.Cu" "In10.Cu" "In11.Cu" "In12.Cu" "In13.Cu" "In14.Cu"
			"In15.Cu" "In16.Cu"
		)
		(hatch none 0.5)
		(connect_pads
			(clearance 0)
		)
		(min_thickness 0.25)
		(keepout
			(tracks not_allowed)
			(vias allowed)
			(pads allowed)
			(copperpour not_allowed)
			(footprints allowed)
		)
		(placement
			(enabled no)
			(sheetname "")
		)
		(fill
			(thermal_gap 0.5)
			(thermal_bridge_width 0.5)
			(island_removal_mode 0)
		)
		(polygon
			(pts
				(arc
					(start 108.460794 -277.325582)
					(mid 108.263944 -277.522432)
					(end 108.460794 -277.719282)
				)
				(arc
					(start 109.400594 -277.719282)
					(mid 109.597444 -277.522432)
					(end 109.400594 -277.325582)
				)
			)
		)
	)
	(zone
		(layers "F.Cu" "B.Cu" "In1.Cu" "In2.Cu" "In3.Cu" "In4.Cu" "In5.Cu" "In6.Cu"
			"In7.Cu" "In8.Cu" "In9.Cu" "In10.Cu" "In11.Cu" "In12.Cu" "In13.Cu" "In14.Cu"
			"In15.Cu" "In16.Cu"
		)
		(hatch none 0.5)
		(connect_pads
			(clearance 0)
		)
		(min_thickness 0.25)
		(keepout
			(tracks not_allowed)
			(vias allowed)
			(pads allowed)
			(copperpour not_allowed)
			(footprints allowed)
		)
		(placement
			(enabled no)
			(sheetname "")
		)
		(fill
			(thermal_gap 0.5)
			(thermal_bridge_width 0.5)
			(island_removal_mode 0)
		)
		(polygon
			(pts
				(arc
					(start 97.353882 -285.563056)
					(mid 97.281893 -285.490897)
					(end 97.183448 -285.464504)
				)
				(arc
					(start 97.183448 -285.464504)
					(mid 97.044254 -285.52216)
					(end 96.986598 -285.661354)
				)
				(arc
					(start 96.986598 -285.661354)
					(mid 96.993355 -285.712235)
					(end 97.013014 -285.759652)
				)
				(arc
					(start 97.482914 -286.573722)
					(mid 97.554903 -286.645881)
					(end 97.653348 -286.672274)
				)
				(arc
					(start 97.653348 -286.672274)
					(mid 97.792542 -286.614618)
					(end 97.850198 -286.475424)
				)
				(arc
					(start 97.850198 -286.475424)
					(mid 97.843441 -286.424543)
					(end 97.823782 -286.377126)
				)
			)
		)
	)
	(zone
		(layers "F.Cu" "B.Cu" "In1.Cu" "In2.Cu" "In3.Cu" "In4.Cu" "In5.Cu" "In6.Cu"
			"In7.Cu" "In8.Cu" "In9.Cu" "In10.Cu" "In11.Cu" "In12.Cu" "In13.Cu" "In14.Cu"
			"In15.Cu" "In16.Cu"
		)
		(hatch none 0.5)
		(connect_pads
			(clearance 0)
		)
		(min_thickness 0.25)
		(keepout
			(tracks not_allowed)
			(vias allowed)
			(pads allowed)
			(copperpour not_allowed)
			(footprints allowed)
		)
		(placement
			(enabled no)
			(sheetname "")
		)
		(fill
			(thermal_gap 0.5)
			(thermal_bridge_width 0.5)
			(island_removal_mode 0)
		)
		(polygon
			(pts
				(arc
					(start 50.570892 -66.060828)
					(mid 45.062902 -60.552838)
					(end 39.554912 -66.060828)
				)
				(arc
					(start 39.554912 -74.760836)
					(mid 45.062902 -80.268826)
					(end 50.570892 -74.760836)
				)
			)
		)
	)
	(zone
		(layers "F.Cu" "B.Cu" "In1.Cu" "In2.Cu" "In3.Cu" "In4.Cu" "In5.Cu" "In6.Cu"
			"In7.Cu" "In8.Cu" "In9.Cu" "In10.Cu" "In11.Cu" "In12.Cu" "In13.Cu" "In14.Cu"
			"In15.Cu" "In16.Cu"
		)
		(hatch none 0.5)
		(connect_pads
			(clearance 0)
		)
		(min_thickness 0.25)
		(keepout
			(tracks not_allowed)
			(vias allowed)
			(pads allowed)
			(copperpour not_allowed)
			(footprints allowed)
		)
		(placement
			(enabled no)
			(sheetname "")
		)
		(fill
			(thermal_gap 0.5)
			(thermal_bridge_width 0.5)
			(island_removal_mode 0)
		)
		(polygon
			(pts
				(arc
					(start 374.006364 -221.133924)
					(mid 373.348504 -221.133924)
					(end 374.006364 -221.133924)
				)
			)
		)
	)
	(zone
		(layers "F.Cu" "B.Cu" "In1.Cu" "In2.Cu" "In3.Cu" "In4.Cu" "In5.Cu" "In6.Cu"
			"In7.Cu" "In8.Cu" "In9.Cu" "In10.Cu" "In11.Cu" "In12.Cu" "In13.Cu" "In14.Cu"
			"In15.Cu" "In16.Cu"
		)
		(hatch none 0.5)
		(connect_pads
			(clearance 0)
		)
		(min_thickness 0.25)
		(keepout
			(tracks not_allowed)
			(vias allowed)
			(pads allowed)
			(copperpour not_allowed)
			(footprints allowed)
		)
		(placement
			(enabled no)
			(sheetname "")
		)
		(fill
			(thermal_gap 0.5)
			(thermal_bridge_width 0.5)
			(island_removal_mode 0)
		)
		(polygon
			(pts
				(arc
					(start 342.834468 -217.780108)
					(mid 342.762479 -217.707949)
					(end 342.664034 -217.681556)
				)
				(arc
					(start 342.664034 -217.681556)
					(mid 342.52484 -217.739212)
					(end 342.467184 -217.878406)
				)
				(arc
					(start 342.467184 -217.878406)
					(mid 342.473941 -217.929287)
					(end 342.4936 -217.976704)
				)
				(arc
					(start 342.963246 -218.79052)
					(mid 343.035235 -218.862679)
					(end 343.13368 -218.889072)
				)
				(arc
					(start 343.13368 -218.889072)
					(mid 343.272874 -218.831416)
					(end 343.33053 -218.692222)
				)
				(arc
					(start 343.33053 -218.692222)
					(mid 343.323773 -218.641341)
					(end 343.304114 -218.593924)
				)
			)
		)
	)
	(zone
		(layers "F.Cu" "B.Cu" "In1.Cu" "In2.Cu" "In3.Cu" "In4.Cu" "In5.Cu" "In6.Cu"
			"In7.Cu" "In8.Cu" "In9.Cu" "In10.Cu" "In11.Cu" "In12.Cu" "In13.Cu" "In14.Cu"
			"In15.Cu" "In16.Cu"
		)
		(hatch none 0.5)
		(connect_pads
			(clearance 0)
		)
		(min_thickness 0.25)
		(keepout
			(tracks not_allowed)
			(vias allowed)
			(pads allowed)
			(copperpour not_allowed)
			(footprints allowed)
		)
		(placement
			(enabled no)
			(sheetname "")
		)
		(fill
			(thermal_gap 0.5)
			(thermal_bridge_width 0.5)
			(island_removal_mode 0)
		)
		(polygon
			(pts
				(arc
					(start 110.841282 -220.319854)
					(mid 111.499142 -220.319854)
					(end 110.841282 -220.319854)
				)
			)
		)
	)
	(zone
		(layers "F.Cu" "B.Cu" "In1.Cu" "In2.Cu" "In3.Cu" "In4.Cu" "In5.Cu" "In6.Cu"
			"In7.Cu" "In8.Cu" "In9.Cu" "In10.Cu" "In11.Cu" "In12.Cu" "In13.Cu" "In14.Cu"
			"In15.Cu" "In16.Cu"
		)
		(hatch none 0.5)
		(connect_pads
			(clearance 0)
		)
		(min_thickness 0.25)
		(keepout
			(tracks not_allowed)
			(vias allowed)
			(pads allowed)
			(copperpour not_allowed)
			(footprints allowed)
		)
		(placement
			(enabled no)
			(sheetname "")
		)
		(fill
			(thermal_gap 0.5)
			(thermal_bridge_width 0.5)
			(island_removal_mode 0)
		)
		(polygon
			(pts
				(arc
					(start 395.92885 -400.477228)
					(mid 395.54785 -400.858228)
					(end 395.92885 -401.239228)
				)
				(arc
					(start 396.79245 -401.239228)
					(mid 397.17345 -400.858228)
					(end 396.79245 -400.477228)
				)
			)
		)
	)
	(zone
		(layers "F.Cu" "B.Cu" "In1.Cu" "In2.Cu" "In3.Cu" "In4.Cu" "In5.Cu" "In6.Cu"
			"In7.Cu" "In8.Cu" "In9.Cu" "In10.Cu" "In11.Cu" "In12.Cu" "In13.Cu" "In14.Cu"
			"In15.Cu" "In16.Cu"
		)
		(hatch none 0.5)
		(connect_pads
			(clearance 0)
		)
		(min_thickness 0.25)
		(keepout
			(tracks not_allowed)
			(vias allowed)
			(pads allowed)
			(copperpour not_allowed)
			(footprints allowed)
		)
		(placement
			(enabled no)
			(sheetname "")
		)
		(fill
			(thermal_gap 0.5)
			(thermal_bridge_width 0.5)
			(island_removal_mode 0)
		)
		(polygon
			(pts
				(arc
					(start 119.017542 -217.064336)
					(mid 118.359682 -217.064336)
					(end 119.017542 -217.064336)
				)
			)
		)
	)
	(zone
		(layers "F.Cu" "B.Cu" "In1.Cu" "In2.Cu" "In3.Cu" "In4.Cu" "In5.Cu" "In6.Cu"
			"In7.Cu" "In8.Cu" "In9.Cu" "In10.Cu" "In11.Cu" "In12.Cu" "In13.Cu" "In14.Cu"
			"In15.Cu" "In16.Cu"
		)
		(hatch none 0.5)
		(connect_pads
			(clearance 0)
		)
		(min_thickness 0.25)
		(keepout
			(tracks not_allowed)
			(vias allowed)
			(pads allowed)
			(copperpour not_allowed)
			(footprints allowed)
		)
		(placement
			(enabled no)
			(sheetname "")
		)
		(fill
			(thermal_gap 0.5)
			(thermal_bridge_width 0.5)
			(island_removal_mode 0)
		)
		(polygon
			(pts
				(arc
					(start 358.810814 -214.524336)
					(mid 358.541923 -214.452399)
					(end 358.469946 -214.721186)
				)
				(arc
					(start 358.939846 -215.535256)
					(mid 359.208832 -215.607138)
					(end 359.280714 -215.338152)
				)
			)
		)
	)
	(zone
		(layers "F.Cu" "B.Cu" "In1.Cu" "In2.Cu" "In3.Cu" "In4.Cu" "In5.Cu" "In6.Cu"
			"In7.Cu" "In8.Cu" "In9.Cu" "In10.Cu" "In11.Cu" "In12.Cu" "In13.Cu" "In14.Cu"
			"In15.Cu" "In16.Cu"
		)
		(hatch none 0.5)
		(connect_pads
			(clearance 0)
		)
		(min_thickness 0.25)
		(keepout
			(tracks not_allowed)
			(vias allowed)
			(pads allowed)
			(copperpour not_allowed)
			(footprints allowed)
		)
		(placement
			(enabled no)
			(sheetname "")
		)
		(fill
			(thermal_gap 0.5)
			(thermal_bridge_width 0.5)
			(island_removal_mode 0)
		)
		(polygon
			(pts
				(arc
					(start 409.599384 -18.744438)
					(mid 409.218384 -19.125438)
					(end 409.599384 -19.506438)
				)
				(arc
					(start 410.462984 -19.506438)
					(mid 410.843984 -19.125438)
					(end 410.462984 -18.744438)
				)
			)
		)
	)
	(zone
		(layers "F.Cu" "B.Cu" "In1.Cu" "In2.Cu" "In3.Cu" "In4.Cu" "In5.Cu" "In6.Cu"
			"In7.Cu" "In8.Cu" "In9.Cu" "In10.Cu" "In11.Cu" "In12.Cu" "In13.Cu" "In14.Cu"
			"In15.Cu" "In16.Cu"
		)
		(hatch none 0.5)
		(connect_pads
			(clearance 0)
		)
		(min_thickness 0.25)
		(keepout
			(tracks not_allowed)
			(vias allowed)
			(pads allowed)
			(copperpour not_allowed)
			(footprints allowed)
		)
		(placement
			(enabled no)
			(sheetname "")
		)
		(fill
			(thermal_gap 0.5)
			(thermal_bridge_width 0.5)
			(island_removal_mode 0)
		)
		(polygon
			(pts
				(arc
					(start 357.041196 -273.354546)
					(mid 356.969207 -273.282387)
					(end 356.870762 -273.255994)
				)
				(arc
					(start 356.870762 -273.255994)
					(mid 356.731568 -273.31365)
					(end 356.673912 -273.452844)
				)
				(arc
					(start 356.673912 -273.452844)
					(mid 356.680669 -273.503725)
					(end 356.700328 -273.551142)
				)
				(arc
					(start 357.170228 -274.365212)
					(mid 357.242217 -274.437371)
					(end 357.340662 -274.463764)
				)
				(arc
					(start 357.340662 -274.463764)
					(mid 357.479856 -274.406108)
					(end 357.537512 -274.266914)
				)
				(arc
					(start 357.537512 -274.266914)
					(mid 357.530755 -274.216033)
					(end 357.511096 -274.168616)
				)
			)
		)
	)
	(zone
		(layers "F.Cu" "B.Cu" "In1.Cu" "In2.Cu" "In3.Cu" "In4.Cu" "In5.Cu" "In6.Cu"
			"In7.Cu" "In8.Cu" "In9.Cu" "In10.Cu" "In11.Cu" "In12.Cu" "In13.Cu" "In14.Cu"
			"In15.Cu" "In16.Cu"
		)
		(hatch none 0.5)
		(connect_pads
			(clearance 0)
		)
		(min_thickness 0.25)
		(keepout
			(tracks not_allowed)
			(vias allowed)
			(pads allowed)
			(copperpour not_allowed)
			(footprints allowed)
		)
		(placement
			(enabled no)
			(sheetname "")
		)
		(fill
			(thermal_gap 0.5)
			(thermal_bridge_width 0.5)
			(island_removal_mode 0)
		)
		(polygon
			(pts
				(arc
					(start 54.98973 -17.23136)
					(mid 54.60873 -17.61236)
					(end 54.98973 -17.99336)
				)
				(arc
					(start 55.85333 -17.99336)
					(mid 56.23433 -17.61236)
					(end 55.85333 -17.23136)
				)
			)
		)
	)
	(zone
		(layers "F.Cu" "B.Cu" "In1.Cu" "In2.Cu" "In3.Cu" "In4.Cu" "In5.Cu" "In6.Cu"
			"In7.Cu" "In8.Cu" "In9.Cu" "In10.Cu" "In11.Cu" "In12.Cu" "In13.Cu" "In14.Cu"
			"In15.Cu" "In16.Cu"
		)
		(hatch none 0.5)
		(connect_pads
			(clearance 0)
		)
		(min_thickness 0.25)
		(keepout
			(tracks not_allowed)
			(vias allowed)
			(pads allowed)
			(copperpour not_allowed)
			(footprints allowed)
		)
		(placement
			(enabled no)
			(sheetname "")
		)
		(fill
			(thermal_gap 0.5)
			(thermal_bridge_width 0.5)
			(island_removal_mode 0)
		)
		(polygon
			(pts
				(arc
					(start 125.236478 -284.847538)
					(mid 124.578618 -284.847538)
					(end 125.236478 -284.847538)
				)
			)
		)
	)
	(zone
		(layers "F.Cu" "B.Cu" "In1.Cu" "In2.Cu" "In3.Cu" "In4.Cu" "In5.Cu" "In6.Cu"
			"In7.Cu" "In8.Cu" "In9.Cu" "In10.Cu" "In11.Cu" "In12.Cu" "In13.Cu" "In14.Cu"
			"In15.Cu" "In16.Cu"
		)
		(hatch none 0.5)
		(connect_pads
			(clearance 0)
		)
		(min_thickness 0.25)
		(keepout
			(tracks not_allowed)
			(vias allowed)
			(pads allowed)
			(copperpour not_allowed)
			(footprints allowed)
		)
		(placement
			(enabled no)
			(sheetname "")
		)
		(fill
			(thermal_gap 0.5)
			(thermal_bridge_width 0.5)
			(island_removal_mode 0)
		)
		(polygon
			(pts
				(arc
					(start 94.424246 -223.67367)
					(mid 94.44393 -223.62626)
					(end 94.450662 -223.575372)
				)
				(arc
					(start 94.450662 -223.575372)
					(mid 94.393006 -223.436178)
					(end 94.253812 -223.378522)
				)
				(arc
					(start 94.253812 -223.378522)
					(mid 94.155381 -223.404938)
					(end 94.083378 -223.477074)
				)
				(arc
					(start 93.613732 -224.291144)
					(mid 93.594048 -224.338554)
					(end 93.587316 -224.389442)
				)
				(arc
					(start 93.587316 -224.389442)
					(mid 93.644972 -224.528636)
					(end 93.784166 -224.586292)
				)
				(arc
					(start 93.784166 -224.586292)
					(mid 93.882597 -224.559876)
					(end 93.9546 -224.48774)
				)
			)
		)
	)
	(zone
		(layers "F.Cu" "B.Cu" "In1.Cu" "In2.Cu" "In3.Cu" "In4.Cu" "In5.Cu" "In6.Cu"
			"In7.Cu" "In8.Cu" "In9.Cu" "In10.Cu" "In11.Cu" "In12.Cu" "In13.Cu" "In14.Cu"
			"In15.Cu" "In16.Cu"
		)
		(hatch none 0.5)
		(connect_pads
			(clearance 0)
		)
		(min_thickness 0.25)
		(keepout
			(tracks not_allowed)
			(vias allowed)
			(pads allowed)
			(copperpour not_allowed)
			(footprints allowed)
		)
		(placement
			(enabled no)
			(sheetname "")
		)
		(fill
			(thermal_gap 0.5)
			(thermal_bridge_width 0.5)
			(island_removal_mode 0)
		)
		(polygon
			(pts
				(arc
					(start 344.013282 -288.818828)
					(mid 343.993598 -288.866238)
					(end 343.986866 -288.917126)
				)
				(arc
					(start 343.986866 -288.917126)
					(mid 344.044522 -289.05632)
					(end 344.183716 -289.113976)
				)
				(arc
					(start 344.183716 -289.113976)
					(mid 344.282147 -289.08756)
					(end 344.35415 -289.015424)
				)
				(arc
					(start 344.82405 -288.201354)
					(mid 344.843734 -288.153944)
					(end 344.850466 -288.103056)
				)
				(arc
					(start 344.850466 -288.103056)
					(mid 344.79281 -287.963862)
					(end 344.653616 -287.906206)
				)
				(arc
					(start 344.653616 -287.906206)
					(mid 344.555185 -287.932622)
					(end 344.483182 -288.004758)
				)
			)
		)
	)
	(zone
		(layers "F.Cu" "B.Cu" "In1.Cu" "In2.Cu" "In3.Cu" "In4.Cu" "In5.Cu" "In6.Cu"
			"In7.Cu" "In8.Cu" "In9.Cu" "In10.Cu" "In11.Cu" "In12.Cu" "In13.Cu" "In14.Cu"
			"In15.Cu" "In16.Cu"
		)
		(hatch none 0.5)
		(connect_pads
			(clearance 0)
		)
		(min_thickness 0.25)
		(keepout
			(tracks not_allowed)
			(vias allowed)
			(pads allowed)
			(copperpour not_allowed)
			(footprints allowed)
		)
		(placement
			(enabled no)
			(sheetname "")
		)
		(fill
			(thermal_gap 0.5)
			(thermal_bridge_width 0.5)
			(island_removal_mode 0)
		)
		(polygon
			(pts
				(arc
					(start 152.133554 -406.62352)
					(mid 151.752554 -407.00452)
					(end 152.133554 -407.38552)
				)
				(arc
					(start 152.997154 -407.38552)
					(mid 153.378154 -407.00452)
					(end 152.997154 -406.62352)
				)
			)
		)
	)
	(zone
		(layers "F.Cu" "B.Cu" "In1.Cu" "In2.Cu" "In3.Cu" "In4.Cu" "In5.Cu" "In6.Cu"
			"In7.Cu" "In8.Cu" "In9.Cu" "In10.Cu" "In11.Cu" "In12.Cu" "In13.Cu" "In14.Cu"
			"In15.Cu" "In16.Cu"
		)
		(hatch none 0.5)
		(connect_pads
			(clearance 0)
		)
		(min_thickness 0.25)
		(keepout
			(tracks not_allowed)
			(vias allowed)
			(pads allowed)
			(copperpour not_allowed)
			(footprints allowed)
		)
		(placement
			(enabled no)
			(sheetname "")
		)
		(fill
			(thermal_gap 0.5)
			(thermal_bridge_width 0.5)
			(island_removal_mode 0)
		)
		(polygon
			(pts
				(arc
					(start 93.0148 -221.035626)
					(mid 92.942811 -220.963467)
					(end 92.844366 -220.937074)
				)
				(arc
					(start 92.844366 -220.937074)
					(mid 92.705172 -220.99473)
					(end 92.647516 -221.133924)
				)
				(arc
					(start 92.647516 -221.133924)
					(mid 92.654273 -221.184805)
					(end 92.673932 -221.232222)
				)
				(arc
					(start 93.143578 -222.046038)
					(mid 93.215567 -222.118197)
					(end 93.314012 -222.14459)
				)
				(arc
					(start 93.314012 -222.14459)
					(mid 93.453206 -222.086934)
					(end 93.510862 -221.94774)
				)
				(arc
					(start 93.510862 -221.94774)
					(mid 93.504105 -221.896859)
					(end 93.484446 -221.849442)
				)
			)
		)
	)
	(zone
		(layers "F.Cu" "B.Cu" "In1.Cu" "In2.Cu" "In3.Cu" "In4.Cu" "In5.Cu" "In6.Cu"
			"In7.Cu" "In8.Cu" "In9.Cu" "In10.Cu" "In11.Cu" "In12.Cu" "In13.Cu" "In14.Cu"
			"In15.Cu" "In16.Cu"
		)
		(hatch none 0.5)
		(connect_pads
			(clearance 0)
		)
		(min_thickness 0.25)
		(keepout
			(tracks not_allowed)
			(vias allowed)
			(pads allowed)
			(copperpour not_allowed)
			(footprints allowed)
		)
		(placement
			(enabled no)
			(sheetname "")
		)
		(fill
			(thermal_gap 0.5)
			(thermal_bridge_width 0.5)
			(island_removal_mode 0)
		)
		(polygon
			(pts
				(arc
					(start 371.65661 -221.94774)
					(mid 370.99875 -221.94774)
					(end 371.65661 -221.94774)
				)
			)
		)
	)
	(zone
		(layers "F.Cu" "B.Cu" "In1.Cu" "In2.Cu" "In3.Cu" "In4.Cu" "In5.Cu" "In6.Cu"
			"In7.Cu" "In8.Cu" "In9.Cu" "In10.Cu" "In11.Cu" "In12.Cu" "In13.Cu" "In14.Cu"
			"In15.Cu" "In16.Cu"
		)
		(hatch none 0.5)
		(connect_pads
			(clearance 0)
		)
		(min_thickness 0.25)
		(keepout
			(tracks not_allowed)
			(vias allowed)
			(pads allowed)
			(copperpour not_allowed)
			(footprints allowed)
		)
		(placement
			(enabled no)
			(sheetname "")
		)
		(fill
			(thermal_gap 0.5)
			(thermal_bridge_width 0.5)
			(island_removal_mode 0)
		)
		(polygon
			(pts
				(arc
					(start 375.83237 -409.649168)
					(mid 375.45137 -410.030168)
					(end 375.83237 -410.411168)
				)
				(arc
					(start 376.69597 -410.411168)
					(mid 377.07697 -410.030168)
					(end 376.69597 -409.649168)
				)
			)
		)
	)
	(zone
		(layers "F.Cu" "B.Cu" "In1.Cu" "In2.Cu" "In3.Cu" "In4.Cu" "In5.Cu" "In6.Cu"
			"In7.Cu" "In8.Cu" "In9.Cu" "In10.Cu" "In11.Cu" "In12.Cu" "In13.Cu" "In14.Cu"
			"In15.Cu" "In16.Cu"
		)
		(hatch none 0.5)
		(connect_pads
			(clearance 0)
		)
		(min_thickness 0.25)
		(keepout
			(tracks not_allowed)
			(vias allowed)
			(pads allowed)
			(copperpour not_allowed)
			(footprints allowed)
		)
		(placement
			(enabled no)
			(sheetname "")
		)
		(fill
			(thermal_gap 0.5)
			(thermal_bridge_width 0.5)
			(island_removal_mode 0)
		)
		(polygon
			(pts
				(arc
					(start 352.031046 -288.917126)
					(mid 351.373186 -288.917126)
					(end 352.031046 -288.917126)
				)
			)
		)
	)
	(zone
		(layers "F.Cu" "B.Cu" "In1.Cu" "In2.Cu" "In3.Cu" "In4.Cu" "In5.Cu" "In6.Cu"
			"In7.Cu" "In8.Cu" "In9.Cu" "In10.Cu" "In11.Cu" "In12.Cu" "In13.Cu" "In14.Cu"
			"In15.Cu" "In16.Cu"
		)
		(hatch none 0.5)
		(connect_pads
			(clearance 0)
		)
		(min_thickness 0.25)
		(keepout
			(tracks not_allowed)
			(vias allowed)
			(pads allowed)
			(copperpour not_allowed)
			(footprints allowed)
		)
		(placement
			(enabled no)
			(sheetname "")
		)
		(fill
			(thermal_gap 0.5)
			(thermal_bridge_width 0.5)
			(island_removal_mode 0)
		)
		(polygon
			(pts
				(arc
					(start 96.073214 -288.818828)
					(mid 96.05353 -288.866238)
					(end 96.046798 -288.917126)
				)
				(arc
					(start 96.046798 -288.917126)
					(mid 96.104454 -289.05632)
					(end 96.243648 -289.113976)
				)
				(arc
					(start 96.243648 -289.113976)
					(mid 96.342079 -289.08756)
					(end 96.414082 -289.015424)
				)
				(arc
					(start 96.883982 -288.201354)
					(mid 96.903666 -288.153944)
					(end 96.910398 -288.103056)
				)
				(arc
					(start 96.910398 -288.103056)
					(mid 96.852742 -287.963862)
					(end 96.713548 -287.906206)
				)
				(arc
					(start 96.713548 -287.906206)
					(mid 96.615117 -287.932622)
					(end 96.543114 -288.004758)
				)
			)
		)
	)
	(zone
		(layers "F.Cu" "B.Cu" "In1.Cu" "In2.Cu" "In3.Cu" "In4.Cu" "In5.Cu" "In6.Cu"
			"In7.Cu" "In8.Cu" "In9.Cu" "In10.Cu" "In11.Cu" "In12.Cu" "In13.Cu" "In14.Cu"
			"In15.Cu" "In16.Cu"
		)
		(hatch none 0.5)
		(connect_pads
			(clearance 0)
		)
		(min_thickness 0.25)
		(keepout
			(tracks not_allowed)
			(vias allowed)
			(pads allowed)
			(copperpour not_allowed)
			(footprints allowed)
		)
		(placement
			(enabled no)
			(sheetname "")
		)
		(fill
			(thermal_gap 0.5)
			(thermal_bridge_width 0.5)
			(island_removal_mode 0)
		)
		(polygon
			(pts
				(arc
					(start 354.270564 -221.133924)
					(mid 353.612704 -221.133924)
					(end 354.270564 -221.133924)
				)
			)
		)
	)
	(zone
		(layers "F.Cu" "B.Cu" "In1.Cu" "In2.Cu" "In3.Cu" "In4.Cu" "In5.Cu" "In6.Cu"
			"In7.Cu" "In8.Cu" "In9.Cu" "In10.Cu" "In11.Cu" "In12.Cu" "In13.Cu" "In14.Cu"
			"In15.Cu" "In16.Cu"
		)
		(hatch none 0.5)
		(connect_pads
			(clearance 0)
		)
		(min_thickness 0.25)
		(keepout
			(tracks not_allowed)
			(vias allowed)
			(pads allowed)
			(copperpour not_allowed)
			(footprints allowed)
		)
		(placement
			(enabled no)
			(sheetname "")
		)
		(fill
			(thermal_gap 0.5)
			(thermal_bridge_width 0.5)
			(island_removal_mode 0)
		)
		(polygon
			(pts
				(arc
					(start 131.705096 -221.133924)
					(mid 131.047236 -221.133924)
					(end 131.705096 -221.133924)
				)
			)
		)
	)
	(zone
		(layers "F.Cu" "B.Cu" "In1.Cu" "In2.Cu" "In3.Cu" "In4.Cu" "In5.Cu" "In6.Cu"
			"In7.Cu" "In8.Cu" "In9.Cu" "In10.Cu" "In11.Cu" "In12.Cu" "In13.Cu" "In14.Cu"
			"In15.Cu" "In16.Cu"
		)
		(hatch none 0.5)
		(connect_pads
			(clearance 0)
		)
		(min_thickness 0.25)
		(keepout
			(tracks not_allowed)
			(vias allowed)
			(pads allowed)
			(copperpour not_allowed)
			(footprints allowed)
		)
		(placement
			(enabled no)
			(sheetname "")
		)
		(fill
			(thermal_gap 0.5)
			(thermal_bridge_width 0.5)
			(island_removal_mode 0)
		)
		(polygon
			(pts
				(arc
					(start 355.210364 -224.389442)
					(mid 354.552504 -224.389442)
					(end 355.210364 -224.389442)
				)
			)
		)
	)
	(zone
		(layers "F.Cu" "B.Cu" "In1.Cu" "In2.Cu" "In3.Cu" "In4.Cu" "In5.Cu" "In6.Cu"
			"In7.Cu" "In8.Cu" "In9.Cu" "In10.Cu" "In11.Cu" "In12.Cu" "In13.Cu" "In14.Cu"
			"In15.Cu" "In16.Cu"
		)
		(hatch none 0.5)
		(connect_pads
			(clearance 0)
		)
		(min_thickness 0.25)
		(keepout
			(tracks not_allowed)
			(vias allowed)
			(pads allowed)
			(copperpour not_allowed)
			(footprints allowed)
		)
		(placement
			(enabled no)
			(sheetname "")
		)
		(fill
			(thermal_gap 0.5)
			(thermal_bridge_width 0.5)
			(island_removal_mode 0)
		)
		(polygon
			(pts
				(arc
					(start 394.21181 -409.649168)
					(mid 393.83081 -410.030168)
					(end 394.21181 -410.411168)
				)
				(arc
					(start 395.07541 -410.411168)
					(mid 395.45641 -410.030168)
					(end 395.07541 -409.649168)
				)
			)
		)
	)
	(zone
		(layers "F.Cu" "B.Cu" "In1.Cu" "In2.Cu" "In3.Cu" "In4.Cu" "In5.Cu" "In6.Cu"
			"In7.Cu" "In8.Cu" "In9.Cu" "In10.Cu" "In11.Cu" "In12.Cu" "In13.Cu" "In14.Cu"
			"In15.Cu" "In16.Cu"
		)
		(hatch none 0.5)
		(connect_pads
			(clearance 0)
		)
		(min_thickness 0.25)
		(keepout
			(tracks not_allowed)
			(vias allowed)
			(pads allowed)
			(copperpour not_allowed)
			(footprints allowed)
		)
		(placement
			(enabled no)
			(sheetname "")
		)
		(fill
			(thermal_gap 0.5)
			(thermal_bridge_width 0.5)
			(island_removal_mode 0)
		)
		(polygon
			(pts
				(arc
					(start 328.04354 -74.617072)
					(mid 327.279 -74.617072)
					(end 328.04354 -74.617072)
				)
			)
		)
	)
	(zone
		(layers "F.Cu" "B.Cu" "In1.Cu" "In2.Cu" "In3.Cu" "In4.Cu" "In5.Cu" "In6.Cu"
			"In7.Cu" "In8.Cu" "In9.Cu" "In10.Cu" "In11.Cu" "In12.Cu" "In13.Cu" "In14.Cu"
			"In15.Cu" "In16.Cu"
		)
		(hatch none 0.5)
		(connect_pads
			(clearance 0)
		)
		(min_thickness 0.25)
		(keepout
			(tracks not_allowed)
			(vias allowed)
			(pads allowed)
			(copperpour not_allowed)
			(footprints allowed)
		)
		(placement
			(enabled no)
			(sheetname "")
		)
		(fill
			(thermal_gap 0.5)
			(thermal_bridge_width 0.5)
			(island_removal_mode 0)
		)
		(polygon
			(pts
				(arc
					(start 125.125988 -214.622634)
					(mid 124.468128 -214.622634)
					(end 125.125988 -214.622634)
				)
			)
		)
	)
	(zone
		(layers "F.Cu" "B.Cu" "In1.Cu" "In2.Cu" "In3.Cu" "In4.Cu" "In5.Cu" "In6.Cu"
			"In7.Cu" "In8.Cu" "In9.Cu" "In10.Cu" "In11.Cu" "In12.Cu" "In13.Cu" "In14.Cu"
			"In15.Cu" "In16.Cu"
		)
		(hatch none 0.5)
		(connect_pads
			(clearance 0)
		)
		(min_thickness 0.25)
		(keepout
			(tracks not_allowed)
			(vias allowed)
			(pads allowed)
			(copperpour not_allowed)
			(footprints allowed)
		)
		(placement
			(enabled no)
			(sheetname "")
		)
		(fill
			(thermal_gap 0.5)
			(thermal_bridge_width 0.5)
			(island_removal_mode 0)
		)
		(polygon
			(pts
				(arc
					(start 342.992456 -214.622634)
					(mid 342.334596 -214.622634)
					(end 342.992456 -214.622634)
				)
			)
		)
	)
	(zone
		(layers "F.Cu" "B.Cu" "In1.Cu" "In2.Cu" "In3.Cu" "In4.Cu" "In5.Cu" "In6.Cu"
			"In7.Cu" "In8.Cu" "In9.Cu" "In10.Cu" "In11.Cu" "In12.Cu" "In13.Cu" "In14.Cu"
			"In15.Cu" "In16.Cu"
		)
		(hatch none 0.5)
		(connect_pads
			(clearance 0)
		)
		(min_thickness 0.25)
		(keepout
			(tracks not_allowed)
			(vias allowed)
			(pads allowed)
			(copperpour not_allowed)
			(footprints allowed)
		)
		(placement
			(enabled no)
			(sheetname "")
		)
		(fill
			(thermal_gap 0.5)
			(thermal_bridge_width 0.5)
			(island_removal_mode 0)
		)
		(polygon
			(pts
				(arc
					(start 344.40241 -223.575626)
					(mid 343.74455 -223.575626)
					(end 344.40241 -223.575626)
				)
			)
		)
	)
	(zone
		(layers "F.Cu" "B.Cu" "In1.Cu" "In2.Cu" "In3.Cu" "In4.Cu" "In5.Cu" "In6.Cu"
			"In7.Cu" "In8.Cu" "In9.Cu" "In10.Cu" "In11.Cu" "In12.Cu" "In13.Cu" "In14.Cu"
			"In15.Cu" "In16.Cu"
		)
		(hatch none 0.5)
		(connect_pads
			(clearance 0)
		)
		(min_thickness 0.25)
		(keepout
			(tracks not_allowed)
			(vias allowed)
			(pads allowed)
			(copperpour not_allowed)
			(footprints allowed)
		)
		(placement
			(enabled no)
			(sheetname "")
		)
		(fill
			(thermal_gap 0.5)
			(thermal_bridge_width 0.5)
			(island_removal_mode 0)
		)
		(polygon
			(pts
				(arc
					(start 380.584964 -217.878406)
					(mid 379.927104 -217.878406)
					(end 380.584964 -217.878406)
				)
			)
		)
	)
	(zone
		(layers "F.Cu" "B.Cu" "In1.Cu" "In2.Cu" "In3.Cu" "In4.Cu" "In5.Cu" "In6.Cu"
			"In7.Cu" "In8.Cu" "In9.Cu" "In10.Cu" "In11.Cu" "In12.Cu" "In13.Cu" "In14.Cu"
			"In15.Cu" "In16.Cu"
		)
		(hatch none 0.5)
		(connect_pads
			(clearance 0)
		)
		(min_thickness 0.25)
		(keepout
			(tracks not_allowed)
			(vias allowed)
			(pads allowed)
			(copperpour not_allowed)
			(footprints allowed)
		)
		(placement
			(enabled no)
			(sheetname "")
		)
		(fill
			(thermal_gap 0.5)
			(thermal_bridge_width 0.5)
			(island_removal_mode 0)
		)
		(polygon
			(pts
				(arc
					(start 93.587062 -288.831274)
					(mid 93.519354 -288.759423)
					(end 93.424248 -288.732976)
				)
				(arc
					(start 93.424248 -288.732976)
					(mid 93.294034 -288.786912)
					(end 93.240098 -288.917126)
				)
				(arc
					(start 93.240098 -288.917126)
					(mid 93.245549 -288.961347)
					(end 93.261434 -289.002978)
				)
				(arc
					(start 93.73108 -289.892994)
					(mid 93.798788 -289.964845)
					(end 93.893894 -289.991292)
				)
				(arc
					(start 93.893894 -289.991292)
					(mid 94.024108 -289.937356)
					(end 94.078044 -289.807142)
				)
				(arc
					(start 94.078044 -289.807142)
					(mid 94.072593 -289.762921)
					(end 94.056708 -289.72129)
				)
			)
		)
	)
	(zone
		(layers "F.Cu" "B.Cu" "In1.Cu" "In2.Cu" "In3.Cu" "In4.Cu" "In5.Cu" "In6.Cu"
			"In7.Cu" "In8.Cu" "In9.Cu" "In10.Cu" "In11.Cu" "In12.Cu" "In13.Cu" "In14.Cu"
			"In15.Cu" "In16.Cu"
		)
		(hatch none 0.5)
		(connect_pads
			(clearance 0)
		)
		(min_thickness 0.25)
		(keepout
			(tracks not_allowed)
			(vias allowed)
			(pads allowed)
			(copperpour not_allowed)
			(footprints allowed)
		)
		(placement
			(enabled no)
			(sheetname "")
		)
		(fill
			(thermal_gap 0.5)
			(thermal_bridge_width 0.5)
			(island_removal_mode 0)
		)
		(polygon
			(pts
				(arc
					(start 353.910392 -280.778204)
					(mid 353.252532 -280.778204)
					(end 353.910392 -280.778204)
				)
			)
		)
	)
	(zone
		(layers "F.Cu" "B.Cu" "In1.Cu" "In2.Cu" "In3.Cu" "In4.Cu" "In5.Cu" "In6.Cu"
			"In7.Cu" "In8.Cu" "In9.Cu" "In10.Cu" "In11.Cu" "In12.Cu" "In13.Cu" "In14.Cu"
			"In15.Cu" "In16.Cu"
		)
		(hatch none 0.5)
		(connect_pads
			(clearance 0)
		)
		(min_thickness 0.25)
		(keepout
			(tracks not_allowed)
			(vias allowed)
			(pads allowed)
			(copperpour not_allowed)
			(footprints allowed)
		)
		(placement
			(enabled no)
			(sheetname "")
		)
		(fill
			(thermal_gap 0.5)
			(thermal_bridge_width 0.5)
			(island_removal_mode 0)
		)
		(polygon
			(pts
				(arc
					(start 73.831958 -409.649168)
					(mid 73.450958 -410.030168)
					(end 73.831958 -410.411168)
				)
				(arc
					(start 74.695558 -410.411168)
					(mid 75.076558 -410.030168)
					(end 74.695558 -409.649168)
				)
			)
		)
	)
	(zone
		(layers "F.Cu" "B.Cu" "In1.Cu" "In2.Cu" "In3.Cu" "In4.Cu" "In5.Cu" "In6.Cu"
			"In7.Cu" "In8.Cu" "In9.Cu" "In10.Cu" "In11.Cu" "In12.Cu" "In13.Cu" "In14.Cu"
			"In15.Cu" "In16.Cu"
		)
		(hatch none 0.5)
		(connect_pads
			(clearance 0)
		)
		(min_thickness 0.25)
		(keepout
			(tracks not_allowed)
			(vias allowed)
			(pads allowed)
			(copperpour not_allowed)
			(footprints allowed)
		)
		(placement
			(enabled no)
			(sheetname "")
		)
		(fill
			(thermal_gap 0.5)
			(thermal_bridge_width 0.5)
			(island_removal_mode 0)
		)
		(polygon
			(pts
				(arc
					(start 346.123514 -223.67367)
					(mid 346.143198 -223.62626)
					(end 346.14993 -223.575372)
				)
				(arc
					(start 346.14993 -223.575372)
					(mid 346.092274 -223.436178)
					(end 345.95308 -223.378522)
				)
				(arc
					(start 345.95308 -223.378522)
					(mid 345.854649 -223.404938)
					(end 345.782646 -223.477074)
				)
				(arc
					(start 345.313 -224.291144)
					(mid 345.293316 -224.338554)
					(end 345.286584 -224.389442)
				)
				(arc
					(start 345.286584 -224.389442)
					(mid 345.34424 -224.528636)
					(end 345.483434 -224.586292)
				)
				(arc
					(start 345.483434 -224.586292)
					(mid 345.581865 -224.559876)
					(end 345.653868 -224.48774)
				)
			)
		)
	)
	(zone
		(layers "F.Cu" "B.Cu" "In1.Cu" "In2.Cu" "In3.Cu" "In4.Cu" "In5.Cu" "In6.Cu"
			"In7.Cu" "In8.Cu" "In9.Cu" "In10.Cu" "In11.Cu" "In12.Cu" "In13.Cu" "In14.Cu"
			"In15.Cu" "In16.Cu"
		)
		(hatch none 0.5)
		(connect_pads
			(clearance 0)
		)
		(min_thickness 0.25)
		(keepout
			(tracks not_allowed)
			(vias allowed)
			(pads allowed)
			(copperpour not_allowed)
			(footprints allowed)
		)
		(placement
			(enabled no)
			(sheetname "")
		)
		(fill
			(thermal_gap 0.5)
			(thermal_bridge_width 0.5)
			(island_removal_mode 0)
		)
		(polygon
			(pts
				(arc
					(start 18.851372 -399.035016)
					(mid 18.470372 -399.416016)
					(end 18.851372 -399.797016)
				)
				(arc
					(start 19.714972 -399.797016)
					(mid 20.095972 -399.416016)
					(end 19.714972 -399.035016)
				)
			)
		)
	)
	(zone
		(layers "F.Cu" "B.Cu" "In1.Cu" "In2.Cu" "In3.Cu" "In4.Cu" "In5.Cu" "In6.Cu"
			"In7.Cu" "In8.Cu" "In9.Cu" "In10.Cu" "In11.Cu" "In12.Cu" "In13.Cu" "In14.Cu"
			"In15.Cu" "In16.Cu"
		)
		(hatch none 0.5)
		(connect_pads
			(clearance 0)
		)
		(min_thickness 0.25)
		(keepout
			(tracks not_allowed)
			(vias allowed)
			(pads allowed)
			(copperpour not_allowed)
			(footprints allowed)
		)
		(placement
			(enabled no)
			(sheetname "")
		)
		(fill
			(thermal_gap 0.5)
			(thermal_bridge_width 0.5)
			(island_removal_mode 0)
		)
		(polygon
			(pts
				(arc
					(start 411.24505 -400.477228)
					(mid 410.86405 -400.858228)
					(end 411.24505 -401.239228)
				)
				(arc
					(start 412.10865 -401.239228)
					(mid 412.48965 -400.858228)
					(end 412.10865 -400.477228)
				)
			)
		)
	)
	(zone
		(layers "F.Cu" "B.Cu" "In1.Cu" "In2.Cu" "In3.Cu" "In4.Cu" "In5.Cu" "In6.Cu"
			"In7.Cu" "In8.Cu" "In9.Cu" "In10.Cu" "In11.Cu" "In12.Cu" "In13.Cu" "In14.Cu"
			"In15.Cu" "In16.Cu"
		)
		(hatch none 0.5)
		(connect_pads
			(clearance 0)
		)
		(min_thickness 0.25)
		(keepout
			(tracks not_allowed)
			(vias allowed)
			(pads allowed)
			(copperpour not_allowed)
			(footprints allowed)
		)
		(placement
			(enabled no)
			(sheetname "")
		)
		(fill
			(thermal_gap 0.5)
			(thermal_bridge_width 0.5)
			(island_removal_mode 0)
		)
		(polygon
			(pts
				(arc
					(start 340.954868 -217.780108)
					(mid 340.882879 -217.707949)
					(end 340.784434 -217.681556)
				)
				(arc
					(start 340.784434 -217.681556)
					(mid 340.64524 -217.739212)
					(end 340.587584 -217.878406)
				)
				(arc
					(start 340.587584 -217.878406)
					(mid 340.594341 -217.929287)
					(end 340.614 -217.976704)
				)
				(arc
					(start 341.083646 -218.79052)
					(mid 341.155635 -218.862679)
					(end 341.25408 -218.889072)
				)
				(arc
					(start 341.25408 -218.889072)
					(mid 341.393274 -218.831416)
					(end 341.45093 -218.692222)
				)
				(arc
					(start 341.45093 -218.692222)
					(mid 341.444173 -218.641341)
					(end 341.424514 -218.593924)
				)
			)
		)
	)
	(zone
		(layers "F.Cu" "B.Cu" "In1.Cu" "In2.Cu" "In3.Cu" "In4.Cu" "In5.Cu" "In6.Cu"
			"In7.Cu" "In8.Cu" "In9.Cu" "In10.Cu" "In11.Cu" "In12.Cu" "In13.Cu" "In14.Cu"
			"In15.Cu" "In16.Cu"
		)
		(hatch none 0.5)
		(connect_pads
			(clearance 0)
		)
		(min_thickness 0.25)
		(keepout
			(tracks not_allowed)
			(vias allowed)
			(pads allowed)
			(copperpour not_allowed)
			(footprints allowed)
		)
		(placement
			(enabled no)
			(sheetname "")
		)
		(fill
			(thermal_gap 0.5)
			(thermal_bridge_width 0.5)
			(island_removal_mode 0)
		)
		(polygon
			(pts
				(arc
					(start 327.352914 5.031994)
					(mid 327.733914 4.650994)
					(end 328.114914 5.031994)
				)
				(arc
					(start 328.114914 5.895594)
					(mid 327.733914 6.276594)
					(end 327.352914 5.895594)
				)
			)
		)
	)
	(zone
		(layers "F.Cu" "B.Cu" "In1.Cu" "In2.Cu" "In3.Cu" "In4.Cu" "In5.Cu" "In6.Cu"
			"In7.Cu" "In8.Cu" "In9.Cu" "In10.Cu" "In11.Cu" "In12.Cu" "In13.Cu" "In14.Cu"
			"In15.Cu" "In16.Cu"
		)
		(hatch none 0.5)
		(connect_pads
			(clearance 0)
		)
		(min_thickness 0.25)
		(keepout
			(tracks not_allowed)
			(vias allowed)
			(pads allowed)
			(copperpour not_allowed)
			(footprints allowed)
		)
		(placement
			(enabled no)
			(sheetname "")
		)
		(fill
			(thermal_gap 0.5)
			(thermal_bridge_width 0.5)
			(island_removal_mode 0)
		)
		(polygon
			(pts
				(arc
					(start 359.281222 -220.22181)
					(mid 359.209233 -220.149651)
					(end 359.110788 -220.123258)
				)
				(arc
					(start 359.110788 -220.123258)
					(mid 358.971594 -220.180914)
					(end 358.913938 -220.320108)
				)
				(arc
					(start 358.913938 -220.320108)
					(mid 358.920695 -220.370989)
					(end 358.940354 -220.418406)
				)
				(arc
					(start 359.41 -221.232222)
					(mid 359.481989 -221.304381)
					(end 359.580434 -221.330774)
				)
				(arc
					(start 359.580434 -221.330774)
					(mid 359.719628 -221.273118)
					(end 359.777284 -221.133924)
				)
				(arc
					(start 359.777284 -221.133924)
					(mid 359.770527 -221.083043)
					(end 359.750868 -221.035626)
				)
			)
		)
	)
	(zone
		(layers "F.Cu" "B.Cu" "In1.Cu" "In2.Cu" "In3.Cu" "In4.Cu" "In5.Cu" "In6.Cu"
			"In7.Cu" "In8.Cu" "In9.Cu" "In10.Cu" "In11.Cu" "In12.Cu" "In13.Cu" "In14.Cu"
			"In15.Cu" "In16.Cu"
		)
		(hatch none 0.5)
		(connect_pads
			(clearance 0)
		)
		(min_thickness 0.25)
		(keepout
			(tracks not_allowed)
			(vias allowed)
			(pads allowed)
			(copperpour not_allowed)
			(footprints allowed)
		)
		(placement
			(enabled no)
			(sheetname "")
		)
		(fill
			(thermal_gap 0.5)
			(thermal_bridge_width 0.5)
			(island_removal_mode 0)
		)
		(polygon
			(pts
				(arc
					(start 318.95796 -68.449952)
					(mid 314.842144 -68.449952)
					(end 318.95796 -68.449952)
				)
			)
		)
	)
	(zone
		(layers "F.Cu" "B.Cu" "In1.Cu" "In2.Cu" "In3.Cu" "In4.Cu" "In5.Cu" "In6.Cu"
			"In7.Cu" "In8.Cu" "In9.Cu" "In10.Cu" "In11.Cu" "In12.Cu" "In13.Cu" "In14.Cu"
			"In15.Cu" "In16.Cu"
		)
		(hatch none 0.5)
		(connect_pads
			(clearance 0)
		)
		(min_thickness 0.25)
		(keepout
			(tracks not_allowed)
			(vias allowed)
			(pads allowed)
			(copperpour not_allowed)
			(footprints allowed)
		)
		(placement
			(enabled no)
			(sheetname "")
		)
		(fill
			(thermal_gap 0.5)
			(thermal_bridge_width 0.5)
			(island_removal_mode 0)
		)
		(polygon
			(pts
				(arc
					(start 339.233256 -214.622634)
					(mid 338.575396 -214.622634)
					(end 339.233256 -214.622634)
				)
			)
		)
	)
	(zone
		(layers "F.Cu" "B.Cu" "In1.Cu" "In2.Cu" "In3.Cu" "In4.Cu" "In5.Cu" "In6.Cu"
			"In7.Cu" "In8.Cu" "In9.Cu" "In10.Cu" "In11.Cu" "In12.Cu" "In13.Cu" "In14.Cu"
			"In15.Cu" "In16.Cu"
		)
		(hatch none 0.5)
		(connect_pads
			(clearance 0)
		)
		(min_thickness 0.25)
		(keepout
			(tracks not_allowed)
			(vias allowed)
			(pads allowed)
			(copperpour not_allowed)
			(footprints allowed)
		)
		(placement
			(enabled no)
			(sheetname "")
		)
		(fill
			(thermal_gap 0.5)
			(thermal_bridge_width 0.5)
			(island_removal_mode 0)
		)
		(polygon
			(pts
				(arc
					(start 366.32896 -217.97645)
					(mid 366.348644 -217.92904)
					(end 366.355376 -217.878152)
				)
				(arc
					(start 366.355376 -217.878152)
					(mid 366.29772 -217.738958)
					(end 366.158526 -217.681302)
				)
				(arc
					(start 366.158526 -217.681302)
					(mid 366.060095 -217.707718)
					(end 365.988092 -217.779854)
				)
				(arc
					(start 365.518446 -218.593924)
					(mid 365.498762 -218.641334)
					(end 365.49203 -218.692222)
				)
				(arc
					(start 365.49203 -218.692222)
					(mid 365.549686 -218.831416)
					(end 365.68888 -218.889072)
				)
				(arc
					(start 365.68888 -218.889072)
					(mid 365.787311 -218.862656)
					(end 365.859314 -218.79052)
				)
			)
		)
	)
	(zone
		(layers "F.Cu" "B.Cu" "In1.Cu" "In2.Cu" "In3.Cu" "In4.Cu" "In5.Cu" "In6.Cu"
			"In7.Cu" "In8.Cu" "In9.Cu" "In10.Cu" "In11.Cu" "In12.Cu" "In13.Cu" "In14.Cu"
			"In15.Cu" "In16.Cu"
		)
		(hatch none 0.5)
		(connect_pads
			(clearance 0)
		)
		(min_thickness 0.25)
		(keepout
			(tracks not_allowed)
			(vias allowed)
			(pads allowed)
			(copperpour not_allowed)
			(footprints allowed)
		)
		(placement
			(enabled no)
			(sheetname "")
		)
		(fill
			(thermal_gap 0.5)
			(thermal_bridge_width 0.5)
			(island_removal_mode 0)
		)
		(polygon
			(pts
				(arc
					(start 352.030792 -277.522432)
					(mid 351.372932 -277.522432)
					(end 352.030792 -277.522432)
				)
			)
		)
	)
	(zone
		(layers "F.Cu" "B.Cu" "In1.Cu" "In2.Cu" "In3.Cu" "In4.Cu" "In5.Cu" "In6.Cu"
			"In7.Cu" "In8.Cu" "In9.Cu" "In10.Cu" "In11.Cu" "In12.Cu" "In13.Cu" "In14.Cu"
			"In15.Cu" "In16.Cu"
		)
		(hatch none 0.5)
		(connect_pads
			(clearance 0)
		)
		(min_thickness 0.25)
		(keepout
			(tracks not_allowed)
			(vias allowed)
			(pads allowed)
			(copperpour not_allowed)
			(footprints allowed)
		)
		(placement
			(enabled no)
			(sheetname "")
		)
		(fill
			(thermal_gap 0.5)
			(thermal_bridge_width 0.5)
			(island_removal_mode 0)
		)
		(polygon
			(pts
				(arc
					(start 351.92081 -223.575626)
					(mid 351.26295 -223.575626)
					(end 351.92081 -223.575626)
				)
			)
		)
	)
	(zone
		(layers "F.Cu" "B.Cu" "In1.Cu" "In2.Cu" "In3.Cu" "In4.Cu" "In5.Cu" "In6.Cu"
			"In7.Cu" "In8.Cu" "In9.Cu" "In10.Cu" "In11.Cu" "In12.Cu" "In13.Cu" "In14.Cu"
			"In15.Cu" "In16.Cu"
		)
		(hatch none 0.5)
		(connect_pads
			(clearance 0)
		)
		(min_thickness 0.25)
		(keepout
			(tracks not_allowed)
			(vias allowed)
			(pads allowed)
			(copperpour not_allowed)
			(footprints allowed)
		)
		(placement
			(enabled no)
			(sheetname "")
		)
		(fill
			(thermal_gap 0.5)
			(thermal_bridge_width 0.5)
			(island_removal_mode 0)
		)
		(polygon
			(pts
				(arc
					(start 372.236746 -286.475424)
					(mid 371.578886 -286.475424)
					(end 372.236746 -286.475424)
				)
			)
		)
	)
	(zone
		(layers "F.Cu" "B.Cu" "In1.Cu" "In2.Cu" "In3.Cu" "In4.Cu" "In5.Cu" "In6.Cu"
			"In7.Cu" "In8.Cu" "In9.Cu" "In10.Cu" "In11.Cu" "In12.Cu" "In13.Cu" "In14.Cu"
			"In15.Cu" "In16.Cu"
		)
		(hatch none 0.5)
		(connect_pads
			(clearance 0)
		)
		(min_thickness 0.25)
		(keepout
			(tracks not_allowed)
			(vias allowed)
			(pads allowed)
			(copperpour not_allowed)
			(footprints allowed)
		)
		(placement
			(enabled no)
			(sheetname "")
		)
		(fill
			(thermal_gap 0.5)
			(thermal_bridge_width 0.5)
			(island_removal_mode 0)
		)
		(polygon
			(pts
				(arc
					(start 340.424008 2.491994)
					(mid 340.805008 2.110994)
					(end 341.186008 2.491994)
				)
				(arc
					(start 341.186008 3.355594)
					(mid 340.805008 3.736594)
					(end 340.424008 3.355594)
				)
			)
		)
	)
	(zone
		(layers "F.Cu" "B.Cu" "In1.Cu" "In2.Cu" "In3.Cu" "In4.Cu" "In5.Cu" "In6.Cu"
			"In7.Cu" "In8.Cu" "In9.Cu" "In10.Cu" "In11.Cu" "In12.Cu" "In13.Cu" "In14.Cu"
			"In15.Cu" "In16.Cu"
		)
		(hatch none 0.5)
		(connect_pads
			(clearance 0)
		)
		(min_thickness 0.25)
		(keepout
			(tracks not_allowed)
			(vias allowed)
			(pads allowed)
			(copperpour not_allowed)
			(footprints allowed)
		)
		(placement
			(enabled no)
			(sheetname "")
		)
		(fill
			(thermal_gap 0.5)
			(thermal_bridge_width 0.5)
			(island_removal_mode 0)
		)
		(polygon
			(pts
				(arc
					(start 95.274638 -406.62352)
					(mid 94.893638 -407.00452)
					(end 95.274638 -407.38552)
				)
				(arc
					(start 96.138238 -407.38552)
					(mid 96.519238 -407.00452)
					(end 96.138238 -406.62352)
				)
			)
		)
	)
	(zone
		(layers "F.Cu" "B.Cu" "In1.Cu" "In2.Cu" "In3.Cu" "In4.Cu" "In5.Cu" "In6.Cu"
			"In7.Cu" "In8.Cu" "In9.Cu" "In10.Cu" "In11.Cu" "In12.Cu" "In13.Cu" "In14.Cu"
			"In15.Cu" "In16.Cu"
		)
		(hatch none 0.5)
		(connect_pads
			(clearance 0)
		)
		(min_thickness 0.25)
		(keepout
			(tracks not_allowed)
			(vias allowed)
			(pads allowed)
			(copperpour not_allowed)
			(footprints allowed)
		)
		(placement
			(enabled no)
			(sheetname "")
		)
		(fill
			(thermal_gap 0.5)
			(thermal_bridge_width 0.5)
			(island_removal_mode 0)
		)
		(polygon
			(pts
				(arc
					(start 102.571296 -221.133924)
					(mid 101.913436 -221.133924)
					(end 102.571296 -221.133924)
				)
			)
		)
	)
	(zone
		(layers "F.Cu" "B.Cu" "In1.Cu" "In2.Cu" "In3.Cu" "In4.Cu" "In5.Cu" "In6.Cu"
			"In7.Cu" "In8.Cu" "In9.Cu" "In10.Cu" "In11.Cu" "In12.Cu" "In13.Cu" "In14.Cu"
			"In15.Cu" "In16.Cu"
		)
		(hatch none 0.5)
		(connect_pads
			(clearance 0)
		)
		(min_thickness 0.25)
		(keepout
			(tracks not_allowed)
			(vias allowed)
			(pads allowed)
			(copperpour not_allowed)
			(footprints allowed)
		)
		(placement
			(enabled no)
			(sheetname "")
		)
		(fill
			(thermal_gap 0.5)
			(thermal_bridge_width 0.5)
			(island_removal_mode 0)
		)
		(polygon
			(pts
				(arc
					(start 360.33202 -55.503572)
					(mid 359.95102 -55.884572)
					(end 360.33202 -56.265572)
				)
				(arc
					(start 361.19562 -56.265572)
					(mid 361.57662 -55.884572)
					(end 361.19562 -55.503572)
				)
			)
		)
	)
	(zone
		(layers "F.Cu" "B.Cu" "In1.Cu" "In2.Cu" "In3.Cu" "In4.Cu" "In5.Cu" "In6.Cu"
			"In7.Cu" "In8.Cu" "In9.Cu" "In10.Cu" "In11.Cu" "In12.Cu" "In13.Cu" "In14.Cu"
			"In15.Cu" "In16.Cu"
		)
		(hatch none 0.5)
		(connect_pads
			(clearance 0)
		)
		(min_thickness 0.25)
		(keepout
			(tracks not_allowed)
			(vias allowed)
			(pads allowed)
			(copperpour not_allowed)
			(footprints allowed)
		)
		(placement
			(enabled no)
			(sheetname "")
		)
		(fill
			(thermal_gap 0.5)
			(thermal_bridge_width 0.5)
			(island_removal_mode 0)
		)
		(polygon
			(pts
				(arc
					(start 356.150164 -221.133924)
					(mid 355.492304 -221.133924)
					(end 356.150164 -221.133924)
				)
			)
		)
	)
	(zone
		(layers "F.Cu" "B.Cu" "In1.Cu" "In2.Cu" "In3.Cu" "In4.Cu" "In5.Cu" "In6.Cu"
			"In7.Cu" "In8.Cu" "In9.Cu" "In10.Cu" "In11.Cu" "In12.Cu" "In13.Cu" "In14.Cu"
			"In15.Cu" "In16.Cu"
		)
		(hatch none 0.5)
		(connect_pads
			(clearance 0)
		)
		(min_thickness 0.25)
		(keepout
			(tracks not_allowed)
			(vias allowed)
			(pads allowed)
			(copperpour not_allowed)
			(footprints allowed)
		)
		(placement
			(enabled no)
			(sheetname "")
		)
		(fill
			(thermal_gap 0.5)
			(thermal_bridge_width 0.5)
			(island_removal_mode 0)
		)
		(polygon
			(pts
				(arc
					(start 350.151192 -285.661354)
					(mid 349.493332 -285.661354)
					(end 350.151192 -285.661354)
				)
			)
		)
	)
	(zone
		(layers "F.Cu" "B.Cu" "In1.Cu" "In2.Cu" "In3.Cu" "In4.Cu" "In5.Cu" "In6.Cu"
			"In7.Cu" "In8.Cu" "In9.Cu" "In10.Cu" "In11.Cu" "In12.Cu" "In13.Cu" "In14.Cu"
			"In15.Cu" "In16.Cu"
		)
		(hatch none 0.5)
		(connect_pads
			(clearance 0)
		)
		(min_thickness 0.25)
		(keepout
			(tracks not_allowed)
			(vias allowed)
			(pads allowed)
			(copperpour not_allowed)
			(footprints allowed)
		)
		(placement
			(enabled no)
			(sheetname "")
		)
		(fill
			(thermal_gap 0.5)
			(thermal_bridge_width 0.5)
			(island_removal_mode 0)
		)
		(polygon
			(pts
				(arc
					(start 367.89741 -225.203258)
					(mid 367.23955 -225.203258)
					(end 367.89741 -225.203258)
				)
			)
		)
	)
	(zone
		(layers "F.Cu" "B.Cu" "In1.Cu" "In2.Cu" "In3.Cu" "In4.Cu" "In5.Cu" "In6.Cu"
			"In7.Cu" "In8.Cu" "In9.Cu" "In10.Cu" "In11.Cu" "In12.Cu" "In13.Cu" "In14.Cu"
			"In15.Cu" "In16.Cu"
		)
		(hatch none 0.5)
		(connect_pads
			(clearance 0)
		)
		(min_thickness 0.25)
		(keepout
			(tracks not_allowed)
			(vias allowed)
			(pads allowed)
			(copperpour not_allowed)
			(footprints allowed)
		)
		(placement
			(enabled no)
			(sheetname "")
		)
		(fill
			(thermal_gap 0.5)
			(thermal_bridge_width 0.5)
			(island_removal_mode 0)
		)
		(polygon
			(pts
				(arc
					(start 381.524764 -217.878406)
					(mid 380.866904 -217.878406)
					(end 381.524764 -217.878406)
				)
			)
		)
	)
	(zone
		(layers "F.Cu" "B.Cu" "In1.Cu" "In2.Cu" "In3.Cu" "In4.Cu" "In5.Cu" "In6.Cu"
			"In7.Cu" "In8.Cu" "In9.Cu" "In10.Cu" "In11.Cu" "In12.Cu" "In13.Cu" "In14.Cu"
			"In15.Cu" "In16.Cu"
		)
		(hatch none 0.5)
		(connect_pads
			(clearance 0)
		)
		(min_thickness 0.25)
		(keepout
			(tracks not_allowed)
			(vias allowed)
			(pads allowed)
			(copperpour not_allowed)
			(footprints allowed)
		)
		(placement
			(enabled no)
			(sheetname "")
		)
		(fill
			(thermal_gap 0.5)
			(thermal_bridge_width 0.5)
			(island_removal_mode 0)
		)
		(polygon
			(pts
				(arc
					(start 347.22181 -215.436704)
					(mid 346.56395 -215.436704)
					(end 347.22181 -215.436704)
				)
			)
		)
	)
	(zone
		(layers "F.Cu" "B.Cu" "In1.Cu" "In2.Cu" "In3.Cu" "In4.Cu" "In5.Cu" "In6.Cu"
			"In7.Cu" "In8.Cu" "In9.Cu" "In10.Cu" "In11.Cu" "In12.Cu" "In13.Cu" "In14.Cu"
			"In15.Cu" "In16.Cu"
		)
		(hatch none 0.5)
		(connect_pads
			(clearance 0)
		)
		(min_thickness 0.25)
		(keepout
			(tracks not_allowed)
			(vias allowed)
			(pads allowed)
			(copperpour not_allowed)
			(footprints allowed)
		)
		(placement
			(enabled no)
			(sheetname "")
		)
		(fill
			(thermal_gap 0.5)
			(thermal_bridge_width 0.5)
			(island_removal_mode 0)
		)
		(polygon
			(pts
				(arc
					(start 368.947446 -288.917126)
					(mid 368.289586 -288.917126)
					(end 368.947446 -288.917126)
				)
			)
		)
	)
	(zone
		(layers "F.Cu" "B.Cu" "In1.Cu" "In2.Cu" "In3.Cu" "In4.Cu" "In5.Cu" "In6.Cu"
			"In7.Cu" "In8.Cu" "In9.Cu" "In10.Cu" "In11.Cu" "In12.Cu" "In13.Cu" "In14.Cu"
			"In15.Cu" "In16.Cu"
		)
		(hatch none 0.5)
		(connect_pads
			(clearance 0)
		)
		(min_thickness 0.25)
		(keepout
			(tracks not_allowed)
			(vias allowed)
			(pads allowed)
			(copperpour not_allowed)
			(footprints allowed)
		)
		(placement
			(enabled no)
			(sheetname "")
		)
		(fill
			(thermal_gap 0.5)
			(thermal_bridge_width 0.5)
			(island_removal_mode 0)
		)
		(polygon
			(pts
				(arc
					(start 95.444564 -289.807142)
					(mid 96.102424 -289.807142)
					(end 95.444564 -289.807142)
				)
			)
		)
	)
	(zone
		(layers "F.Cu" "B.Cu" "In1.Cu" "In2.Cu" "In3.Cu" "In4.Cu" "In5.Cu" "In6.Cu"
			"In7.Cu" "In8.Cu" "In9.Cu" "In10.Cu" "In11.Cu" "In12.Cu" "In13.Cu" "In14.Cu"
			"In15.Cu" "In16.Cu"
		)
		(hatch none 0.5)
		(connect_pads
			(clearance 0)
		)
		(min_thickness 0.25)
		(keepout
			(tracks not_allowed)
			(vias allowed)
			(pads allowed)
			(copperpour not_allowed)
			(footprints allowed)
		)
		(placement
			(enabled no)
			(sheetname "")
		)
		(fill
			(thermal_gap 0.5)
			(thermal_bridge_width 0.5)
			(island_removal_mode 0)
		)
		(polygon
			(pts
				(arc
					(start 352.030792 -279.150318)
					(mid 351.372932 -279.150318)
					(end 352.030792 -279.150318)
				)
			)
		)
	)
	(zone
		(layers "F.Cu" "B.Cu" "In1.Cu" "In2.Cu" "In3.Cu" "In4.Cu" "In5.Cu" "In6.Cu"
			"In7.Cu" "In8.Cu" "In9.Cu" "In10.Cu" "In11.Cu" "In12.Cu" "In13.Cu" "In14.Cu"
			"In15.Cu" "In16.Cu"
		)
		(hatch none 0.5)
		(connect_pads
			(clearance 0)
		)
		(min_thickness 0.25)
		(keepout
			(tracks not_allowed)
			(vias allowed)
			(pads allowed)
			(copperpour not_allowed)
			(footprints allowed)
		)
		(placement
			(enabled no)
			(sheetname "")
		)
		(fill
			(thermal_gap 0.5)
			(thermal_bridge_width 0.5)
			(island_removal_mode 0)
		)
		(polygon
			(pts
				(arc
					(start 348.211648 -406.62352)
					(mid 347.830648 -407.00452)
					(end 348.211648 -407.38552)
				)
				(arc
					(start 349.075248 -407.38552)
					(mid 349.456248 -407.00452)
					(end 349.075248 -406.62352)
				)
			)
		)
	)
	(zone
		(layers "F.Cu" "B.Cu" "In1.Cu" "In2.Cu" "In3.Cu" "In4.Cu" "In5.Cu" "In6.Cu"
			"In7.Cu" "In8.Cu" "In9.Cu" "In10.Cu" "In11.Cu" "In12.Cu" "In13.Cu" "In14.Cu"
			"In15.Cu" "In16.Cu"
		)
		(hatch none 0.5)
		(connect_pads
			(clearance 0)
		)
		(min_thickness 0.25)
		(keepout
			(tracks not_allowed)
			(vias allowed)
			(pads allowed)
			(copperpour not_allowed)
			(footprints allowed)
		)
		(placement
			(enabled no)
			(sheetname "")
		)
		(fill
			(thermal_gap 0.5)
			(thermal_bridge_width 0.5)
			(island_removal_mode 0)
		)
		(polygon
			(pts
				(arc
					(start 144.660874 -403.502876)
					(mid 144.279874 -403.883876)
					(end 144.660874 -404.264876)
				)
				(arc
					(start 145.524474 -404.264876)
					(mid 145.905474 -403.883876)
					(end 145.524474 -403.502876)
				)
			)
		)
	)
	(zone
		(layers "F.Cu" "B.Cu" "In1.Cu" "In2.Cu" "In3.Cu" "In4.Cu" "In5.Cu" "In6.Cu"
			"In7.Cu" "In8.Cu" "In9.Cu" "In10.Cu" "In11.Cu" "In12.Cu" "In13.Cu" "In14.Cu"
			"In15.Cu" "In16.Cu"
		)
		(hatch none 0.5)
		(connect_pads
			(clearance 0)
		)
		(min_thickness 0.25)
		(keepout
			(tracks not_allowed)
			(vias allowed)
			(pads allowed)
			(copperpour not_allowed)
			(footprints allowed)
		)
		(placement
			(enabled no)
			(sheetname "")
		)
		(fill
			(thermal_gap 0.5)
			(thermal_bridge_width 0.5)
			(island_removal_mode 0)
		)
		(polygon
			(pts
				(arc
					(start 100.221796 -213.732618)
					(mid 99.563936 -213.732618)
					(end 100.221796 -213.732618)
				)
			)
		)
	)
	(zone
		(layers "F.Cu" "B.Cu" "In1.Cu" "In2.Cu" "In3.Cu" "In4.Cu" "In5.Cu" "In6.Cu"
			"In7.Cu" "In8.Cu" "In9.Cu" "In10.Cu" "In11.Cu" "In12.Cu" "In13.Cu" "In14.Cu"
			"In15.Cu" "In16.Cu"
		)
		(hatch none 0.5)
		(connect_pads
			(clearance 0)
		)
		(min_thickness 0.25)
		(keepout
			(tracks not_allowed)
			(vias allowed)
			(pads allowed)
			(copperpour not_allowed)
			(footprints allowed)
		)
		(placement
			(enabled no)
			(sheetname "")
		)
		(fill
			(thermal_gap 0.5)
			(thermal_bridge_width 0.5)
			(island_removal_mode 0)
		)
		(polygon
			(pts
				(arc
					(start 96.384618 -283.219906)
					(mid 97.042478 -283.219906)
					(end 96.384618 -283.219906)
				)
			)
		)
	)
	(zone
		(layers "F.Cu" "B.Cu" "In1.Cu" "In2.Cu" "In3.Cu" "In4.Cu" "In5.Cu" "In6.Cu"
			"In7.Cu" "In8.Cu" "In9.Cu" "In10.Cu" "In11.Cu" "In12.Cu" "In13.Cu" "In14.Cu"
			"In15.Cu" "In16.Cu"
		)
		(hatch none 0.5)
		(connect_pads
			(clearance 0)
		)
		(min_thickness 0.25)
		(keepout
			(tracks not_allowed)
			(vias allowed)
			(pads allowed)
			(copperpour not_allowed)
			(footprints allowed)
		)
		(placement
			(enabled no)
			(sheetname "")
		)
		(fill
			(thermal_gap 0.5)
			(thermal_bridge_width 0.5)
			(island_removal_mode 0)
		)
		(polygon
			(pts
				(arc
					(start 124.497846 -223.67367)
					(mid 124.51753 -223.62626)
					(end 124.524262 -223.575372)
				)
				(arc
					(start 124.524262 -223.575372)
					(mid 124.466606 -223.436178)
					(end 124.327412 -223.378522)
				)
				(arc
					(start 124.327412 -223.378522)
					(mid 124.228981 -223.404938)
					(end 124.156978 -223.477074)
				)
				(arc
					(start 123.687332 -224.291144)
					(mid 123.667648 -224.338554)
					(end 123.660916 -224.389442)
				)
				(arc
					(start 123.660916 -224.389442)
					(mid 123.718572 -224.528636)
					(end 123.857766 -224.586292)
				)
				(arc
					(start 123.857766 -224.586292)
					(mid 123.956197 -224.559876)
					(end 124.0282 -224.48774)
				)
			)
		)
	)
	(zone
		(layers "F.Cu" "B.Cu" "In1.Cu" "In2.Cu" "In3.Cu" "In4.Cu" "In5.Cu" "In6.Cu"
			"In7.Cu" "In8.Cu" "In9.Cu" "In10.Cu" "In11.Cu" "In12.Cu" "In13.Cu" "In14.Cu"
			"In15.Cu" "In16.Cu"
		)
		(hatch none 0.5)
		(connect_pads
			(clearance 0)
		)
		(min_thickness 0.25)
		(keepout
			(tracks not_allowed)
			(vias allowed)
			(pads allowed)
			(copperpour not_allowed)
			(footprints allowed)
		)
		(placement
			(enabled no)
			(sheetname "")
		)
		(fill
			(thermal_gap 0.5)
			(thermal_bridge_width 0.5)
			(island_removal_mode 0)
		)
		(polygon
			(pts
				(arc
					(start 86.704424 -286.475424)
					(mid 86.046564 -286.475424)
					(end 86.704424 -286.475424)
				)
			)
		)
	)
	(zone
		(layers "F.Cu" "B.Cu" "In1.Cu" "In2.Cu" "In3.Cu" "In4.Cu" "In5.Cu" "In6.Cu"
			"In7.Cu" "In8.Cu" "In9.Cu" "In10.Cu" "In11.Cu" "In12.Cu" "In13.Cu" "In14.Cu"
			"In15.Cu" "In16.Cu"
		)
		(hatch none 0.5)
		(connect_pads
			(clearance 0)
		)
		(min_thickness 0.25)
		(keepout
			(tracks not_allowed)
			(vias allowed)
			(pads allowed)
			(copperpour not_allowed)
			(footprints allowed)
		)
		(placement
			(enabled no)
			(sheetname "")
		)
		(fill
			(thermal_gap 0.5)
			(thermal_bridge_width 0.5)
			(island_removal_mode 0)
		)
		(polygon
			(pts
				(arc
					(start 130.690874 -409.649168)
					(mid 130.309874 -410.030168)
					(end 130.690874 -410.411168)
				)
				(arc
					(start 131.554474 -410.411168)
					(mid 131.935474 -410.030168)
					(end 131.554474 -409.649168)
				)
			)
		)
	)
	(zone
		(layers "F.Cu" "B.Cu" "In1.Cu" "In2.Cu" "In3.Cu" "In4.Cu" "In5.Cu" "In6.Cu"
			"In7.Cu" "In8.Cu" "In9.Cu" "In10.Cu" "In11.Cu" "In12.Cu" "In13.Cu" "In14.Cu"
			"In15.Cu" "In16.Cu"
		)
		(hatch none 0.5)
		(connect_pads
			(clearance 0)
		)
		(min_thickness 0.25)
		(keepout
			(tracks not_allowed)
			(vias allowed)
			(pads allowed)
			(copperpour not_allowed)
			(footprints allowed)
		)
		(placement
			(enabled no)
			(sheetname "")
		)
		(fill
			(thermal_gap 0.5)
			(thermal_bridge_width 0.5)
			(island_removal_mode 0)
		)
		(polygon
			(pts
				(arc
					(start 339.343492 -284.847538)
					(mid 338.685632 -284.847538)
					(end 339.343492 -284.847538)
				)
			)
		)
	)
	(zone
		(layers "F.Cu" "B.Cu" "In1.Cu" "In2.Cu" "In3.Cu" "In4.Cu" "In5.Cu" "In6.Cu"
			"In7.Cu" "In8.Cu" "In9.Cu" "In10.Cu" "In11.Cu" "In12.Cu" "In13.Cu" "In14.Cu"
			"In15.Cu" "In16.Cu"
		)
		(hatch none 0.5)
		(connect_pads
			(clearance 0)
		)
		(min_thickness 0.25)
		(keepout
			(tracks not_allowed)
			(vias allowed)
			(pads allowed)
			(copperpour not_allowed)
			(footprints allowed)
		)
		(placement
			(enabled no)
			(sheetname "")
		)
		(fill
			(thermal_gap 0.5)
			(thermal_bridge_width 0.5)
			(island_removal_mode 0)
		)
		(polygon
			(pts
				(arc
					(start 113.220754 -220.22181)
					(mid 113.148765 -220.149651)
					(end 113.05032 -220.123258)
				)
				(arc
					(start 113.05032 -220.123258)
					(mid 112.911126 -220.180914)
					(end 112.85347 -220.320108)
				)
				(arc
					(start 112.85347 -220.320108)
					(mid 112.860227 -220.370989)
					(end 112.879886 -220.418406)
				)
				(arc
					(start 113.349532 -221.232222)
					(mid 113.421521 -221.304381)
					(end 113.519966 -221.330774)
				)
				(arc
					(start 113.519966 -221.330774)
					(mid 113.65916 -221.273118)
					(end 113.716816 -221.133924)
				)
				(arc
					(start 113.716816 -221.133924)
					(mid 113.710059 -221.083043)
					(end 113.6904 -221.035626)
				)
			)
		)
	)
	(zone
		(layers "F.Cu" "B.Cu" "In1.Cu" "In2.Cu" "In3.Cu" "In4.Cu" "In5.Cu" "In6.Cu"
			"In7.Cu" "In8.Cu" "In9.Cu" "In10.Cu" "In11.Cu" "In12.Cu" "In13.Cu" "In14.Cu"
			"In15.Cu" "In16.Cu"
		)
		(hatch none 0.5)
		(connect_pads
			(clearance 0)
		)
		(min_thickness 0.25)
		(keepout
			(tracks not_allowed)
			(vias allowed)
			(pads allowed)
			(copperpour not_allowed)
			(footprints allowed)
		)
		(placement
			(enabled no)
			(sheetname "")
		)
		(fill
			(thermal_gap 0.5)
			(thermal_bridge_width 0.5)
			(island_removal_mode 0)
		)
		(polygon
			(pts
				(arc
					(start 113.848896 -221.133924)
					(mid 113.191036 -221.133924)
					(end 113.848896 -221.133924)
				)
			)
		)
	)
	(zone
		(layers "F.Cu" "B.Cu" "In1.Cu" "In2.Cu" "In3.Cu" "In4.Cu" "In5.Cu" "In6.Cu"
			"In7.Cu" "In8.Cu" "In9.Cu" "In10.Cu" "In11.Cu" "In12.Cu" "In13.Cu" "In14.Cu"
			"In15.Cu" "In16.Cu"
		)
		(hatch none 0.5)
		(connect_pads
			(clearance 0)
		)
		(min_thickness 0.25)
		(keepout
			(tracks not_allowed)
			(vias allowed)
			(pads allowed)
			(copperpour not_allowed)
			(footprints allowed)
		)
		(placement
			(enabled no)
			(sheetname "")
		)
		(fill
			(thermal_gap 0.5)
			(thermal_bridge_width 0.5)
			(island_removal_mode 0)
		)
		(polygon
			(pts
				(arc
					(start 127.786892 -217.97645)
					(mid 127.806576 -217.92904)
					(end 127.813308 -217.878152)
				)
				(arc
					(start 127.813308 -217.878152)
					(mid 127.755652 -217.738958)
					(end 127.616458 -217.681302)
				)
				(arc
					(start 127.616458 -217.681302)
					(mid 127.518027 -217.707718)
					(end 127.446024 -217.779854)
				)
				(arc
					(start 126.976378 -218.593924)
					(mid 126.956694 -218.641334)
					(end 126.949962 -218.692222)
				)
				(arc
					(start 126.949962 -218.692222)
					(mid 127.007618 -218.831416)
					(end 127.146812 -218.889072)
				)
				(arc
					(start 127.146812 -218.889072)
					(mid 127.245243 -218.862656)
					(end 127.317246 -218.79052)
				)
			)
		)
	)
	(zone
		(layers "F.Cu" "B.Cu" "In1.Cu" "In2.Cu" "In3.Cu" "In4.Cu" "In5.Cu" "In6.Cu"
			"In7.Cu" "In8.Cu" "In9.Cu" "In10.Cu" "In11.Cu" "In12.Cu" "In13.Cu" "In14.Cu"
			"In15.Cu" "In16.Cu"
		)
		(hatch none 0.5)
		(connect_pads
			(clearance 0)
		)
		(min_thickness 0.25)
		(keepout
			(tracks not_allowed)
			(vias allowed)
			(pads allowed)
			(copperpour not_allowed)
			(footprints allowed)
		)
		(placement
			(enabled no)
			(sheetname "")
		)
		(fill
			(thermal_gap 0.5)
			(thermal_bridge_width 0.5)
			(island_removal_mode 0)
		)
		(polygon
			(pts
				(arc
					(start 20.22348 -384.920744)
					(mid 19.84248 -384.539744)
					(end 19.46148 -384.920744)
				)
				(arc
					(start 19.46148 -385.784344)
					(mid 19.84248 -386.165344)
					(end 20.22348 -385.784344)
				)
			)
		)
	)
	(zone
		(layers "F.Cu" "B.Cu" "In1.Cu" "In2.Cu" "In3.Cu" "In4.Cu" "In5.Cu" "In6.Cu"
			"In7.Cu" "In8.Cu" "In9.Cu" "In10.Cu" "In11.Cu" "In12.Cu" "In13.Cu" "In14.Cu"
			"In15.Cu" "In16.Cu"
		)
		(hatch none 0.5)
		(connect_pads
			(clearance 0)
		)
		(min_thickness 0.25)
		(keepout
			(tracks not_allowed)
			(vias allowed)
			(pads allowed)
			(copperpour not_allowed)
			(footprints allowed)
		)
		(placement
			(enabled no)
			(sheetname "")
		)
		(fill
			(thermal_gap 0.5)
			(thermal_bridge_width 0.5)
			(island_removal_mode 0)
		)
		(polygon
			(pts
				(arc
					(start 230.87838 -53.84292)
					(mid 230.49738 -53.46192)
					(end 230.11638 -53.84292)
				)
				(arc
					(start 230.11638 -54.70652)
					(mid 230.49738 -55.08752)
					(end 230.87838 -54.70652)
				)
			)
		)
	)
	(zone
		(layers "F.Cu" "B.Cu" "In1.Cu" "In2.Cu" "In3.Cu" "In4.Cu" "In5.Cu" "In6.Cu"
			"In7.Cu" "In8.Cu" "In9.Cu" "In10.Cu" "In11.Cu" "In12.Cu" "In13.Cu" "In14.Cu"
			"In15.Cu" "In16.Cu"
		)
		(hatch none 0.5)
		(connect_pads
			(clearance 0)
		)
		(min_thickness 0.25)
		(keepout
			(tracks not_allowed)
			(vias allowed)
			(pads allowed)
			(copperpour not_allowed)
			(footprints allowed)
		)
		(placement
			(enabled no)
			(sheetname "")
		)
		(fill
			(thermal_gap 0.5)
			(thermal_bridge_width 0.5)
			(island_removal_mode 0)
		)
		(polygon
			(pts
				(arc
					(start 70.768718 -409.649168)
					(mid 70.387718 -410.030168)
					(end 70.768718 -410.411168)
				)
				(arc
					(start 71.632318 -410.411168)
					(mid 72.013318 -410.030168)
					(end 71.632318 -409.649168)
				)
			)
		)
	)
	(zone
		(layers "F.Cu" "B.Cu" "In1.Cu" "In2.Cu" "In3.Cu" "In4.Cu" "In5.Cu" "In6.Cu"
			"In7.Cu" "In8.Cu" "In9.Cu" "In10.Cu" "In11.Cu" "In12.Cu" "In13.Cu" "In14.Cu"
			"In15.Cu" "In16.Cu"
		)
		(hatch none 0.5)
		(connect_pads
			(clearance 0)
		)
		(min_thickness 0.25)
		(keepout
			(tracks not_allowed)
			(vias allowed)
			(pads allowed)
			(copperpour not_allowed)
			(footprints allowed)
		)
		(placement
			(enabled no)
			(sheetname "")
		)
		(fill
			(thermal_gap 0.5)
			(thermal_bridge_width 0.5)
			(island_removal_mode 0)
		)
		(polygon
			(pts
				(arc
					(start 332.895448 -406.62352)
					(mid 332.514448 -407.00452)
					(end 332.895448 -407.38552)
				)
				(arc
					(start 333.759048 -407.38552)
					(mid 334.140048 -407.00452)
					(end 333.759048 -406.62352)
				)
			)
		)
	)
	(zone
		(layers "F.Cu" "B.Cu" "In1.Cu" "In2.Cu" "In3.Cu" "In4.Cu" "In5.Cu" "In6.Cu"
			"In7.Cu" "In8.Cu" "In9.Cu" "In10.Cu" "In11.Cu" "In12.Cu" "In13.Cu" "In14.Cu"
			"In15.Cu" "In16.Cu"
		)
		(hatch none 0.5)
		(connect_pads
			(clearance 0)
		)
		(min_thickness 0.25)
		(keepout
			(tracks not_allowed)
			(vias allowed)
			(pads allowed)
			(copperpour not_allowed)
			(footprints allowed)
		)
		(placement
			(enabled no)
			(sheetname "")
		)
		(fill
			(thermal_gap 0.5)
			(thermal_bridge_width 0.5)
			(island_removal_mode 0)
		)
		(polygon
			(pts
				(arc
					(start 99.673664 -282.405836)
					(mid 100.331524 -282.405836)
					(end 99.673664 -282.405836)
				)
			)
		)
	)
	(zone
		(layers "F.Cu" "B.Cu" "In1.Cu" "In2.Cu" "In3.Cu" "In4.Cu" "In5.Cu" "In6.Cu"
			"In7.Cu" "In8.Cu" "In9.Cu" "In10.Cu" "In11.Cu" "In12.Cu" "In13.Cu" "In14.Cu"
			"In15.Cu" "In16.Cu"
		)
		(hatch none 0.5)
		(connect_pads
			(clearance 0)
		)
		(min_thickness 0.25)
		(keepout
			(tracks not_allowed)
			(vias allowed)
			(pads allowed)
			(copperpour not_allowed)
			(footprints allowed)
		)
		(placement
			(enabled no)
			(sheetname "")
		)
		(fill
			(thermal_gap 0.5)
			(thermal_bridge_width 0.5)
			(island_removal_mode 0)
		)
		(polygon
			(pts
				(arc
					(start 110.559596 -221.94774)
					(mid 109.901736 -221.94774)
					(end 110.559596 -221.94774)
				)
			)
		)
	)
	(zone
		(layers "F.Cu" "B.Cu" "In1.Cu" "In2.Cu" "In3.Cu" "In4.Cu" "In5.Cu" "In6.Cu"
			"In7.Cu" "In8.Cu" "In9.Cu" "In10.Cu" "In11.Cu" "In12.Cu" "In13.Cu" "In14.Cu"
			"In15.Cu" "In16.Cu"
		)
		(hatch none 0.5)
		(connect_pads
			(clearance 0)
		)
		(min_thickness 0.25)
		(keepout
			(tracks not_allowed)
			(vias allowed)
			(pads allowed)
			(copperpour not_allowed)
			(footprints allowed)
		)
		(placement
			(enabled no)
			(sheetname "")
		)
		(fill
			(thermal_gap 0.5)
			(thermal_bridge_width 0.5)
			(island_removal_mode 0)
		)
		(polygon
			(pts
				(arc
					(start 95.914464 -285.661354)
					(mid 96.572324 -285.661354)
					(end 95.914464 -285.661354)
				)
			)
		)
	)
	(zone
		(layers "F.Cu" "B.Cu" "In1.Cu" "In2.Cu" "In3.Cu" "In4.Cu" "In5.Cu" "In6.Cu"
			"In7.Cu" "In8.Cu" "In9.Cu" "In10.Cu" "In11.Cu" "In12.Cu" "In13.Cu" "In14.Cu"
			"In15.Cu" "In16.Cu"
		)
		(hatch none 0.5)
		(connect_pads
			(clearance 0)
		)
		(min_thickness 0.25)
		(keepout
			(tracks not_allowed)
			(vias allowed)
			(pads allowed)
			(copperpour not_allowed)
			(footprints allowed)
		)
		(placement
			(enabled no)
			(sheetname "")
		)
		(fill
			(thermal_gap 0.5)
			(thermal_bridge_width 0.5)
			(island_removal_mode 0)
		)
		(polygon
			(pts
				(arc
					(start 72.142096 -421.760396)
					(mid 72.164414 -421.814278)
					(end 72.218296 -421.836596)
				)
				(arc
					(start 73.158096 -421.836596)
					(mid 73.211978 -421.814278)
					(end 73.234296 -421.760396)
				)
				(arc
					(start 73.234296 -419.218872)
					(mid 73.211978 -419.16499)
					(end 73.158096 -419.142672)
				)
				(arc
					(start 72.218296 -419.142672)
					(mid 72.164414 -419.16499)
					(end 72.142096 -419.218872)
				)
			)
		)
	)
	(zone
		(layers "F.Cu" "B.Cu" "In1.Cu" "In2.Cu" "In3.Cu" "In4.Cu" "In5.Cu" "In6.Cu"
			"In7.Cu" "In8.Cu" "In9.Cu" "In10.Cu" "In11.Cu" "In12.Cu" "In13.Cu" "In14.Cu"
			"In15.Cu" "In16.Cu"
		)
		(hatch none 0.5)
		(connect_pads
			(clearance 0)
		)
		(min_thickness 0.25)
		(keepout
			(tracks not_allowed)
			(vias allowed)
			(pads allowed)
			(copperpour not_allowed)
			(footprints allowed)
		)
		(placement
			(enabled no)
			(sheetname "")
		)
		(fill
			(thermal_gap 0.5)
			(thermal_bridge_width 0.5)
			(island_removal_mode 0)
		)
		(polygon
			(pts
				(arc
					(start 347.22181 -225.203258)
					(mid 346.56395 -225.203258)
					(end 347.22181 -225.203258)
				)
			)
		)
	)
	(zone
		(layers "F.Cu" "B.Cu" "In1.Cu" "In2.Cu" "In3.Cu" "In4.Cu" "In5.Cu" "In6.Cu"
			"In7.Cu" "In8.Cu" "In9.Cu" "In10.Cu" "In11.Cu" "In12.Cu" "In13.Cu" "In14.Cu"
			"In15.Cu" "In16.Cu"
		)
		(hatch none 0.5)
		(connect_pads
			(clearance 0)
		)
		(min_thickness 0.25)
		(keepout
			(tracks not_allowed)
			(vias allowed)
			(pads allowed)
			(copperpour not_allowed)
			(footprints allowed)
		)
		(placement
			(enabled no)
			(sheetname "")
		)
		(fill
			(thermal_gap 0.5)
			(thermal_bridge_width 0.5)
			(island_removal_mode 0)
		)
		(polygon
			(pts
				(arc
					(start 126.281434 -403.502876)
					(mid 125.900434 -403.883876)
					(end 126.281434 -404.264876)
				)
				(arc
					(start 127.145034 -404.264876)
					(mid 127.526034 -403.883876)
					(end 127.145034 -403.502876)
				)
			)
		)
	)
	(zone
		(layers "F.Cu" "B.Cu" "In1.Cu" "In2.Cu" "In3.Cu" "In4.Cu" "In5.Cu" "In6.Cu"
			"In7.Cu" "In8.Cu" "In9.Cu" "In10.Cu" "In11.Cu" "In12.Cu" "In13.Cu" "In14.Cu"
			"In15.Cu" "In16.Cu"
		)
		(hatch none 0.5)
		(connect_pads
			(clearance 0)
		)
		(min_thickness 0.25)
		(keepout
			(tracks not_allowed)
			(vias allowed)
			(pads allowed)
			(copperpour not_allowed)
			(footprints allowed)
		)
		(placement
			(enabled no)
			(sheetname "")
		)
		(fill
			(thermal_gap 0.5)
			(thermal_bridge_width 0.5)
			(island_removal_mode 0)
		)
		(polygon
			(pts
				(arc
					(start 307.043328 -403.502876)
					(mid 306.662328 -403.883876)
					(end 307.043328 -404.264876)
				)
				(arc
					(start 307.906928 -404.264876)
					(mid 308.287928 -403.883876)
					(end 307.906928 -403.502876)
				)
			)
		)
	)
	(zone
		(layers "F.Cu" "B.Cu" "In1.Cu" "In2.Cu" "In3.Cu" "In4.Cu" "In5.Cu" "In6.Cu"
			"In7.Cu" "In8.Cu" "In9.Cu" "In10.Cu" "In11.Cu" "In12.Cu" "In13.Cu" "In14.Cu"
			"In15.Cu" "In16.Cu"
		)
		(hatch none 0.5)
		(connect_pads
			(clearance 0)
		)
		(min_thickness 0.25)
		(keepout
			(tracks not_allowed)
			(vias allowed)
			(pads allowed)
			(copperpour not_allowed)
			(footprints allowed)
		)
		(placement
			(enabled no)
			(sheetname "")
		)
		(fill
			(thermal_gap 0.5)
			(thermal_bridge_width 0.5)
			(island_removal_mode 0)
		)
		(polygon
			(pts
				(arc
					(start 117.607588 -214.622634)
					(mid 116.949728 -214.622634)
					(end 117.607588 -214.622634)
				)
			)
		)
	)
	(zone
		(layers "F.Cu" "B.Cu" "In1.Cu" "In2.Cu" "In3.Cu" "In4.Cu" "In5.Cu" "In6.Cu"
			"In7.Cu" "In8.Cu" "In9.Cu" "In10.Cu" "In11.Cu" "In12.Cu" "In13.Cu" "In14.Cu"
			"In15.Cu" "In16.Cu"
		)
		(hatch none 0.5)
		(connect_pads
			(clearance 0)
		)
		(min_thickness 0.25)
		(keepout
			(tracks not_allowed)
			(vias allowed)
			(pads allowed)
			(copperpour not_allowed)
			(footprints allowed)
		)
		(placement
			(enabled no)
			(sheetname "")
		)
		(fill
			(thermal_gap 0.5)
			(thermal_bridge_width 0.5)
			(island_removal_mode 0)
		)
		(polygon
			(pts
				(arc
					(start 357.089964 -224.389442)
					(mid 356.432104 -224.389442)
					(end 357.089964 -224.389442)
				)
			)
		)
	)
	(zone
		(layers "F.Cu" "B.Cu" "In1.Cu" "In2.Cu" "In3.Cu" "In4.Cu" "In5.Cu" "In6.Cu"
			"In7.Cu" "In8.Cu" "In9.Cu" "In10.Cu" "In11.Cu" "In12.Cu" "In13.Cu" "In14.Cu"
			"In15.Cu" "In16.Cu"
		)
		(hatch none 0.5)
		(connect_pads
			(clearance 0)
		)
		(min_thickness 0.25)
		(keepout
			(tracks not_allowed)
			(vias allowed)
			(pads allowed)
			(copperpour not_allowed)
			(footprints allowed)
		)
		(placement
			(enabled no)
			(sheetname "")
		)
		(fill
			(thermal_gap 0.5)
			(thermal_bridge_width 0.5)
			(island_removal_mode 0)
		)
		(polygon
			(pts
				(arc
					(start 98.734118 -288.917126)
					(mid 99.391978 -288.917126)
					(end 98.734118 -288.917126)
				)
			)
		)
	)
	(zone
		(layers "F.Cu" "B.Cu" "In1.Cu" "In2.Cu" "In3.Cu" "In4.Cu" "In5.Cu" "In6.Cu"
			"In7.Cu" "In8.Cu" "In9.Cu" "In10.Cu" "In11.Cu" "In12.Cu" "In13.Cu" "In14.Cu"
			"In15.Cu" "In16.Cu"
		)
		(hatch none 0.5)
		(connect_pads
			(clearance 0)
		)
		(min_thickness 0.25)
		(keepout
			(tracks not_allowed)
			(vias allowed)
			(pads allowed)
			(copperpour not_allowed)
			(footprints allowed)
		)
		(placement
			(enabled no)
			(sheetname "")
		)
		(fill
			(thermal_gap 0.5)
			(thermal_bridge_width 0.5)
			(island_removal_mode 0)
		)
		(polygon
			(pts
				(xy 468.100156 -105.470706) (xy 468.100156 -110.470696) (xy 467.795356 -110.165896) (xy 467.795356 -105.775506)
			)
		)
	)
	(zone
		(layers "F.Cu" "B.Cu" "In1.Cu" "In2.Cu" "In3.Cu" "In4.Cu" "In5.Cu" "In6.Cu"
			"In7.Cu" "In8.Cu" "In9.Cu" "In10.Cu" "In11.Cu" "In12.Cu" "In13.Cu" "In14.Cu"
			"In15.Cu" "In16.Cu"
		)
		(hatch none 0.5)
		(connect_pads
			(clearance 0)
		)
		(min_thickness 0.25)
		(keepout
			(tracks not_allowed)
			(vias allowed)
			(pads allowed)
			(copperpour not_allowed)
			(footprints allowed)
		)
		(placement
			(enabled no)
			(sheetname "")
		)
		(fill
			(thermal_gap 0.5)
			(thermal_bridge_width 0.5)
			(island_removal_mode 0)
		)
		(polygon
			(pts
				(arc
					(start 382.464564 -217.878406)
					(mid 381.806704 -217.878406)
					(end 382.464564 -217.878406)
				)
			)
		)
	)
	(zone
		(layers "F.Cu" "B.Cu" "In1.Cu" "In2.Cu" "In3.Cu" "In4.Cu" "In5.Cu" "In6.Cu"
			"In7.Cu" "In8.Cu" "In9.Cu" "In10.Cu" "In11.Cu" "In12.Cu" "In13.Cu" "In14.Cu"
			"In15.Cu" "In16.Cu"
		)
		(hatch none 0.5)
		(connect_pads
			(clearance 0)
		)
		(min_thickness 0.25)
		(keepout
			(tracks not_allowed)
			(vias allowed)
			(pads allowed)
			(copperpour not_allowed)
			(footprints allowed)
		)
		(placement
			(enabled no)
			(sheetname "")
		)
		(fill
			(thermal_gap 0.5)
			(thermal_bridge_width 0.5)
			(island_removal_mode 0)
		)
		(polygon
			(pts
				(arc
					(start 355.68001 -217.064336)
					(mid 355.02215 -217.064336)
					(end 355.68001 -217.064336)
				)
			)
		)
	)
	(zone
		(layers "F.Cu" "B.Cu" "In1.Cu" "In2.Cu" "In3.Cu" "In4.Cu" "In5.Cu" "In6.Cu"
			"In7.Cu" "In8.Cu" "In9.Cu" "In10.Cu" "In11.Cu" "In12.Cu" "In13.Cu" "In14.Cu"
			"In15.Cu" "In16.Cu"
		)
		(hatch none 0.5)
		(connect_pads
			(clearance 0)
		)
		(min_thickness 0.25)
		(keepout
			(tracks not_allowed)
			(vias allowed)
			(pads allowed)
			(copperpour not_allowed)
			(footprints allowed)
		)
		(placement
			(enabled no)
			(sheetname "")
		)
		(fill
			(thermal_gap 0.5)
			(thermal_bridge_width 0.5)
			(island_removal_mode 0)
		)
		(polygon
			(pts
				(arc
					(start 331.988668 -74.710544)
					(mid 332.369668 -74.329544)
					(end 331.988668 -73.948544)
				)
				(arc
					(start 331.125068 -73.948544)
					(mid 330.744068 -74.329544)
					(end 331.125068 -74.710544)
				)
			)
		)
	)
	(zone
		(layers "F.Cu" "B.Cu" "In1.Cu" "In2.Cu" "In3.Cu" "In4.Cu" "In5.Cu" "In6.Cu"
			"In7.Cu" "In8.Cu" "In9.Cu" "In10.Cu" "In11.Cu" "In12.Cu" "In13.Cu" "In14.Cu"
			"In15.Cu" "In16.Cu"
		)
		(hatch none 0.5)
		(connect_pads
			(clearance 0)
		)
		(min_thickness 0.25)
		(keepout
			(tracks not_allowed)
			(vias allowed)
			(pads allowed)
			(copperpour not_allowed)
			(footprints allowed)
		)
		(placement
			(enabled no)
			(sheetname "")
		)
		(fill
			(thermal_gap 0.5)
			(thermal_bridge_width 0.5)
			(island_removal_mode 0)
		)
		(polygon
			(pts
				(arc
					(start 100.221542 -217.064336)
					(mid 99.563682 -217.064336)
					(end 100.221542 -217.064336)
				)
			)
		)
	)
	(zone
		(layers "F.Cu" "B.Cu" "In1.Cu" "In2.Cu" "In3.Cu" "In4.Cu" "In5.Cu" "In6.Cu"
			"In7.Cu" "In8.Cu" "In9.Cu" "In10.Cu" "In11.Cu" "In12.Cu" "In13.Cu" "In14.Cu"
			"In15.Cu" "In16.Cu"
		)
		(hatch none 0.5)
		(connect_pads
			(clearance 0)
		)
		(min_thickness 0.25)
		(keepout
			(tracks not_allowed)
			(vias allowed)
			(pads allowed)
			(copperpour not_allowed)
			(footprints allowed)
		)
		(placement
			(enabled no)
			(sheetname "")
		)
		(fill
			(thermal_gap 0.5)
			(thermal_bridge_width 0.5)
			(island_removal_mode 0)
		)
		(polygon
			(pts
				(arc
					(start 141.01445 -17.763744)
					(mid 140.63345 -18.144744)
					(end 141.01445 -18.525744)
				)
				(arc
					(start 141.87805 -18.525744)
					(mid 142.25905 -18.144744)
					(end 141.87805 -17.763744)
				)
			)
		)
	)
	(zone
		(layers "F.Cu" "B.Cu" "In1.Cu" "In2.Cu" "In3.Cu" "In4.Cu" "In5.Cu" "In6.Cu"
			"In7.Cu" "In8.Cu" "In9.Cu" "In10.Cu" "In11.Cu" "In12.Cu" "In13.Cu" "In14.Cu"
			"In15.Cu" "In16.Cu"
		)
		(hatch none 0.5)
		(connect_pads
			(clearance 0)
		)
		(min_thickness 0.25)
		(keepout
			(tracks not_allowed)
			(vias allowed)
			(pads allowed)
			(copperpour not_allowed)
			(footprints allowed)
		)
		(placement
			(enabled no)
			(sheetname "")
		)
		(fill
			(thermal_gap 0.5)
			(thermal_bridge_width 0.5)
			(island_removal_mode 0)
		)
		(polygon
			(pts
				(arc
					(start 97.183194 -282.208986)
					(mid 96.986344 -282.405836)
					(end 97.183194 -282.602686)
				)
				(arc
					(start 98.122994 -282.602686)
					(mid 98.319844 -282.405836)
					(end 98.122994 -282.208986)
				)
			)
		)
	)
	(zone
		(layers "F.Cu" "B.Cu" "In1.Cu" "In2.Cu" "In3.Cu" "In4.Cu" "In5.Cu" "In6.Cu"
			"In7.Cu" "In8.Cu" "In9.Cu" "In10.Cu" "In11.Cu" "In12.Cu" "In13.Cu" "In14.Cu"
			"In15.Cu" "In16.Cu"
		)
		(hatch none 0.5)
		(connect_pads
			(clearance 0)
		)
		(min_thickness 0.25)
		(keepout
			(tracks not_allowed)
			(vias allowed)
			(pads allowed)
			(copperpour not_allowed)
			(footprints allowed)
		)
		(placement
			(enabled no)
			(sheetname "")
		)
		(fill
			(thermal_gap 0.5)
			(thermal_bridge_width 0.5)
			(island_removal_mode 0)
		)
		(polygon
			(pts
				(arc
					(start 350.151446 -288.917126)
					(mid 349.493586 -288.917126)
					(end 350.151446 -288.917126)
				)
			)
		)
	)
	(zone
		(layers "F.Cu" "B.Cu" "In1.Cu" "In2.Cu" "In3.Cu" "In4.Cu" "In5.Cu" "In6.Cu"
			"In7.Cu" "In8.Cu" "In9.Cu" "In10.Cu" "In11.Cu" "In12.Cu" "In13.Cu" "In14.Cu"
			"In15.Cu" "In16.Cu"
		)
		(hatch none 0.5)
		(connect_pads
			(clearance 0)
		)
		(min_thickness 0.25)
		(keepout
			(tracks not_allowed)
			(vias allowed)
			(pads allowed)
			(copperpour not_allowed)
			(footprints allowed)
		)
		(placement
			(enabled no)
			(sheetname "")
		)
		(fill
			(thermal_gap 0.5)
			(thermal_bridge_width 0.5)
			(island_removal_mode 0)
		)
		(polygon
			(pts
				(arc
					(start 432.291236 -18.744438)
					(mid 431.910236 -19.125438)
					(end 432.291236 -19.506438)
				)
				(arc
					(start 433.154836 -19.506438)
					(mid 433.535836 -19.125438)
					(end 433.154836 -18.744438)
				)
			)
		)
	)
	(zone
		(layers "F.Cu" "B.Cu" "In1.Cu" "In2.Cu" "In3.Cu" "In4.Cu" "In5.Cu" "In6.Cu"
			"In7.Cu" "In8.Cu" "In9.Cu" "In10.Cu" "In11.Cu" "In12.Cu" "In13.Cu" "In14.Cu"
			"In15.Cu" "In16.Cu"
		)
		(hatch none 0.5)
		(connect_pads
			(clearance 0)
		)
		(min_thickness 0.25)
		(keepout
			(tracks not_allowed)
			(vias allowed)
			(pads allowed)
			(copperpour not_allowed)
			(footprints allowed)
		)
		(placement
			(enabled no)
			(sheetname "")
		)
		(fill
			(thermal_gap 0.5)
			(thermal_bridge_width 0.5)
			(island_removal_mode 0)
		)
		(polygon
			(pts
				(arc
					(start 380.05893 -289.003232)
					(mid 380.074854 -288.961481)
					(end 380.080266 -288.917126)
				)
				(arc
					(start 380.080266 -288.917126)
					(mid 380.02633 -288.786912)
					(end 379.896116 -288.732976)
				)
				(arc
					(start 379.896116 -288.732976)
					(mid 379.801096 -288.759384)
					(end 379.733302 -288.83102)
				)
				(arc
					(start 379.263148 -289.721036)
					(mid 379.247224 -289.762787)
					(end 379.241812 -289.807142)
				)
				(arc
					(start 379.241812 -289.807142)
					(mid 379.295748 -289.937356)
					(end 379.425962 -289.991292)
				)
				(arc
					(start 379.425962 -289.991292)
					(mid 379.520982 -289.964884)
					(end 379.588776 -289.893248)
				)
			)
		)
	)
	(zone
		(layers "F.Cu" "B.Cu" "In1.Cu" "In2.Cu" "In3.Cu" "In4.Cu" "In5.Cu" "In6.Cu"
			"In7.Cu" "In8.Cu" "In9.Cu" "In10.Cu" "In11.Cu" "In12.Cu" "In13.Cu" "In14.Cu"
			"In15.Cu" "In16.Cu"
		)
		(hatch none 0.5)
		(connect_pads
			(clearance 0)
		)
		(min_thickness 0.25)
		(keepout
			(tracks not_allowed)
			(vias allowed)
			(pads allowed)
			(copperpour not_allowed)
			(footprints allowed)
		)
		(placement
			(enabled no)
			(sheetname "")
		)
		(fill
			(thermal_gap 0.5)
			(thermal_bridge_width 0.5)
			(island_removal_mode 0)
		)
		(polygon
			(pts
				(arc
					(start 94.864682 -215.436704)
					(mid 95.522542 -215.436704)
					(end 94.864682 -215.436704)
				)
			)
		)
	)
	(zone
		(layers "F.Cu" "B.Cu" "In1.Cu" "In2.Cu" "In3.Cu" "In4.Cu" "In5.Cu" "In6.Cu"
			"In7.Cu" "In8.Cu" "In9.Cu" "In10.Cu" "In11.Cu" "In12.Cu" "In13.Cu" "In14.Cu"
			"In15.Cu" "In16.Cu"
		)
		(hatch none 0.5)
		(connect_pads
			(clearance 0)
		)
		(min_thickness 0.25)
		(keepout
			(tracks not_allowed)
			(vias allowed)
			(pads allowed)
			(copperpour not_allowed)
			(footprints allowed)
		)
		(placement
			(enabled no)
			(sheetname "")
		)
		(fill
			(thermal_gap 0.5)
			(thermal_bridge_width 0.5)
			(island_removal_mode 0)
		)
		(polygon
			(pts
				(arc
					(start 113.378742 -223.575626)
					(mid 112.720882 -223.575626)
					(end 113.378742 -223.575626)
				)
			)
		)
	)
	(zone
		(layers "F.Cu" "B.Cu" "In1.Cu" "In2.Cu" "In3.Cu" "In4.Cu" "In5.Cu" "In6.Cu"
			"In7.Cu" "In8.Cu" "In9.Cu" "In10.Cu" "In11.Cu" "In12.Cu" "In13.Cu" "In14.Cu"
			"In15.Cu" "In16.Cu"
		)
		(hatch none 0.5)
		(connect_pads
			(clearance 0)
		)
		(min_thickness 0.25)
		(keepout
			(tracks not_allowed)
			(vias allowed)
			(pads allowed)
			(copperpour not_allowed)
			(footprints allowed)
		)
		(placement
			(enabled no)
			(sheetname "")
		)
		(fill
			(thermal_gap 0.5)
			(thermal_bridge_width 0.5)
			(island_removal_mode 0)
		)
		(polygon
			(pts
				(arc
					(start 47.979838 -403.502876)
					(mid 47.598838 -403.883876)
					(end 47.979838 -404.264876)
				)
				(arc
					(start 48.843438 -404.264876)
					(mid 49.224438 -403.883876)
					(end 48.843438 -403.502876)
				)
			)
		)
	)
	(zone
		(layers "F.Cu" "B.Cu" "In1.Cu" "In2.Cu" "In3.Cu" "In4.Cu" "In5.Cu" "In6.Cu"
			"In7.Cu" "In8.Cu" "In9.Cu" "In10.Cu" "In11.Cu" "In12.Cu" "In13.Cu" "In14.Cu"
			"In15.Cu" "In16.Cu"
		)
		(hatch none 0.5)
		(connect_pads
			(clearance 0)
		)
		(min_thickness 0.25)
		(keepout
			(tracks not_allowed)
			(vias allowed)
			(pads allowed)
			(copperpour not_allowed)
			(footprints allowed)
		)
		(placement
			(enabled no)
			(sheetname "")
		)
		(fill
			(thermal_gap 0.5)
			(thermal_bridge_width 0.5)
			(island_removal_mode 0)
		)
		(polygon
			(pts
				(arc
					(start 352.471228 -280.679906)
					(mid 352.451544 -280.727316)
					(end 352.444812 -280.778204)
				)
				(arc
					(start 352.444812 -280.778204)
					(mid 352.502468 -280.917398)
					(end 352.641662 -280.975054)
				)
				(arc
					(start 352.641662 -280.975054)
					(mid 352.740093 -280.948638)
					(end 352.812096 -280.876502)
				)
				(arc
					(start 353.281996 -280.062432)
					(mid 353.30168 -280.015022)
					(end 353.308412 -279.964134)
				)
				(arc
					(start 353.308412 -279.964134)
					(mid 353.250756 -279.82494)
					(end 353.111562 -279.767284)
				)
				(arc
					(start 353.111562 -279.767284)
					(mid 353.013131 -279.7937)
					(end 352.941128 -279.865836)
				)
			)
		)
	)
	(zone
		(layers "F.Cu" "B.Cu" "In1.Cu" "In2.Cu" "In3.Cu" "In4.Cu" "In5.Cu" "In6.Cu"
			"In7.Cu" "In8.Cu" "In9.Cu" "In10.Cu" "In11.Cu" "In12.Cu" "In13.Cu" "In14.Cu"
			"In15.Cu" "In16.Cu"
		)
		(hatch none 0.5)
		(connect_pads
			(clearance 0)
		)
		(min_thickness 0.25)
		(keepout
			(tracks not_allowed)
			(vias allowed)
			(pads allowed)
			(copperpour not_allowed)
			(footprints allowed)
		)
		(placement
			(enabled no)
			(sheetname "")
		)
		(fill
			(thermal_gap 0.5)
			(thermal_bridge_width 0.5)
			(island_removal_mode 0)
		)
		(polygon
			(pts
				(arc
					(start 131.156964 -289.807142)
					(mid 131.814824 -289.807142)
					(end 131.156964 -289.807142)
				)
			)
		)
	)
	(zone
		(layers "F.Cu" "B.Cu" "In1.Cu" "In2.Cu" "In3.Cu" "In4.Cu" "In5.Cu" "In6.Cu"
			"In7.Cu" "In8.Cu" "In9.Cu" "In10.Cu" "In11.Cu" "In12.Cu" "In13.Cu" "In14.Cu"
			"In15.Cu" "In16.Cu"
		)
		(hatch none 0.5)
		(connect_pads
			(clearance 0)
		)
		(min_thickness 0.25)
		(keepout
			(tracks not_allowed)
			(vias allowed)
			(pads allowed)
			(copperpour not_allowed)
			(footprints allowed)
		)
		(placement
			(enabled no)
			(sheetname "")
		)
		(fill
			(thermal_gap 0.5)
			(thermal_bridge_width 0.5)
			(island_removal_mode 0)
		)
		(polygon
			(pts
				(arc
					(start 113.6904 -224.291144)
					(mid 113.618411 -224.218985)
					(end 113.519966 -224.192592)
				)
				(arc
					(start 113.519966 -224.192592)
					(mid 113.380772 -224.250248)
					(end 113.323116 -224.389442)
				)
				(arc
					(start 113.323116 -224.389442)
					(mid 113.329873 -224.440323)
					(end 113.349532 -224.48774)
				)
				(arc
					(start 113.819178 -225.301556)
					(mid 113.891167 -225.373715)
					(end 113.989612 -225.400108)
				)
				(arc
					(start 113.989612 -225.400108)
					(mid 114.128806 -225.342452)
					(end 114.186462 -225.203258)
				)
				(arc
					(start 114.186462 -225.203258)
					(mid 114.179705 -225.152377)
					(end 114.160046 -225.10496)
				)
			)
		)
	)
	(zone
		(layers "F.Cu" "B.Cu" "In1.Cu" "In2.Cu" "In3.Cu" "In4.Cu" "In5.Cu" "In6.Cu"
			"In7.Cu" "In8.Cu" "In9.Cu" "In10.Cu" "In11.Cu" "In12.Cu" "In13.Cu" "In14.Cu"
			"In15.Cu" "In16.Cu"
		)
		(hatch none 0.5)
		(connect_pads
			(clearance 0)
		)
		(min_thickness 0.25)
		(keepout
			(tracks not_allowed)
			(vias allowed)
			(pads allowed)
			(copperpour not_allowed)
			(footprints allowed)
		)
		(placement
			(enabled no)
			(sheetname "")
		)
		(fill
			(thermal_gap 0.5)
			(thermal_bridge_width 0.5)
			(island_removal_mode 0)
		)
		(polygon
			(pts
				(arc
					(start 107.111292 -214.720932)
					(mid 107.130976 -214.673522)
					(end 107.137708 -214.622634)
				)
				(arc
					(start 107.137708 -214.622634)
					(mid 107.080052 -214.48344)
					(end 106.940858 -214.425784)
				)
				(arc
					(start 106.940858 -214.425784)
					(mid 106.842427 -214.4522)
					(end 106.770424 -214.524336)
				)
				(arc
					(start 106.300778 -215.338406)
					(mid 106.281094 -215.385816)
					(end 106.274362 -215.436704)
				)
				(arc
					(start 106.274362 -215.436704)
					(mid 106.332018 -215.575898)
					(end 106.471212 -215.633554)
				)
				(arc
					(start 106.471212 -215.633554)
					(mid 106.569643 -215.607138)
					(end 106.641646 -215.535002)
				)
			)
		)
	)
	(zone
		(layers "F.Cu" "B.Cu" "In1.Cu" "In2.Cu" "In3.Cu" "In4.Cu" "In5.Cu" "In6.Cu"
			"In7.Cu" "In8.Cu" "In9.Cu" "In10.Cu" "In11.Cu" "In12.Cu" "In13.Cu" "In14.Cu"
			"In15.Cu" "In16.Cu"
		)
		(hatch none 0.5)
		(connect_pads
			(clearance 0)
		)
		(min_thickness 0.25)
		(keepout
			(tracks not_allowed)
			(vias allowed)
			(pads allowed)
			(copperpour not_allowed)
			(footprints allowed)
		)
		(placement
			(enabled no)
			(sheetname "")
		)
		(fill
			(thermal_gap 0.5)
			(thermal_bridge_width 0.5)
			(island_removal_mode 0)
		)
		(polygon
			(pts
				(arc
					(start 127.397764 -289.807142)
					(mid 128.055624 -289.807142)
					(end 127.397764 -289.807142)
				)
			)
		)
	)
	(zone
		(layers "F.Cu" "B.Cu" "In1.Cu" "In2.Cu" "In3.Cu" "In4.Cu" "In5.Cu" "In6.Cu"
			"In7.Cu" "In8.Cu" "In9.Cu" "In10.Cu" "In11.Cu" "In12.Cu" "In13.Cu" "In14.Cu"
			"In15.Cu" "In16.Cu"
		)
		(hatch none 0.5)
		(connect_pads
			(clearance 0)
		)
		(min_thickness 0.25)
		(keepout
			(tracks not_allowed)
			(vias allowed)
			(pads allowed)
			(copperpour not_allowed)
			(footprints allowed)
		)
		(placement
			(enabled no)
			(sheetname "")
		)
		(fill
			(thermal_gap 0.5)
			(thermal_bridge_width 0.5)
			(island_removal_mode 0)
		)
		(polygon
			(pts
				(arc
					(start 114.629946 -221.231968)
					(mid 114.64963 -221.184558)
					(end 114.656362 -221.13367)
				)
				(arc
					(start 114.656362 -221.13367)
					(mid 114.598706 -220.994476)
					(end 114.459512 -220.93682)
				)
				(arc
					(start 114.459512 -220.93682)
					(mid 114.361081 -220.963236)
					(end 114.289078 -221.035372)
				)
				(arc
					(start 113.819432 -221.849442)
					(mid 113.799748 -221.896852)
					(end 113.793016 -221.94774)
				)
				(arc
					(start 113.793016 -221.94774)
					(mid 113.850672 -222.086934)
					(end 113.989866 -222.14459)
				)
				(arc
					(start 113.989866 -222.14459)
					(mid 114.088297 -222.118174)
					(end 114.1603 -222.046038)
				)
			)
		)
	)
	(zone
		(layers "F.Cu" "B.Cu" "In1.Cu" "In2.Cu" "In3.Cu" "In4.Cu" "In5.Cu" "In6.Cu"
			"In7.Cu" "In8.Cu" "In9.Cu" "In10.Cu" "In11.Cu" "In12.Cu" "In13.Cu" "In14.Cu"
			"In15.Cu" "In16.Cu"
		)
		(hatch none 0.5)
		(connect_pads
			(clearance 0)
		)
		(min_thickness 0.25)
		(keepout
			(tracks not_allowed)
			(vias allowed)
			(pads allowed)
			(copperpour not_allowed)
			(footprints allowed)
		)
		(placement
			(enabled no)
			(sheetname "")
		)
		(fill
			(thermal_gap 0.5)
			(thermal_bridge_width 0.5)
			(island_removal_mode 0)
		)
		(polygon
			(pts
				(arc
					(start 369.887246 -288.917126)
					(mid 369.229386 -288.917126)
					(end 369.887246 -288.917126)
				)
			)
		)
	)
	(zone
		(layers "F.Cu" "B.Cu" "In1.Cu" "In2.Cu" "In3.Cu" "In4.Cu" "In5.Cu" "In6.Cu"
			"In7.Cu" "In8.Cu" "In9.Cu" "In10.Cu" "In11.Cu" "In12.Cu" "In13.Cu" "In14.Cu"
			"In15.Cu" "In16.Cu"
		)
		(hatch none 0.5)
		(connect_pads
			(clearance 0)
		)
		(min_thickness 0.25)
		(keepout
			(tracks not_allowed)
			(vias allowed)
			(pads allowed)
			(copperpour not_allowed)
			(footprints allowed)
		)
		(placement
			(enabled no)
			(sheetname "")
		)
		(fill
			(thermal_gap 0.5)
			(thermal_bridge_width 0.5)
			(island_removal_mode 0)
		)
		(polygon
			(pts
				(arc
					(start 375.72696 -217.97645)
					(mid 375.746644 -217.92904)
					(end 375.753376 -217.878152)
				)
				(arc
					(start 375.753376 -217.878152)
					(mid 375.69572 -217.738958)
					(end 375.556526 -217.681302)
				)
				(arc
					(start 375.556526 -217.681302)
					(mid 375.458095 -217.707718)
					(end 375.386092 -217.779854)
				)
				(arc
					(start 374.916446 -218.593924)
					(mid 374.896762 -218.641334)
					(end 374.89003 -218.692222)
				)
				(arc
					(start 374.89003 -218.692222)
					(mid 374.947686 -218.831416)
					(end 375.08688 -218.889072)
				)
				(arc
					(start 375.08688 -218.889072)
					(mid 375.185311 -218.862656)
					(end 375.257314 -218.79052)
				)
			)
		)
	)
	(zone
		(layers "F.Cu" "B.Cu" "In1.Cu" "In2.Cu" "In3.Cu" "In4.Cu" "In5.Cu" "In6.Cu"
			"In7.Cu" "In8.Cu" "In9.Cu" "In10.Cu" "In11.Cu" "In12.Cu" "In13.Cu" "In14.Cu"
			"In15.Cu" "In16.Cu"
		)
		(hatch none 0.5)
		(connect_pads
			(clearance 0)
		)
		(min_thickness 0.25)
		(keepout
			(tracks not_allowed)
			(vias allowed)
			(pads allowed)
			(copperpour not_allowed)
			(footprints allowed)
		)
		(placement
			(enabled no)
			(sheetname "")
		)
		(fill
			(thermal_gap 0.5)
			(thermal_bridge_width 0.5)
			(island_removal_mode 0)
		)
		(polygon
			(pts
				(arc
					(start 368.83721 -220.319854)
					(mid 368.17935 -220.319854)
					(end 368.83721 -220.319854)
				)
			)
		)
	)
	(zone
		(layers "F.Cu" "B.Cu" "In1.Cu" "In2.Cu" "In3.Cu" "In4.Cu" "In5.Cu" "In6.Cu"
			"In7.Cu" "In8.Cu" "In9.Cu" "In10.Cu" "In11.Cu" "In12.Cu" "In13.Cu" "In14.Cu"
			"In15.Cu" "In16.Cu"
		)
		(hatch none 0.5)
		(connect_pads
			(clearance 0)
		)
		(min_thickness 0.25)
		(keepout
			(tracks not_allowed)
			(vias allowed)
			(pads allowed)
			(copperpour not_allowed)
			(footprints allowed)
		)
		(placement
			(enabled no)
			(sheetname "")
		)
		(fill
			(thermal_gap 0.5)
			(thermal_bridge_width 0.5)
			(island_removal_mode 0)
		)
		(polygon
			(pts
				(arc
					(start 114.788442 -214.622634)
					(mid 114.130582 -214.622634)
					(end 114.788442 -214.622634)
				)
			)
		)
	)
	(zone
		(layers "F.Cu" "B.Cu" "In1.Cu" "In2.Cu" "In3.Cu" "In4.Cu" "In5.Cu" "In6.Cu"
			"In7.Cu" "In8.Cu" "In9.Cu" "In10.Cu" "In11.Cu" "In12.Cu" "In13.Cu" "In14.Cu"
			"In15.Cu" "In16.Cu"
		)
		(hatch none 0.5)
		(connect_pads
			(clearance 0)
		)
		(min_thickness 0.25)
		(keepout
			(tracks not_allowed)
			(vias allowed)
			(pads allowed)
			(copperpour not_allowed)
			(footprints allowed)
		)
		(placement
			(enabled no)
			(sheetname "")
		)
		(fill
			(thermal_gap 0.5)
			(thermal_bridge_width 0.5)
			(island_removal_mode 0)
		)
		(polygon
			(pts
				(arc
					(start 111.341154 -220.22181)
					(mid 111.269165 -220.149651)
					(end 111.17072 -220.123258)
				)
				(arc
					(start 111.17072 -220.123258)
					(mid 111.031526 -220.180914)
					(end 110.97387 -220.320108)
				)
				(arc
					(start 110.97387 -220.320108)
					(mid 110.980627 -220.370989)
					(end 111.000286 -220.418406)
				)
				(arc
					(start 111.469932 -221.232222)
					(mid 111.541921 -221.304381)
					(end 111.640366 -221.330774)
				)
				(arc
					(start 111.640366 -221.330774)
					(mid 111.77956 -221.273118)
					(end 111.837216 -221.133924)
				)
				(arc
					(start 111.837216 -221.133924)
					(mid 111.830459 -221.083043)
					(end 111.8108 -221.035626)
				)
			)
		)
	)
	(zone
		(layers "F.Cu" "B.Cu" "In1.Cu" "In2.Cu" "In3.Cu" "In4.Cu" "In5.Cu" "In6.Cu"
			"In7.Cu" "In8.Cu" "In9.Cu" "In10.Cu" "In11.Cu" "In12.Cu" "In13.Cu" "In14.Cu"
			"In15.Cu" "In16.Cu"
		)
		(hatch none 0.5)
		(connect_pads
			(clearance 0)
		)
		(min_thickness 0.25)
		(keepout
			(tracks not_allowed)
			(vias allowed)
			(pads allowed)
			(copperpour not_allowed)
			(footprints allowed)
		)
		(placement
			(enabled no)
			(sheetname "")
		)
		(fill
			(thermal_gap 0.5)
			(thermal_bridge_width 0.5)
			(island_removal_mode 0)
		)
		(polygon
			(pts
				(arc
					(start 93.564964 -283.219906)
					(mid 94.222824 -283.219906)
					(end 93.564964 -283.219906)
				)
			)
		)
	)
	(zone
		(layers "F.Cu" "B.Cu" "In1.Cu" "In2.Cu" "In3.Cu" "In4.Cu" "In5.Cu" "In6.Cu"
			"In7.Cu" "In8.Cu" "In9.Cu" "In10.Cu" "In11.Cu" "In12.Cu" "In13.Cu" "In14.Cu"
			"In15.Cu" "In16.Cu"
		)
		(hatch none 0.5)
		(connect_pads
			(clearance 0)
		)
		(min_thickness 0.25)
		(keepout
			(tracks not_allowed)
			(vias allowed)
			(pads allowed)
			(copperpour not_allowed)
			(footprints allowed)
		)
		(placement
			(enabled no)
			(sheetname "")
		)
		(fill
			(thermal_gap 0.5)
			(thermal_bridge_width 0.5)
			(island_removal_mode 0)
		)
		(polygon
			(pts
				(arc
					(start 103.822246 -223.67367)
					(mid 103.84193 -223.62626)
					(end 103.848662 -223.575372)
				)
				(arc
					(start 103.848662 -223.575372)
					(mid 103.791006 -223.436178)
					(end 103.651812 -223.378522)
				)
				(arc
					(start 103.651812 -223.378522)
					(mid 103.553381 -223.404938)
					(end 103.481378 -223.477074)
				)
				(arc
					(start 103.011732 -224.291144)
					(mid 102.992048 -224.338554)
					(end 102.985316 -224.389442)
				)
				(arc
					(start 102.985316 -224.389442)
					(mid 103.042972 -224.528636)
					(end 103.182166 -224.586292)
				)
				(arc
					(start 103.182166 -224.586292)
					(mid 103.280597 -224.559876)
					(end 103.3526 -224.48774)
				)
			)
		)
	)
	(zone
		(layers "F.Cu" "B.Cu" "In1.Cu" "In2.Cu" "In3.Cu" "In4.Cu" "In5.Cu" "In6.Cu"
			"In7.Cu" "In8.Cu" "In9.Cu" "In10.Cu" "In11.Cu" "In12.Cu" "In13.Cu" "In14.Cu"
			"In15.Cu" "In16.Cu"
		)
		(hatch none 0.5)
		(connect_pads
			(clearance 0)
		)
		(min_thickness 0.25)
		(keepout
			(tracks not_allowed)
			(vias allowed)
			(pads allowed)
			(copperpour not_allowed)
			(footprints allowed)
		)
		(placement
			(enabled no)
			(sheetname "")
		)
		(fill
			(thermal_gap 0.5)
			(thermal_bridge_width 0.5)
			(island_removal_mode 0)
		)
		(polygon
			(pts
				(arc
					(start 106.172 -217.780108)
					(mid 106.100011 -217.707949)
					(end 106.001566 -217.681556)
				)
				(arc
					(start 106.001566 -217.681556)
					(mid 105.862372 -217.739212)
					(end 105.804716 -217.878406)
				)
				(arc
					(start 105.804716 -217.878406)
					(mid 105.811473 -217.929287)
					(end 105.831132 -217.976704)
				)
				(arc
					(start 106.300778 -218.79052)
					(mid 106.372767 -218.862679)
					(end 106.471212 -218.889072)
				)
				(arc
					(start 106.471212 -218.889072)
					(mid 106.610406 -218.831416)
					(end 106.668062 -218.692222)
				)
				(arc
					(start 106.668062 -218.692222)
					(mid 106.661305 -218.641341)
					(end 106.641646 -218.593924)
				)
			)
		)
	)
	(zone
		(layers "F.Cu" "B.Cu" "In1.Cu" "In2.Cu" "In3.Cu" "In4.Cu" "In5.Cu" "In6.Cu"
			"In7.Cu" "In8.Cu" "In9.Cu" "In10.Cu" "In11.Cu" "In12.Cu" "In13.Cu" "In14.Cu"
			"In15.Cu" "In16.Cu"
		)
		(hatch none 0.5)
		(connect_pads
			(clearance 0)
		)
		(min_thickness 0.25)
		(keepout
			(tracks not_allowed)
			(vias allowed)
			(pads allowed)
			(copperpour not_allowed)
			(footprints allowed)
		)
		(placement
			(enabled no)
			(sheetname "")
		)
		(fill
			(thermal_gap 0.5)
			(thermal_bridge_width 0.5)
			(island_removal_mode 0)
		)
		(polygon
			(pts
				(arc
					(start 404.011384 -18.744438)
					(mid 403.630384 -19.125438)
					(end 404.011384 -19.506438)
				)
				(arc
					(start 404.874984 -19.506438)
					(mid 405.255984 -19.125438)
					(end 404.874984 -18.744438)
				)
			)
		)
	)
	(zone
		(layers "F.Cu" "B.Cu" "In1.Cu" "In2.Cu" "In3.Cu" "In4.Cu" "In5.Cu" "In6.Cu"
			"In7.Cu" "In8.Cu" "In9.Cu" "In10.Cu" "In11.Cu" "In12.Cu" "In13.Cu" "In14.Cu"
			"In15.Cu" "In16.Cu"
		)
		(hatch none 0.5)
		(connect_pads
			(clearance 0)
		)
		(min_thickness 0.25)
		(keepout
			(tracks not_allowed)
			(vias allowed)
			(pads allowed)
			(copperpour not_allowed)
			(footprints allowed)
		)
		(placement
			(enabled no)
			(sheetname "")
		)
		(fill
			(thermal_gap 0.5)
			(thermal_bridge_width 0.5)
			(island_removal_mode 0)
		)
		(polygon
			(pts
				(arc
					(start 42.485564 -398.390872)
					(mid 42.104564 -398.771872)
					(end 42.485564 -399.152872)
				)
				(arc
					(start 43.349164 -399.152872)
					(mid 43.730164 -398.771872)
					(end 43.349164 -398.390872)
				)
			)
		)
	)
	(zone
		(layers "F.Cu" "B.Cu" "In1.Cu" "In2.Cu" "In3.Cu" "In4.Cu" "In5.Cu" "In6.Cu"
			"In7.Cu" "In8.Cu" "In9.Cu" "In10.Cu" "In11.Cu" "In12.Cu" "In13.Cu" "In14.Cu"
			"In15.Cu" "In16.Cu"
		)
		(hatch none 0.5)
		(connect_pads
			(clearance 0)
		)
		(min_thickness 0.25)
		(keepout
			(tracks not_allowed)
			(vias allowed)
			(pads allowed)
			(copperpour not_allowed)
			(footprints allowed)
		)
		(placement
			(enabled no)
			(sheetname "")
		)
		(fill
			(thermal_gap 0.5)
			(thermal_bridge_width 0.5)
			(island_removal_mode 0)
		)
		(polygon
			(pts
				(arc
					(start 345.889834 -84.77885)
					(mid 346.270834 -84.39785)
					(end 345.889834 -84.01685)
				)
				(arc
					(start 345.026234 -84.01685)
					(mid 344.645234 -84.39785)
					(end 345.026234 -84.77885)
				)
			)
		)
	)
	(zone
		(layers "F.Cu" "B.Cu" "In1.Cu" "In2.Cu" "In3.Cu" "In4.Cu" "In5.Cu" "In6.Cu"
			"In7.Cu" "In8.Cu" "In9.Cu" "In10.Cu" "In11.Cu" "In12.Cu" "In13.Cu" "In14.Cu"
			"In15.Cu" "In16.Cu"
		)
		(hatch none 0.5)
		(connect_pads
			(clearance 0)
		)
		(min_thickness 0.25)
		(keepout
			(tracks not_allowed)
			(vias allowed)
			(pads allowed)
			(copperpour not_allowed)
			(footprints allowed)
		)
		(placement
			(enabled no)
			(sheetname "")
		)
		(fill
			(thermal_gap 0.5)
			(thermal_bridge_width 0.5)
			(island_removal_mode 0)
		)
		(polygon
			(pts
				(arc
					(start 400.33829 -406.62352)
					(mid 399.95729 -407.00452)
					(end 400.33829 -407.38552)
				)
				(arc
					(start 401.20189 -407.38552)
					(mid 401.58289 -407.00452)
					(end 401.20189 -406.62352)
				)
			)
		)
	)
	(zone
		(layers "F.Cu" "B.Cu" "In1.Cu" "In2.Cu" "In3.Cu" "In4.Cu" "In5.Cu" "In6.Cu"
			"In7.Cu" "In8.Cu" "In9.Cu" "In10.Cu" "In11.Cu" "In12.Cu" "In13.Cu" "In14.Cu"
			"In15.Cu" "In16.Cu"
		)
		(hatch none 0.5)
		(connect_pads
			(clearance 0)
		)
		(min_thickness 0.25)
		(keepout
			(tracks not_allowed)
			(vias allowed)
			(pads allowed)
			(copperpour not_allowed)
			(footprints allowed)
		)
		(placement
			(enabled no)
			(sheetname "")
		)
		(fill
			(thermal_gap 0.5)
			(thermal_bridge_width 0.5)
			(island_removal_mode 0)
		)
		(polygon
			(pts
				(arc
					(start 118.859046 -223.67367)
					(mid 118.87873 -223.62626)
					(end 118.885462 -223.575372)
				)
				(arc
					(start 118.885462 -223.575372)
					(mid 118.827806 -223.436178)
					(end 118.688612 -223.378522)
				)
				(arc
					(start 118.688612 -223.378522)
					(mid 118.590181 -223.404938)
					(end 118.518178 -223.477074)
				)
				(arc
					(start 118.048532 -224.291144)
					(mid 118.028848 -224.338554)
					(end 118.022116 -224.389442)
				)
				(arc
					(start 118.022116 -224.389442)
					(mid 118.079772 -224.528636)
					(end 118.218966 -224.586292)
				)
				(arc
					(start 118.218966 -224.586292)
					(mid 118.317397 -224.559876)
					(end 118.3894 -224.48774)
				)
			)
		)
	)
	(zone
		(layers "F.Cu" "B.Cu" "In1.Cu" "In2.Cu" "In3.Cu" "In4.Cu" "In5.Cu" "In6.Cu"
			"In7.Cu" "In8.Cu" "In9.Cu" "In10.Cu" "In11.Cu" "In12.Cu" "In13.Cu" "In14.Cu"
			"In15.Cu" "In16.Cu"
		)
		(hatch none 0.5)
		(connect_pads
			(clearance 0)
		)
		(min_thickness 0.25)
		(keepout
			(tracks not_allowed)
			(vias allowed)
			(pads allowed)
			(copperpour not_allowed)
			(footprints allowed)
		)
		(placement
			(enabled no)
			(sheetname "")
		)
		(fill
			(thermal_gap 0.5)
			(thermal_bridge_width 0.5)
			(island_removal_mode 0)
		)
		(polygon
			(pts
				(arc
					(start 355.521514 -217.162634)
					(mid 355.541198 -217.115224)
					(end 355.54793 -217.064336)
				)
				(arc
					(start 355.54793 -217.064336)
					(mid 355.490274 -216.925142)
					(end 355.35108 -216.867486)
				)
				(arc
					(start 355.35108 -216.867486)
					(mid 355.252649 -216.893902)
					(end 355.180646 -216.966038)
				)
				(arc
					(start 354.711 -217.780108)
					(mid 354.691316 -217.827518)
					(end 354.684584 -217.878406)
				)
				(arc
					(start 354.684584 -217.878406)
					(mid 354.74224 -218.0176)
					(end 354.881434 -218.075256)
				)
				(arc
					(start 354.881434 -218.075256)
					(mid 354.979865 -218.04884)
					(end 355.051868 -217.976704)
				)
			)
		)
	)
	(zone
		(layers "F.Cu" "B.Cu" "In1.Cu" "In2.Cu" "In3.Cu" "In4.Cu" "In5.Cu" "In6.Cu"
			"In7.Cu" "In8.Cu" "In9.Cu" "In10.Cu" "In11.Cu" "In12.Cu" "In13.Cu" "In14.Cu"
			"In15.Cu" "In16.Cu"
		)
		(hatch none 0.5)
		(connect_pads
			(clearance 0)
		)
		(min_thickness 0.25)
		(keepout
			(tracks not_allowed)
			(vias allowed)
			(pads allowed)
			(copperpour not_allowed)
			(footprints allowed)
		)
		(placement
			(enabled no)
			(sheetname "")
		)
		(fill
			(thermal_gap 0.5)
			(thermal_bridge_width 0.5)
			(island_removal_mode 0)
		)
		(polygon
			(pts
				(arc
					(start 67.705478 -406.62352)
					(mid 67.324478 -407.00452)
					(end 67.705478 -407.38552)
				)
				(arc
					(start 68.569078 -407.38552)
					(mid 68.950078 -407.00452)
					(end 68.569078 -406.62352)
				)
			)
		)
	)
	(zone
		(layers "F.Cu" "B.Cu" "In1.Cu" "In2.Cu" "In3.Cu" "In4.Cu" "In5.Cu" "In6.Cu"
			"In7.Cu" "In8.Cu" "In9.Cu" "In10.Cu" "In11.Cu" "In12.Cu" "In13.Cu" "In14.Cu"
			"In15.Cu" "In16.Cu"
		)
		(hatch none 0.5)
		(connect_pads
			(clearance 0)
		)
		(min_thickness 0.25)
		(keepout
			(tracks not_allowed)
			(vias allowed)
			(pads allowed)
			(copperpour not_allowed)
			(footprints allowed)
		)
		(placement
			(enabled no)
			(sheetname "")
		)
		(fill
			(thermal_gap 0.5)
			(thermal_bridge_width 0.5)
			(island_removal_mode 0)
		)
		(polygon
			(pts
				(arc
					(start 347.22181 -221.94774)
					(mid 346.56395 -221.94774)
					(end 347.22181 -221.94774)
				)
			)
		)
	)
	(zone
		(layers "F.Cu" "B.Cu" "In1.Cu" "In2.Cu" "In3.Cu" "In4.Cu" "In5.Cu" "In6.Cu"
			"In7.Cu" "In8.Cu" "In9.Cu" "In10.Cu" "In11.Cu" "In12.Cu" "In13.Cu" "In14.Cu"
			"In15.Cu" "In16.Cu"
		)
		(hatch none 0.5)
		(connect_pads
			(clearance 0)
		)
		(min_thickness 0.25)
		(keepout
			(tracks not_allowed)
			(vias allowed)
			(pads allowed)
			(copperpour not_allowed)
			(footprints allowed)
		)
		(placement
			(enabled no)
			(sheetname "")
		)
		(fill
			(thermal_gap 0.5)
			(thermal_bridge_width 0.5)
			(island_removal_mode 0)
		)
		(polygon
			(pts
				(arc
					(start 354.221796 -281.493468)
					(mid 354.149807 -281.421309)
					(end 354.051362 -281.394916)
				)
				(arc
					(start 354.051362 -281.394916)
					(mid 353.912168 -281.452572)
					(end 353.854512 -281.591766)
				)
				(arc
					(start 353.854512 -281.591766)
					(mid 353.861269 -281.642647)
					(end 353.880928 -281.690064)
				)
				(arc
					(start 354.350828 -282.504134)
					(mid 354.422817 -282.576293)
					(end 354.521262 -282.602686)
				)
				(arc
					(start 354.521262 -282.602686)
					(mid 354.660456 -282.54503)
					(end 354.718112 -282.405836)
				)
				(arc
					(start 354.718112 -282.405836)
					(mid 354.711355 -282.354955)
					(end 354.691696 -282.307538)
				)
			)
		)
	)
	(zone
		(layers "F.Cu" "B.Cu" "In1.Cu" "In2.Cu" "In3.Cu" "In4.Cu" "In5.Cu" "In6.Cu"
			"In7.Cu" "In8.Cu" "In9.Cu" "In10.Cu" "In11.Cu" "In12.Cu" "In13.Cu" "In14.Cu"
			"In15.Cu" "In16.Cu"
		)
		(hatch none 0.5)
		(connect_pads
			(clearance 0)
		)
		(min_thickness 0.25)
		(keepout
			(tracks not_allowed)
			(vias allowed)
			(pads allowed)
			(copperpour not_allowed)
			(footprints allowed)
		)
		(placement
			(enabled no)
			(sheetname "")
		)
		(fill
			(thermal_gap 0.5)
			(thermal_bridge_width 0.5)
			(island_removal_mode 0)
		)
		(polygon
			(pts
				(arc
					(start 94.035118 -288.917126)
					(mid 94.692978 -288.917126)
					(end 94.035118 -288.917126)
				)
			)
		)
	)
	(zone
		(layers "F.Cu" "B.Cu" "In1.Cu" "In2.Cu" "In3.Cu" "In4.Cu" "In5.Cu" "In6.Cu"
			"In7.Cu" "In8.Cu" "In9.Cu" "In10.Cu" "In11.Cu" "In12.Cu" "In13.Cu" "In14.Cu"
			"In15.Cu" "In16.Cu"
		)
		(hatch none 0.5)
		(connect_pads
			(clearance 0)
		)
		(min_thickness 0.25)
		(keepout
			(tracks not_allowed)
			(vias allowed)
			(pads allowed)
			(copperpour not_allowed)
			(footprints allowed)
		)
		(placement
			(enabled no)
			(sheetname "")
		)
		(fill
			(thermal_gap 0.5)
			(thermal_bridge_width 0.5)
			(island_removal_mode 0)
		)
		(polygon
			(pts
				(arc
					(start 356.150164 -224.389442)
					(mid 355.492304 -224.389442)
					(end 356.150164 -224.389442)
				)
			)
		)
	)
	(zone
		(layers "F.Cu" "B.Cu" "In1.Cu" "In2.Cu" "In3.Cu" "In4.Cu" "In5.Cu" "In6.Cu"
			"In7.Cu" "In8.Cu" "In9.Cu" "In10.Cu" "In11.Cu" "In12.Cu" "In13.Cu" "In14.Cu"
			"In15.Cu" "In16.Cu"
		)
		(hatch none 0.5)
		(connect_pads
			(clearance 0)
		)
		(min_thickness 0.25)
		(keepout
			(tracks not_allowed)
			(vias allowed)
			(pads allowed)
			(copperpour not_allowed)
			(footprints allowed)
		)
		(placement
			(enabled no)
			(sheetname "")
		)
		(fill
			(thermal_gap 0.5)
			(thermal_bridge_width 0.5)
			(island_removal_mode 0)
		)
		(polygon
			(pts
				(arc
					(start 344.013028 -285.563056)
					(mid 343.993344 -285.610466)
					(end 343.986612 -285.661354)
				)
				(arc
					(start 343.986612 -285.661354)
					(mid 344.044268 -285.800548)
					(end 344.183462 -285.858204)
				)
				(arc
					(start 344.183462 -285.858204)
					(mid 344.281893 -285.831788)
					(end 344.353896 -285.759652)
				)
				(arc
					(start 344.823796 -284.945582)
					(mid 344.84348 -284.898172)
					(end 344.850212 -284.847284)
				)
				(arc
					(start 344.850212 -284.847284)
					(mid 344.792556 -284.70809)
					(end 344.653362 -284.650434)
				)
				(arc
					(start 344.653362 -284.650434)
					(mid 344.554931 -284.67685)
					(end 344.482928 -284.748986)
				)
			)
		)
	)
	(zone
		(layers "F.Cu" "B.Cu" "In1.Cu" "In2.Cu" "In3.Cu" "In4.Cu" "In5.Cu" "In6.Cu"
			"In7.Cu" "In8.Cu" "In9.Cu" "In10.Cu" "In11.Cu" "In12.Cu" "In13.Cu" "In14.Cu"
			"In15.Cu" "In16.Cu"
		)
		(hatch none 0.5)
		(connect_pads
			(clearance 0)
		)
		(min_thickness 0.25)
		(keepout
			(tracks not_allowed)
			(vias allowed)
			(pads allowed)
			(copperpour not_allowed)
			(footprints allowed)
		)
		(placement
			(enabled no)
			(sheetname "")
		)
		(fill
			(thermal_gap 0.5)
			(thermal_bridge_width 0.5)
			(island_removal_mode 0)
		)
		(polygon
			(pts
				(arc
					(start 339.233764 -217.878406)
					(mid 338.575904 -217.878406)
					(end 339.233764 -217.878406)
				)
			)
		)
	)
	(zone
		(layers "F.Cu" "B.Cu" "In1.Cu" "In2.Cu" "In3.Cu" "In4.Cu" "In5.Cu" "In6.Cu"
			"In7.Cu" "In8.Cu" "In9.Cu" "In10.Cu" "In11.Cu" "In12.Cu" "In13.Cu" "In14.Cu"
			"In15.Cu" "In16.Cu"
		)
		(hatch none 0.5)
		(connect_pads
			(clearance 0)
		)
		(min_thickness 0.25)
		(keepout
			(tracks not_allowed)
			(vias allowed)
			(pads allowed)
			(copperpour not_allowed)
			(footprints allowed)
		)
		(placement
			(enabled no)
			(sheetname "")
		)
		(fill
			(thermal_gap 0.5)
			(thermal_bridge_width 0.5)
			(island_removal_mode 0)
		)
		(polygon
			(pts
				(arc
					(start 378.345192 -285.661354)
					(mid 377.687332 -285.661354)
					(end 378.345192 -285.661354)
				)
			)
		)
	)
	(zone
		(layers "F.Cu" "B.Cu" "In1.Cu" "In2.Cu" "In3.Cu" "In4.Cu" "In5.Cu" "In6.Cu"
			"In7.Cu" "In8.Cu" "In9.Cu" "In10.Cu" "In11.Cu" "In12.Cu" "In13.Cu" "In14.Cu"
			"In15.Cu" "In16.Cu"
		)
		(hatch none 0.5)
		(connect_pads
			(clearance 0)
		)
		(min_thickness 0.25)
		(keepout
			(tracks not_allowed)
			(vias allowed)
			(pads allowed)
			(copperpour not_allowed)
			(footprints allowed)
		)
		(placement
			(enabled no)
			(sheetname "")
		)
		(fill
			(thermal_gap 0.5)
			(thermal_bridge_width 0.5)
			(island_removal_mode 0)
		)
		(polygon
			(pts
				(arc
					(start 352.172016 -276.511766)
					(mid 351.975166 -276.708616)
					(end 352.172016 -276.905466)
				)
				(arc
					(start 353.111816 -276.905466)
					(mid 353.308666 -276.708616)
					(end 353.111816 -276.511766)
				)
			)
		)
	)
	(zone
		(layers "F.Cu" "B.Cu" "In1.Cu" "In2.Cu" "In3.Cu" "In4.Cu" "In5.Cu" "In6.Cu"
			"In7.Cu" "In8.Cu" "In9.Cu" "In10.Cu" "In11.Cu" "In12.Cu" "In13.Cu" "In14.Cu"
			"In15.Cu" "In16.Cu"
		)
		(hatch none 0.5)
		(connect_pads
			(clearance 0)
		)
		(min_thickness 0.25)
		(keepout
			(tracks not_allowed)
			(vias allowed)
			(pads allowed)
			(copperpour not_allowed)
			(footprints allowed)
		)
		(placement
			(enabled no)
			(sheetname "")
		)
		(fill
			(thermal_gap 0.5)
			(thermal_bridge_width 0.5)
			(island_removal_mode 0)
		)
		(polygon
			(pts
				(arc
					(start 328.486008 -403.502876)
					(mid 328.105008 -403.883876)
					(end 328.486008 -404.264876)
				)
				(arc
					(start 329.349608 -404.264876)
					(mid 329.730608 -403.883876)
					(end 329.349608 -403.502876)
				)
			)
		)
	)
	(zone
		(layers "F.Cu" "B.Cu" "In1.Cu" "In2.Cu" "In3.Cu" "In4.Cu" "In5.Cu" "In6.Cu"
			"In7.Cu" "In8.Cu" "In9.Cu" "In10.Cu" "In11.Cu" "In12.Cu" "In13.Cu" "In14.Cu"
			"In15.Cu" "In16.Cu"
		)
		(hatch none 0.5)
		(connect_pads
			(clearance 0)
		)
		(min_thickness 0.25)
		(keepout
			(tracks not_allowed)
			(vias allowed)
			(pads allowed)
			(copperpour not_allowed)
			(footprints allowed)
		)
		(placement
			(enabled no)
			(sheetname "")
		)
		(fill
			(thermal_gap 0.5)
			(thermal_bridge_width 0.5)
			(island_removal_mode 0)
		)
		(polygon
			(pts
				(arc
					(start 119.487188 -214.622634)
					(mid 118.829328 -214.622634)
					(end 119.487188 -214.622634)
				)
			)
		)
	)
	(zone
		(layers "F.Cu" "B.Cu" "In1.Cu" "In2.Cu" "In3.Cu" "In4.Cu" "In5.Cu" "In6.Cu"
			"In7.Cu" "In8.Cu" "In9.Cu" "In10.Cu" "In11.Cu" "In12.Cu" "In13.Cu" "In14.Cu"
			"In15.Cu" "In16.Cu"
		)
		(hatch none 0.5)
		(connect_pads
			(clearance 0)
		)
		(min_thickness 0.25)
		(keepout
			(tracks not_allowed)
			(vias allowed)
			(pads allowed)
			(copperpour not_allowed)
			(footprints allowed)
		)
		(placement
			(enabled no)
			(sheetname "")
		)
		(fill
			(thermal_gap 0.5)
			(thermal_bridge_width 0.5)
			(island_removal_mode 0)
		)
		(polygon
			(pts
				(arc
					(start 104.560878 -284.847538)
					(mid 103.903018 -284.847538)
					(end 104.560878 -284.847538)
				)
			)
		)
	)
	(zone
		(layers "F.Cu" "B.Cu" "In1.Cu" "In2.Cu" "In3.Cu" "In4.Cu" "In5.Cu" "In6.Cu"
			"In7.Cu" "In8.Cu" "In9.Cu" "In10.Cu" "In11.Cu" "In12.Cu" "In13.Cu" "In14.Cu"
			"In15.Cu" "In16.Cu"
		)
		(hatch none 0.5)
		(connect_pads
			(clearance 0)
		)
		(min_thickness 0.25)
		(keepout
			(tracks not_allowed)
			(vias allowed)
			(pads allowed)
			(copperpour not_allowed)
			(footprints allowed)
		)
		(placement
			(enabled no)
			(sheetname "")
		)
		(fill
			(thermal_gap 0.5)
			(thermal_bridge_width 0.5)
			(island_removal_mode 0)
		)
		(polygon
			(pts
				(arc
					(start 340.424008 -0.048006)
					(mid 340.805008 -0.429006)
					(end 341.186008 -0.048006)
				)
				(arc
					(start 341.186008 0.815594)
					(mid 340.805008 1.196594)
					(end 340.424008 0.815594)
				)
			)
		)
	)
	(zone
		(layers "F.Cu" "B.Cu" "In1.Cu" "In2.Cu" "In3.Cu" "In4.Cu" "In5.Cu" "In6.Cu"
			"In7.Cu" "In8.Cu" "In9.Cu" "In10.Cu" "In11.Cu" "In12.Cu" "In13.Cu" "In14.Cu"
			"In15.Cu" "In16.Cu"
		)
		(hatch none 0.5)
		(connect_pads
			(clearance 0)
		)
		(min_thickness 0.25)
		(keepout
			(tracks not_allowed)
			(vias allowed)
			(pads allowed)
			(copperpour not_allowed)
			(footprints allowed)
		)
		(placement
			(enabled no)
			(sheetname "")
		)
		(fill
			(thermal_gap 0.5)
			(thermal_bridge_width 0.5)
			(island_removal_mode 0)
		)
		(polygon
			(pts
				(arc
					(start 118.859554 -220.22181)
					(mid 118.787565 -220.149651)
					(end 118.68912 -220.123258)
				)
				(arc
					(start 118.68912 -220.123258)
					(mid 118.549926 -220.180914)
					(end 118.49227 -220.320108)
				)
				(arc
					(start 118.49227 -220.320108)
					(mid 118.499027 -220.370989)
					(end 118.518686 -220.418406)
				)
				(arc
					(start 118.988332 -221.232222)
					(mid 119.060321 -221.304381)
					(end 119.158766 -221.330774)
				)
				(arc
					(start 119.158766 -221.330774)
					(mid 119.29796 -221.273118)
					(end 119.355616 -221.133924)
				)
				(arc
					(start 119.355616 -221.133924)
					(mid 119.348859 -221.083043)
					(end 119.3292 -221.035626)
				)
			)
		)
	)
	(zone
		(layers "F.Cu" "B.Cu" "In1.Cu" "In2.Cu" "In3.Cu" "In4.Cu" "In5.Cu" "In6.Cu"
			"In7.Cu" "In8.Cu" "In9.Cu" "In10.Cu" "In11.Cu" "In12.Cu" "In13.Cu" "In14.Cu"
			"In15.Cu" "In16.Cu"
		)
		(hatch none 0.5)
		(connect_pads
			(clearance 0)
		)
		(min_thickness 0.25)
		(keepout
			(tracks not_allowed)
			(vias allowed)
			(pads allowed)
			(copperpour not_allowed)
			(footprints allowed)
		)
		(placement
			(enabled no)
			(sheetname "")
		)
		(fill
			(thermal_gap 0.5)
			(thermal_bridge_width 0.5)
			(island_removal_mode 0)
		)
		(polygon
			(pts
				(arc
					(start 402.05533 -403.502876)
					(mid 401.67433 -403.883876)
					(end 402.05533 -404.264876)
				)
				(arc
					(start 402.91893 -404.264876)
					(mid 403.29993 -403.883876)
					(end 402.91893 -403.502876)
				)
			)
		)
	)
	(zone
		(layers "F.Cu" "B.Cu" "In1.Cu" "In2.Cu" "In3.Cu" "In4.Cu" "In5.Cu" "In6.Cu"
			"In7.Cu" "In8.Cu" "In9.Cu" "In10.Cu" "In11.Cu" "In12.Cu" "In13.Cu" "In14.Cu"
			"In15.Cu" "In16.Cu"
		)
		(hatch none 0.5)
		(connect_pads
			(clearance 0)
		)
		(min_thickness 0.25)
		(keepout
			(tracks not_allowed)
			(vias allowed)
			(pads allowed)
			(copperpour not_allowed)
			(footprints allowed)
		)
		(placement
			(enabled no)
			(sheetname "")
		)
		(fill
			(thermal_gap 0.5)
			(thermal_bridge_width 0.5)
			(island_removal_mode 0)
		)
		(polygon
			(pts
				(arc
					(start 375.526046 -288.917126)
					(mid 374.868186 -288.917126)
					(end 375.526046 -288.917126)
				)
			)
		)
	)
	(zone
		(layers "F.Cu" "B.Cu" "In1.Cu" "In2.Cu" "In3.Cu" "In4.Cu" "In5.Cu" "In6.Cu"
			"In7.Cu" "In8.Cu" "In9.Cu" "In10.Cu" "In11.Cu" "In12.Cu" "In13.Cu" "In14.Cu"
			"In15.Cu" "In16.Cu"
		)
		(hatch none 0.5)
		(connect_pads
			(clearance 0)
		)
		(min_thickness 0.25)
		(keepout
			(tracks not_allowed)
			(vias allowed)
			(pads allowed)
			(copperpour not_allowed)
			(footprints allowed)
		)
		(placement
			(enabled no)
			(sheetname "")
		)
		(fill
			(thermal_gap 0.5)
			(thermal_bridge_width 0.5)
			(island_removal_mode 0)
		)
		(polygon
			(pts
				(arc
					(start 102.493064 -285.661354)
					(mid 103.150924 -285.661354)
					(end 102.493064 -285.661354)
				)
			)
		)
	)
	(zone
		(layers "F.Cu" "B.Cu" "In1.Cu" "In2.Cu" "In3.Cu" "In4.Cu" "In5.Cu" "In6.Cu"
			"In7.Cu" "In8.Cu" "In9.Cu" "In10.Cu" "In11.Cu" "In12.Cu" "In13.Cu" "In14.Cu"
			"In15.Cu" "In16.Cu"
		)
		(hatch none 0.5)
		(connect_pads
			(clearance 0)
		)
		(min_thickness 0.25)
		(keepout
			(tracks not_allowed)
			(vias allowed)
			(pads allowed)
			(copperpour not_allowed)
			(footprints allowed)
		)
		(placement
			(enabled no)
			(sheetname "")
		)
		(fill
			(thermal_gap 0.5)
			(thermal_bridge_width 0.5)
			(island_removal_mode 0)
		)
		(polygon
			(pts
				(arc
					(start 352.86061 -225.203258)
					(mid 352.20275 -225.203258)
					(end 352.86061 -225.203258)
				)
			)
		)
	)
	(zone
		(layers "F.Cu" "B.Cu" "In1.Cu" "In2.Cu" "In3.Cu" "In4.Cu" "In5.Cu" "In6.Cu"
			"In7.Cu" "In8.Cu" "In9.Cu" "In10.Cu" "In11.Cu" "In12.Cu" "In13.Cu" "In14.Cu"
			"In15.Cu" "In16.Cu"
		)
		(hatch none 0.5)
		(connect_pads
			(clearance 0)
		)
		(min_thickness 0.25)
		(keepout
			(tracks not_allowed)
			(vias allowed)
			(pads allowed)
			(copperpour not_allowed)
			(footprints allowed)
		)
		(placement
			(enabled no)
			(sheetname "")
		)
		(fill
			(thermal_gap 0.5)
			(thermal_bridge_width 0.5)
			(island_removal_mode 0)
		)
		(polygon
			(pts
				(arc
					(start 340.424008 5.031994)
					(mid 340.805008 4.650994)
					(end 341.186008 5.031994)
				)
				(arc
					(start 341.186008 5.895594)
					(mid 340.805008 6.276594)
					(end 340.424008 5.895594)
				)
			)
		)
	)
	(zone
		(layers "F.Cu" "B.Cu" "In1.Cu" "In2.Cu" "In3.Cu" "In4.Cu" "In5.Cu" "In6.Cu"
			"In7.Cu" "In8.Cu" "In9.Cu" "In10.Cu" "In11.Cu" "In12.Cu" "In13.Cu" "In14.Cu"
			"In15.Cu" "In16.Cu"
		)
		(hatch none 0.5)
		(connect_pads
			(clearance 0)
		)
		(min_thickness 0.25)
		(keepout
			(tracks not_allowed)
			(vias allowed)
			(pads allowed)
			(copperpour not_allowed)
			(footprints allowed)
		)
		(placement
			(enabled no)
			(sheetname "")
		)
		(fill
			(thermal_gap 0.5)
			(thermal_bridge_width 0.5)
			(island_removal_mode 0)
		)
		(polygon
			(pts
				(arc
					(start 103.322882 -220.319854)
					(mid 103.980742 -220.319854)
					(end 103.322882 -220.319854)
				)
			)
		)
	)
	(zone
		(layers "F.Cu" "B.Cu" "In1.Cu" "In2.Cu" "In3.Cu" "In4.Cu" "In5.Cu" "In6.Cu"
			"In7.Cu" "In8.Cu" "In9.Cu" "In10.Cu" "In11.Cu" "In12.Cu" "In13.Cu" "In14.Cu"
			"In15.Cu" "In16.Cu"
		)
		(hatch none 0.5)
		(connect_pads
			(clearance 0)
		)
		(min_thickness 0.25)
		(keepout
			(tracks not_allowed)
			(vias allowed)
			(pads allowed)
			(copperpour not_allowed)
			(footprints allowed)
		)
		(placement
			(enabled no)
			(sheetname "")
		)
		(fill
			(thermal_gap 0.5)
			(thermal_bridge_width 0.5)
			(island_removal_mode 0)
		)
		(polygon
			(pts
				(arc
					(start 414.30829 -403.502876)
					(mid 413.92729 -403.883876)
					(end 414.30829 -404.264876)
				)
				(arc
					(start 415.17189 -404.264876)
					(mid 415.55289 -403.883876)
					(end 415.17189 -403.502876)
				)
			)
		)
	)
	(zone
		(layers "F.Cu" "B.Cu" "In1.Cu" "In2.Cu" "In3.Cu" "In4.Cu" "In5.Cu" "In6.Cu"
			"In7.Cu" "In8.Cu" "In9.Cu" "In10.Cu" "In11.Cu" "In12.Cu" "In13.Cu" "In14.Cu"
			"In15.Cu" "In16.Cu"
		)
		(hatch none 0.5)
		(connect_pads
			(clearance 0)
		)
		(min_thickness 0.25)
		(keepout
			(tracks not_allowed)
			(vias allowed)
			(pads allowed)
			(copperpour not_allowed)
			(footprints allowed)
		)
		(placement
			(enabled no)
			(sheetname "")
		)
		(fill
			(thermal_gap 0.5)
			(thermal_bridge_width 0.5)
			(island_removal_mode 0)
		)
		(polygon
			(pts
				(arc
					(start 123.168918 -288.917126)
					(mid 123.826778 -288.917126)
					(end 123.168918 -288.917126)
				)
			)
		)
	)
	(zone
		(layers "F.Cu" "B.Cu" "In1.Cu" "In2.Cu" "In3.Cu" "In4.Cu" "In5.Cu" "In6.Cu"
			"In7.Cu" "In8.Cu" "In9.Cu" "In10.Cu" "In11.Cu" "In12.Cu" "In13.Cu" "In14.Cu"
			"In15.Cu" "In16.Cu"
		)
		(hatch none 0.5)
		(connect_pads
			(clearance 0)
		)
		(min_thickness 0.25)
		(keepout
			(tracks not_allowed)
			(vias allowed)
			(pads allowed)
			(copperpour not_allowed)
			(footprints allowed)
		)
		(placement
			(enabled no)
			(sheetname "")
		)
		(fill
			(thermal_gap 0.5)
			(thermal_bridge_width 0.5)
			(island_removal_mode 0)
		)
		(polygon
			(pts
				(arc
					(start 128.359662 -289.003232)
					(mid 128.375586 -288.961481)
					(end 128.380998 -288.917126)
				)
				(arc
					(start 128.380998 -288.917126)
					(mid 128.327062 -288.786912)
					(end 128.196848 -288.732976)
				)
				(arc
					(start 128.196848 -288.732976)
					(mid 128.101828 -288.759384)
					(end 128.034034 -288.83102)
				)
				(arc
					(start 127.56388 -289.721036)
					(mid 127.547956 -289.762787)
					(end 127.542544 -289.807142)
				)
				(arc
					(start 127.542544 -289.807142)
					(mid 127.59648 -289.937356)
					(end 127.726694 -289.991292)
				)
				(arc
					(start 127.726694 -289.991292)
					(mid 127.821714 -289.964884)
					(end 127.889508 -289.893248)
				)
			)
		)
	)
	(zone
		(layers "F.Cu" "B.Cu" "In1.Cu" "In2.Cu" "In3.Cu" "In4.Cu" "In5.Cu" "In6.Cu"
			"In7.Cu" "In8.Cu" "In9.Cu" "In10.Cu" "In11.Cu" "In12.Cu" "In13.Cu" "In14.Cu"
			"In15.Cu" "In16.Cu"
		)
		(hatch none 0.5)
		(connect_pads
			(clearance 0)
		)
		(min_thickness 0.25)
		(keepout
			(tracks not_allowed)
			(vias allowed)
			(pads allowed)
			(copperpour not_allowed)
			(footprints allowed)
		)
		(placement
			(enabled no)
			(sheetname "")
		)
		(fill
			(thermal_gap 0.5)
			(thermal_bridge_width 0.5)
			(island_removal_mode 0)
		)
		(polygon
			(pts
				(arc
					(start 366.487964 -221.133924)
					(mid 365.830104 -221.133924)
					(end 366.487964 -221.133924)
				)
			)
		)
	)
	(zone
		(layers "F.Cu" "B.Cu" "In1.Cu" "In2.Cu" "In3.Cu" "In4.Cu" "In5.Cu" "In6.Cu"
			"In7.Cu" "In8.Cu" "In9.Cu" "In10.Cu" "In11.Cu" "In12.Cu" "In13.Cu" "In14.Cu"
			"In15.Cu" "In16.Cu"
		)
		(hatch none 0.5)
		(connect_pads
			(clearance 0)
		)
		(min_thickness 0.25)
		(keepout
			(tracks not_allowed)
			(vias allowed)
			(pads allowed)
			(copperpour not_allowed)
			(footprints allowed)
		)
		(placement
			(enabled no)
			(sheetname "")
		)
		(fill
			(thermal_gap 0.5)
			(thermal_bridge_width 0.5)
			(island_removal_mode 0)
		)
		(polygon
			(pts
				(arc
					(start 94.582742 -217.064336)
					(mid 93.924882 -217.064336)
					(end 94.582742 -217.064336)
				)
			)
		)
	)
	(zone
		(layers "F.Cu" "B.Cu" "In1.Cu" "In2.Cu" "In3.Cu" "In4.Cu" "In5.Cu" "In6.Cu"
			"In7.Cu" "In8.Cu" "In9.Cu" "In10.Cu" "In11.Cu" "In12.Cu" "In13.Cu" "In14.Cu"
			"In15.Cu" "In16.Cu"
		)
		(hatch none 0.5)
		(connect_pads
			(clearance 0)
		)
		(min_thickness 0.25)
		(keepout
			(tracks not_allowed)
			(vias allowed)
			(pads allowed)
			(copperpour not_allowed)
			(footprints allowed)
		)
		(placement
			(enabled no)
			(sheetname "")
		)
		(fill
			(thermal_gap 0.5)
			(thermal_bridge_width 0.5)
			(island_removal_mode 0)
		)
		(polygon
			(pts
				(arc
					(start 379.956822 -220.22181)
					(mid 379.884833 -220.149651)
					(end 379.786388 -220.123258)
				)
				(arc
					(start 379.786388 -220.123258)
					(mid 379.647194 -220.180914)
					(end 379.589538 -220.320108)
				)
				(arc
					(start 379.589538 -220.320108)
					(mid 379.596295 -220.370989)
					(end 379.615954 -220.418406)
				)
				(arc
					(start 380.0856 -221.232222)
					(mid 380.157589 -221.304381)
					(end 380.256034 -221.330774)
				)
				(arc
					(start 380.256034 -221.330774)
					(mid 380.395228 -221.273118)
					(end 380.452884 -221.133924)
				)
				(arc
					(start 380.452884 -221.133924)
					(mid 380.446127 -221.083043)
					(end 380.426468 -221.035626)
				)
			)
		)
	)
	(zone
		(layers "F.Cu" "B.Cu" "In1.Cu" "In2.Cu" "In3.Cu" "In4.Cu" "In5.Cu" "In6.Cu"
			"In7.Cu" "In8.Cu" "In9.Cu" "In10.Cu" "In11.Cu" "In12.Cu" "In13.Cu" "In14.Cu"
			"In15.Cu" "In16.Cu"
		)
		(hatch none 0.5)
		(connect_pads
			(clearance 0)
		)
		(min_thickness 0.25)
		(keepout
			(tracks not_allowed)
			(vias allowed)
			(pads allowed)
			(copperpour not_allowed)
			(footprints allowed)
		)
		(placement
			(enabled no)
			(sheetname "")
		)
		(fill
			(thermal_gap 0.5)
			(thermal_bridge_width 0.5)
			(island_removal_mode 0)
		)
		(polygon
			(pts
				(arc
					(start 135.309102 -214.454486)
					(mid 135.236681 -214.377879)
					(end 135.135112 -214.349584)
				)
				(arc
					(start 135.135112 -214.349584)
					(mid 134.995918 -214.40724)
					(end 134.938262 -214.546434)
				)
				(arc
					(start 134.938262 -214.546434)
					(mid 134.944049 -214.593815)
					(end 134.961122 -214.638382)
				)
				(arc
					(start 135.431022 -215.528652)
					(mid 135.503443 -215.605259)
					(end 135.605012 -215.633554)
				)
				(arc
					(start 135.605012 -215.633554)
					(mid 135.744206 -215.575898)
					(end 135.801862 -215.436704)
				)
				(arc
					(start 135.801862 -215.436704)
					(mid 135.796075 -215.389323)
					(end 135.779002 -215.344756)
				)
			)
		)
	)
	(zone
		(layers "F.Cu" "B.Cu" "In1.Cu" "In2.Cu" "In3.Cu" "In4.Cu" "In5.Cu" "In6.Cu"
			"In7.Cu" "In8.Cu" "In9.Cu" "In10.Cu" "In11.Cu" "In12.Cu" "In13.Cu" "In14.Cu"
			"In15.Cu" "In16.Cu"
		)
		(hatch none 0.5)
		(connect_pads
			(clearance 0)
		)
		(min_thickness 0.25)
		(keepout
			(tracks not_allowed)
			(vias allowed)
			(pads allowed)
			(copperpour not_allowed)
			(footprints allowed)
		)
		(placement
			(enabled no)
			(sheetname "")
		)
		(fill
			(thermal_gap 0.5)
			(thermal_bridge_width 0.5)
			(island_removal_mode 0)
		)
		(polygon
			(pts
				(arc
					(start 375.885964 -221.133924)
					(mid 375.228104 -221.133924)
					(end 375.885964 -221.133924)
				)
			)
		)
	)
	(zone
		(layers "F.Cu" "B.Cu" "In1.Cu" "In2.Cu" "In3.Cu" "In4.Cu" "In5.Cu" "In6.Cu"
			"In7.Cu" "In8.Cu" "In9.Cu" "In10.Cu" "In11.Cu" "In12.Cu" "In13.Cu" "In14.Cu"
			"In15.Cu" "In16.Cu"
		)
		(hatch none 0.5)
		(connect_pads
			(clearance 0)
		)
		(min_thickness 0.25)
		(keepout
			(tracks not_allowed)
			(vias allowed)
			(pads allowed)
			(copperpour not_allowed)
			(footprints allowed)
		)
		(placement
			(enabled no)
			(sheetname "")
		)
		(fill
			(thermal_gap 0.5)
			(thermal_bridge_width 0.5)
			(island_removal_mode 0)
		)
		(polygon
			(pts
				(arc
					(start 345.922092 -289.807142)
					(mid 345.264232 -289.807142)
					(end 345.922092 -289.807142)
				)
			)
		)
	)
	(zone
		(layers "F.Cu" "B.Cu" "In1.Cu" "In2.Cu" "In3.Cu" "In4.Cu" "In5.Cu" "In6.Cu"
			"In7.Cu" "In8.Cu" "In9.Cu" "In10.Cu" "In11.Cu" "In12.Cu" "In13.Cu" "In14.Cu"
			"In15.Cu" "In16.Cu"
		)
		(hatch none 0.5)
		(connect_pads
			(clearance 0)
		)
		(min_thickness 0.25)
		(keepout
			(tracks not_allowed)
			(vias allowed)
			(pads allowed)
			(copperpour not_allowed)
			(footprints allowed)
		)
		(placement
			(enabled no)
			(sheetname "")
		)
		(fill
			(thermal_gap 0.5)
			(thermal_bridge_width 0.5)
			(island_removal_mode 0)
		)
		(polygon
			(pts
				(arc
					(start 109.259624 -273.453098)
					(mid 108.601764 -273.453098)
					(end 109.259624 -273.453098)
				)
			)
		)
	)
	(zone
		(layers "F.Cu" "B.Cu" "In1.Cu" "In2.Cu" "In3.Cu" "In4.Cu" "In5.Cu" "In6.Cu"
			"In7.Cu" "In8.Cu" "In9.Cu" "In10.Cu" "In11.Cu" "In12.Cu" "In13.Cu" "In14.Cu"
			"In15.Cu" "In16.Cu"
		)
		(hatch none 0.5)
		(connect_pads
			(clearance 0)
		)
		(min_thickness 0.25)
		(keepout
			(tracks not_allowed)
			(vias allowed)
			(pads allowed)
			(copperpour not_allowed)
			(footprints allowed)
		)
		(placement
			(enabled no)
			(sheetname "")
		)
		(fill
			(thermal_gap 0.5)
			(thermal_bridge_width 0.5)
			(island_removal_mode 0)
		)
		(polygon
			(pts
				(xy 851.721944 -404.78583) (xy 851.721944 -394.78585) (xy 852.026744 -395.09065) (xy 852.026744 -404.48103)
			)
		)
	)
	(zone
		(layers "F.Cu" "B.Cu" "In1.Cu" "In2.Cu" "In3.Cu" "In4.Cu" "In5.Cu" "In6.Cu"
			"In7.Cu" "In8.Cu" "In9.Cu" "In10.Cu" "In11.Cu" "In12.Cu" "In13.Cu" "In14.Cu"
			"In15.Cu" "In16.Cu"
		)
		(hatch none 0.5)
		(connect_pads
			(clearance 0)
		)
		(min_thickness 0.25)
		(keepout
			(tracks not_allowed)
			(vias allowed)
			(pads allowed)
			(copperpour not_allowed)
			(footprints allowed)
		)
		(placement
			(enabled no)
			(sheetname "")
		)
		(fill
			(thermal_gap 0.5)
			(thermal_bridge_width 0.5)
			(island_removal_mode 0)
		)
		(polygon
			(pts
				(arc
					(start 350.98101 -218.692222)
					(mid 350.32315 -218.692222)
					(end 350.98101 -218.692222)
				)
			)
		)
	)
	(zone
		(layers "F.Cu" "B.Cu" "In1.Cu" "In2.Cu" "In3.Cu" "In4.Cu" "In5.Cu" "In6.Cu"
			"In7.Cu" "In8.Cu" "In9.Cu" "In10.Cu" "In11.Cu" "In12.Cu" "In13.Cu" "In14.Cu"
			"In15.Cu" "In16.Cu"
		)
		(hatch none 0.5)
		(connect_pads
			(clearance 0)
		)
		(min_thickness 0.25)
		(keepout
			(tracks not_allowed)
			(vias allowed)
			(pads allowed)
			(copperpour not_allowed)
			(footprints allowed)
		)
		(placement
			(enabled no)
			(sheetname "")
		)
		(fill
			(thermal_gap 0.5)
			(thermal_bridge_width 0.5)
			(island_removal_mode 0)
		)
		(polygon
			(pts
				(arc
					(start 343.46261 -225.203258)
					(mid 342.80475 -225.203258)
					(end 343.46261 -225.203258)
				)
			)
		)
	)
	(zone
		(layers "F.Cu" "B.Cu" "In1.Cu" "In2.Cu" "In3.Cu" "In4.Cu" "In5.Cu" "In6.Cu"
			"In7.Cu" "In8.Cu" "In9.Cu" "In10.Cu" "In11.Cu" "In12.Cu" "In13.Cu" "In14.Cu"
			"In15.Cu" "In16.Cu"
		)
		(hatch none 0.5)
		(connect_pads
			(clearance 0)
		)
		(min_thickness 0.25)
		(keepout
			(tracks not_allowed)
			(vias allowed)
			(pads allowed)
			(copperpour not_allowed)
			(footprints allowed)
		)
		(placement
			(enabled no)
			(sheetname "")
		)
		(fill
			(thermal_gap 0.5)
			(thermal_bridge_width 0.5)
			(island_removal_mode 0)
		)
		(polygon
			(pts
				(arc
					(start 345.422982 -281.493722)
					(mid 345.403298 -281.541132)
					(end 345.396566 -281.59202)
				)
				(arc
					(start 345.396566 -281.59202)
					(mid 345.454222 -281.731214)
					(end 345.593416 -281.78887)
				)
				(arc
					(start 345.593416 -281.78887)
					(mid 345.691847 -281.762454)
					(end 345.76385 -281.690318)
				)
				(arc
					(start 346.23375 -280.876248)
					(mid 346.253434 -280.828838)
					(end 346.260166 -280.77795)
				)
				(arc
					(start 346.260166 -280.77795)
					(mid 346.20251 -280.638756)
					(end 346.063316 -280.5811)
				)
				(arc
					(start 346.063316 -280.5811)
					(mid 345.964885 -280.607516)
					(end 345.892882 -280.679652)
				)
			)
		)
	)
	(zone
		(layers "F.Cu" "B.Cu" "In1.Cu" "In2.Cu" "In3.Cu" "In4.Cu" "In5.Cu" "In6.Cu"
			"In7.Cu" "In8.Cu" "In9.Cu" "In10.Cu" "In11.Cu" "In12.Cu" "In13.Cu" "In14.Cu"
			"In15.Cu" "In16.Cu"
		)
		(hatch none 0.5)
		(connect_pads
			(clearance 0)
		)
		(min_thickness 0.25)
		(keepout
			(tracks not_allowed)
			(vias allowed)
			(pads allowed)
			(copperpour not_allowed)
			(footprints allowed)
		)
		(placement
			(enabled no)
			(sheetname "")
		)
		(fill
			(thermal_gap 0.5)
			(thermal_bridge_width 0.5)
			(island_removal_mode 0)
		)
		(polygon
			(pts
				(arc
					(start 125.907292 -217.97645)
					(mid 125.926976 -217.92904)
					(end 125.933708 -217.878152)
				)
				(arc
					(start 125.933708 -217.878152)
					(mid 125.876052 -217.738958)
					(end 125.736858 -217.681302)
				)
				(arc
					(start 125.736858 -217.681302)
					(mid 125.638427 -217.707718)
					(end 125.566424 -217.779854)
				)
				(arc
					(start 125.096778 -218.593924)
					(mid 125.077094 -218.641334)
					(end 125.070362 -218.692222)
				)
				(arc
					(start 125.070362 -218.692222)
					(mid 125.128018 -218.831416)
					(end 125.267212 -218.889072)
				)
				(arc
					(start 125.267212 -218.889072)
					(mid 125.365643 -218.862656)
					(end 125.437646 -218.79052)
				)
			)
		)
	)
	(zone
		(layers "F.Cu" "B.Cu" "In1.Cu" "In2.Cu" "In3.Cu" "In4.Cu" "In5.Cu" "In6.Cu"
			"In7.Cu" "In8.Cu" "In9.Cu" "In10.Cu" "In11.Cu" "In12.Cu" "In13.Cu" "In14.Cu"
			"In15.Cu" "In16.Cu"
		)
		(hatch none 0.5)
		(connect_pads
			(clearance 0)
		)
		(min_thickness 0.25)
		(keepout
			(tracks not_allowed)
			(vias allowed)
			(pads allowed)
			(copperpour not_allowed)
			(footprints allowed)
		)
		(placement
			(enabled no)
			(sheetname "")
		)
		(fill
			(thermal_gap 0.5)
			(thermal_bridge_width 0.5)
			(island_removal_mode 0)
		)
		(polygon
			(pts
				(arc
					(start 351.561146 -276.708616)
					(mid 350.903286 -276.708616)
					(end 351.561146 -276.708616)
				)
			)
		)
	)
	(zone
		(layers "F.Cu" "B.Cu" "In1.Cu" "In2.Cu" "In3.Cu" "In4.Cu" "In5.Cu" "In6.Cu"
			"In7.Cu" "In8.Cu" "In9.Cu" "In10.Cu" "In11.Cu" "In12.Cu" "In13.Cu" "In14.Cu"
			"In15.Cu" "In16.Cu"
		)
		(hatch none 0.5)
		(connect_pads
			(clearance 0)
		)
		(min_thickness 0.25)
		(keepout
			(tracks not_allowed)
			(vias allowed)
			(pads allowed)
			(copperpour not_allowed)
			(footprints allowed)
		)
		(placement
			(enabled no)
			(sheetname "")
		)
		(fill
			(thermal_gap 0.5)
			(thermal_bridge_width 0.5)
			(island_removal_mode 0)
		)
		(polygon
			(pts
				(arc
					(start 126.535942 -213.732618)
					(mid 125.878082 -213.732618)
					(end 126.535942 -213.732618)
				)
			)
		)
	)
	(zone
		(layers "F.Cu" "B.Cu" "In1.Cu" "In2.Cu" "In3.Cu" "In4.Cu" "In5.Cu" "In6.Cu"
			"In7.Cu" "In8.Cu" "In9.Cu" "In10.Cu" "In11.Cu" "In12.Cu" "In13.Cu" "In14.Cu"
			"In15.Cu" "In16.Cu"
		)
		(hatch none 0.5)
		(connect_pads
			(clearance 0)
		)
		(min_thickness 0.25)
		(keepout
			(tracks not_allowed)
			(vias allowed)
			(pads allowed)
			(copperpour not_allowed)
			(footprints allowed)
		)
		(placement
			(enabled no)
			(sheetname "")
		)
		(fill
			(thermal_gap 0.5)
			(thermal_bridge_width 0.5)
			(island_removal_mode 0)
		)
		(polygon
			(pts
				(arc
					(start 89.835228 -285.563056)
					(mid 89.763239 -285.490897)
					(end 89.664794 -285.464504)
				)
				(arc
					(start 89.664794 -285.464504)
					(mid 89.5256 -285.52216)
					(end 89.467944 -285.661354)
				)
				(arc
					(start 89.467944 -285.661354)
					(mid 89.474701 -285.712235)
					(end 89.49436 -285.759652)
				)
				(arc
					(start 89.96426 -286.573722)
					(mid 90.036249 -286.645881)
					(end 90.134694 -286.672274)
				)
				(arc
					(start 90.134694 -286.672274)
					(mid 90.273888 -286.614618)
					(end 90.331544 -286.475424)
				)
				(arc
					(start 90.331544 -286.475424)
					(mid 90.324787 -286.424543)
					(end 90.305128 -286.377126)
				)
			)
		)
	)
	(zone
		(layers "F.Cu" "B.Cu" "In1.Cu" "In2.Cu" "In3.Cu" "In4.Cu" "In5.Cu" "In6.Cu"
			"In7.Cu" "In8.Cu" "In9.Cu" "In10.Cu" "In11.Cu" "In12.Cu" "In13.Cu" "In14.Cu"
			"In15.Cu" "In16.Cu"
		)
		(hatch none 0.5)
		(connect_pads
			(clearance 0)
		)
		(min_thickness 0.25)
		(keepout
			(tracks not_allowed)
			(vias allowed)
			(pads allowed)
			(copperpour not_allowed)
			(footprints allowed)
		)
		(placement
			(enabled no)
			(sheetname "")
		)
		(fill
			(thermal_gap 0.5)
			(thermal_bridge_width 0.5)
			(island_removal_mode 0)
		)
		(polygon
			(pts
				(arc
					(start 98.6536 -224.291144)
					(mid 98.581611 -224.218985)
					(end 98.483166 -224.192592)
				)
				(arc
					(start 98.483166 -224.192592)
					(mid 98.343972 -224.250248)
					(end 98.286316 -224.389442)
				)
				(arc
					(start 98.286316 -224.389442)
					(mid 98.293073 -224.440323)
					(end 98.312732 -224.48774)
				)
				(arc
					(start 98.782378 -225.301556)
					(mid 98.854367 -225.373715)
					(end 98.952812 -225.400108)
				)
				(arc
					(start 98.952812 -225.400108)
					(mid 99.092006 -225.342452)
					(end 99.149662 -225.203258)
				)
				(arc
					(start 99.149662 -225.203258)
					(mid 99.142905 -225.152377)
					(end 99.123246 -225.10496)
				)
			)
		)
	)
	(zone
		(layers "F.Cu" "B.Cu" "In1.Cu" "In2.Cu" "In3.Cu" "In4.Cu" "In5.Cu" "In6.Cu"
			"In7.Cu" "In8.Cu" "In9.Cu" "In10.Cu" "In11.Cu" "In12.Cu" "In13.Cu" "In14.Cu"
			"In15.Cu" "In16.Cu"
		)
		(hatch none 0.5)
		(connect_pads
			(clearance 0)
		)
		(min_thickness 0.25)
		(keepout
			(tracks not_allowed)
			(vias allowed)
			(pads allowed)
			(copperpour not_allowed)
			(footprints allowed)
		)
		(placement
			(enabled no)
			(sheetname "")
		)
		(fill
			(thermal_gap 0.5)
			(thermal_bridge_width 0.5)
			(island_removal_mode 0)
		)
		(polygon
			(pts
				(arc
					(start 106.172 -224.291144)
					(mid 106.100011 -224.218985)
					(end 106.001566 -224.192592)
				)
				(arc
					(start 106.001566 -224.192592)
					(mid 105.862372 -224.250248)
					(end 105.804716 -224.389442)
				)
				(arc
					(start 105.804716 -224.389442)
					(mid 105.811473 -224.440323)
					(end 105.831132 -224.48774)
				)
				(arc
					(start 106.300778 -225.301556)
					(mid 106.372767 -225.373715)
					(end 106.471212 -225.400108)
				)
				(arc
					(start 106.471212 -225.400108)
					(mid 106.610406 -225.342452)
					(end 106.668062 -225.203258)
				)
				(arc
					(start 106.668062 -225.203258)
					(mid 106.661305 -225.152377)
					(end 106.641646 -225.10496)
				)
			)
		)
	)
	(zone
		(layers "F.Cu" "B.Cu" "In1.Cu" "In2.Cu" "In3.Cu" "In4.Cu" "In5.Cu" "In6.Cu"
			"In7.Cu" "In8.Cu" "In9.Cu" "In10.Cu" "In11.Cu" "In12.Cu" "In13.Cu" "In14.Cu"
			"In15.Cu" "In16.Cu"
		)
		(hatch none 0.5)
		(connect_pads
			(clearance 0)
		)
		(min_thickness 0.25)
		(keepout
			(tracks not_allowed)
			(vias allowed)
			(pads allowed)
			(copperpour not_allowed)
			(footprints allowed)
		)
		(placement
			(enabled no)
			(sheetname "")
		)
		(fill
			(thermal_gap 0.5)
			(thermal_bridge_width 0.5)
			(island_removal_mode 0)
		)
		(polygon
			(pts
				(arc
					(start 126.535942 -217.064336)
					(mid 125.878082 -217.064336)
					(end 126.535942 -217.064336)
				)
			)
		)
	)
	(zone
		(layers "F.Cu" "B.Cu" "In1.Cu" "In2.Cu" "In3.Cu" "In4.Cu" "In5.Cu" "In6.Cu"
			"In7.Cu" "In8.Cu" "In9.Cu" "In10.Cu" "In11.Cu" "In12.Cu" "In13.Cu" "In14.Cu"
			"In15.Cu" "In16.Cu"
		)
		(hatch none 0.5)
		(connect_pads
			(clearance 0)
		)
		(min_thickness 0.25)
		(keepout
			(tracks not_allowed)
			(vias allowed)
			(pads allowed)
			(copperpour not_allowed)
			(footprints allowed)
		)
		(placement
			(enabled no)
			(sheetname "")
		)
		(fill
			(thermal_gap 0.5)
			(thermal_bridge_width 0.5)
			(island_removal_mode 0)
		)
		(polygon
			(pts
				(arc
					(start 93.954092 -214.720932)
					(mid 93.973776 -214.673522)
					(end 93.980508 -214.622634)
				)
				(arc
					(start 93.980508 -214.622634)
					(mid 93.922852 -214.48344)
					(end 93.783658 -214.425784)
				)
				(arc
					(start 93.783658 -214.425784)
					(mid 93.685227 -214.4522)
					(end 93.613224 -214.524336)
				)
				(arc
					(start 93.143578 -215.338406)
					(mid 93.123894 -215.385816)
					(end 93.117162 -215.436704)
				)
				(arc
					(start 93.117162 -215.436704)
					(mid 93.174818 -215.575898)
					(end 93.314012 -215.633554)
				)
				(arc
					(start 93.314012 -215.633554)
					(mid 93.412443 -215.607138)
					(end 93.484446 -215.535002)
				)
			)
		)
	)
	(zone
		(layers "F.Cu" "B.Cu" "In1.Cu" "In2.Cu" "In3.Cu" "In4.Cu" "In5.Cu" "In6.Cu"
			"In7.Cu" "In8.Cu" "In9.Cu" "In10.Cu" "In11.Cu" "In12.Cu" "In13.Cu" "In14.Cu"
			"In15.Cu" "In16.Cu"
		)
		(hatch none 0.5)
		(connect_pads
			(clearance 0)
		)
		(min_thickness 0.25)
		(keepout
			(tracks not_allowed)
			(vias allowed)
			(pads allowed)
			(copperpour not_allowed)
			(footprints allowed)
		)
		(placement
			(enabled no)
			(sheetname "")
		)
		(fill
			(thermal_gap 0.5)
			(thermal_bridge_width 0.5)
			(island_removal_mode 0)
		)
		(polygon
			(pts
				(arc
					(start 115.09248 -213.646766)
					(mid 115.024772 -213.574915)
					(end 114.929666 -213.548468)
				)
				(arc
					(start 114.929666 -213.548468)
					(mid 114.799452 -213.602404)
					(end 114.745516 -213.732618)
				)
				(arc
					(start 114.745516 -213.732618)
					(mid 114.750967 -213.776839)
					(end 114.766852 -213.81847)
				)
				(arc
					(start 115.236244 -214.708486)
					(mid 115.303952 -214.780337)
					(end 115.399058 -214.806784)
				)
				(arc
					(start 115.399058 -214.806784)
					(mid 115.529272 -214.752848)
					(end 115.583208 -214.622634)
				)
				(arc
					(start 115.583208 -214.622634)
					(mid 115.577757 -214.578413)
					(end 115.561872 -214.536782)
				)
			)
		)
	)
	(zone
		(layers "F.Cu" "B.Cu" "In1.Cu" "In2.Cu" "In3.Cu" "In4.Cu" "In5.Cu" "In6.Cu"
			"In7.Cu" "In8.Cu" "In9.Cu" "In10.Cu" "In11.Cu" "In12.Cu" "In13.Cu" "In14.Cu"
			"In15.Cu" "In16.Cu"
		)
		(hatch none 0.5)
		(connect_pads
			(clearance 0)
		)
		(min_thickness 0.25)
		(keepout
			(tracks not_allowed)
			(vias allowed)
			(pads allowed)
			(copperpour not_allowed)
			(footprints allowed)
		)
		(placement
			(enabled no)
			(sheetname "")
		)
		(fill
			(thermal_gap 0.5)
			(thermal_bridge_width 0.5)
			(island_removal_mode 0)
		)
		(polygon
			(pts
				(arc
					(start 379.48616 -217.97645)
					(mid 379.505844 -217.92904)
					(end 379.512576 -217.878152)
				)
				(arc
					(start 379.512576 -217.878152)
					(mid 379.45492 -217.738958)
					(end 379.315726 -217.681302)
				)
				(arc
					(start 379.315726 -217.681302)
					(mid 379.217295 -217.707718)
					(end 379.145292 -217.779854)
				)
				(arc
					(start 378.675646 -218.593924)
					(mid 378.655962 -218.641334)
					(end 378.64923 -218.692222)
				)
				(arc
					(start 378.64923 -218.692222)
					(mid 378.706886 -218.831416)
					(end 378.84608 -218.889072)
				)
				(arc
					(start 378.84608 -218.889072)
					(mid 378.944511 -218.862656)
					(end 379.016514 -218.79052)
				)
			)
		)
	)
	(zone
		(layers "F.Cu" "B.Cu" "In1.Cu" "In2.Cu" "In3.Cu" "In4.Cu" "In5.Cu" "In6.Cu"
			"In7.Cu" "In8.Cu" "In9.Cu" "In10.Cu" "In11.Cu" "In12.Cu" "In13.Cu" "In14.Cu"
			"In15.Cu" "In16.Cu"
		)
		(hatch none 0.5)
		(connect_pads
			(clearance 0)
		)
		(min_thickness 0.25)
		(keepout
			(tracks not_allowed)
			(vias allowed)
			(pads allowed)
			(copperpour not_allowed)
			(footprints allowed)
		)
		(placement
			(enabled no)
			(sheetname "")
		)
		(fill
			(thermal_gap 0.5)
			(thermal_bridge_width 0.5)
			(island_removal_mode 0)
		)
		(polygon
			(pts
				(arc
					(start 124.498354 -216.966292)
					(mid 124.426365 -216.894133)
					(end 124.32792 -216.86774)
				)
				(arc
					(start 124.32792 -216.86774)
					(mid 124.188726 -216.925396)
					(end 124.13107 -217.06459)
				)
				(arc
					(start 124.13107 -217.06459)
					(mid 124.137827 -217.115471)
					(end 124.157486 -217.162888)
				)
				(arc
					(start 124.627132 -217.976704)
					(mid 124.699121 -218.048863)
					(end 124.797566 -218.075256)
				)
				(arc
					(start 124.797566 -218.075256)
					(mid 124.93676 -218.0176)
					(end 124.994416 -217.878406)
				)
				(arc
					(start 124.994416 -217.878406)
					(mid 124.987659 -217.827525)
					(end 124.968 -217.780108)
				)
			)
		)
	)
	(zone
		(layers "F.Cu" "B.Cu" "In1.Cu" "In2.Cu" "In3.Cu" "In4.Cu" "In5.Cu" "In6.Cu"
			"In7.Cu" "In8.Cu" "In9.Cu" "In10.Cu" "In11.Cu" "In12.Cu" "In13.Cu" "In14.Cu"
			"In15.Cu" "In16.Cu"
		)
		(hatch none 0.5)
		(connect_pads
			(clearance 0)
		)
		(min_thickness 0.25)
		(keepout
			(tracks not_allowed)
			(vias allowed)
			(pads allowed)
			(copperpour not_allowed)
			(footprints allowed)
		)
		(placement
			(enabled no)
			(sheetname "")
		)
		(fill
			(thermal_gap 0.5)
			(thermal_bridge_width 0.5)
			(island_removal_mode 0)
		)
		(polygon
			(pts
				(arc
					(start 377.405392 -285.661354)
					(mid 376.747532 -285.661354)
					(end 377.405392 -285.661354)
				)
			)
		)
	)
	(zone
		(layers "F.Cu" "B.Cu" "In1.Cu" "In2.Cu" "In3.Cu" "In4.Cu" "In5.Cu" "In6.Cu"
			"In7.Cu" "In8.Cu" "In9.Cu" "In10.Cu" "In11.Cu" "In12.Cu" "In13.Cu" "In14.Cu"
			"In15.Cu" "In16.Cu"
		)
		(hatch none 0.5)
		(connect_pads
			(clearance 0)
		)
		(min_thickness 0.25)
		(keepout
			(tracks not_allowed)
			(vias allowed)
			(pads allowed)
			(copperpour not_allowed)
			(footprints allowed)
		)
		(placement
			(enabled no)
			(sheetname "")
		)
		(fill
			(thermal_gap 0.5)
			(thermal_bridge_width 0.5)
			(island_removal_mode 0)
		)
		(polygon
			(pts
				(arc
					(start 373.018304 -288.005012)
					(mid 372.946315 -287.932853)
					(end 372.84787 -287.90646)
				)
				(arc
					(start 372.84787 -287.90646)
					(mid 372.708676 -287.964116)
					(end 372.65102 -288.10331)
				)
				(arc
					(start 372.65102 -288.10331)
					(mid 372.657777 -288.154191)
					(end 372.677436 -288.201608)
				)
				(arc
					(start 373.147082 -289.015424)
					(mid 373.219071 -289.087583)
					(end 373.317516 -289.113976)
				)
				(arc
					(start 373.317516 -289.113976)
					(mid 373.45671 -289.05632)
					(end 373.514366 -288.917126)
				)
				(arc
					(start 373.514366 -288.917126)
					(mid 373.507609 -288.866245)
					(end 373.48795 -288.818828)
				)
			)
		)
	)
	(zone
		(layers "F.Cu" "B.Cu" "In1.Cu" "In2.Cu" "In3.Cu" "In4.Cu" "In5.Cu" "In6.Cu"
			"In7.Cu" "In8.Cu" "In9.Cu" "In10.Cu" "In11.Cu" "In12.Cu" "In13.Cu" "In14.Cu"
			"In15.Cu" "In16.Cu"
		)
		(hatch none 0.5)
		(connect_pads
			(clearance 0)
		)
		(min_thickness 0.25)
		(keepout
			(tracks not_allowed)
			(vias allowed)
			(pads allowed)
			(copperpour not_allowed)
			(footprints allowed)
		)
		(placement
			(enabled no)
			(sheetname "")
		)
		(fill
			(thermal_gap 0.5)
			(thermal_bridge_width 0.5)
			(island_removal_mode 0)
		)
		(polygon
			(pts
				(arc
					(start 445.838326 -12.472162)
					(mid 445.457326 -12.853162)
					(end 445.838326 -13.234162)
				)
				(arc
					(start 446.701926 -13.234162)
					(mid 447.082926 -12.853162)
					(end 446.701926 -12.472162)
				)
			)
		)
	)
	(zone
		(layers "F.Cu" "B.Cu" "In1.Cu" "In2.Cu" "In3.Cu" "In4.Cu" "In5.Cu" "In6.Cu"
			"In7.Cu" "In8.Cu" "In9.Cu" "In10.Cu" "In11.Cu" "In12.Cu" "In13.Cu" "In14.Cu"
			"In15.Cu" "In16.Cu"
		)
		(hatch none 0.5)
		(connect_pads
			(clearance 0)
		)
		(min_thickness 0.25)
		(keepout
			(tracks not_allowed)
			(vias allowed)
			(pads allowed)
			(copperpour not_allowed)
			(footprints allowed)
		)
		(placement
			(enabled no)
			(sheetname "")
		)
		(fill
			(thermal_gap 0.5)
			(thermal_bridge_width 0.5)
			(island_removal_mode 0)
		)
		(polygon
			(pts
				(arc
					(start 412.59125 -406.62352)
					(mid 412.21025 -407.00452)
					(end 412.59125 -407.38552)
				)
				(arc
					(start 413.45485 -407.38552)
					(mid 413.83585 -407.00452)
					(end 413.45485 -406.62352)
				)
			)
		)
	)
	(zone
		(layers "F.Cu" "B.Cu" "In1.Cu" "In2.Cu" "In3.Cu" "In4.Cu" "In5.Cu" "In6.Cu"
			"In7.Cu" "In8.Cu" "In9.Cu" "In10.Cu" "In11.Cu" "In12.Cu" "In13.Cu" "In14.Cu"
			"In15.Cu" "In16.Cu"
		)
		(hatch none 0.5)
		(connect_pads
			(clearance 0)
		)
		(min_thickness 0.25)
		(keepout
			(tracks not_allowed)
			(vias allowed)
			(pads allowed)
			(copperpour not_allowed)
			(footprints allowed)
		)
		(placement
			(enabled no)
			(sheetname "")
		)
		(fill
			(thermal_gap 0.5)
			(thermal_bridge_width 0.5)
			(island_removal_mode 0)
		)
		(polygon
			(pts
				(arc
					(start 381.36576 -217.97645)
					(mid 381.385444 -217.92904)
					(end 381.392176 -217.878152)
				)
				(arc
					(start 381.392176 -217.878152)
					(mid 381.33452 -217.738958)
					(end 381.195326 -217.681302)
				)
				(arc
					(start 381.195326 -217.681302)
					(mid 381.096895 -217.707718)
					(end 381.024892 -217.779854)
				)
				(arc
					(start 380.555246 -218.593924)
					(mid 380.535562 -218.641334)
					(end 380.52883 -218.692222)
				)
				(arc
					(start 380.52883 -218.692222)
					(mid 380.586486 -218.831416)
					(end 380.72568 -218.889072)
				)
				(arc
					(start 380.72568 -218.889072)
					(mid 380.824111 -218.862656)
					(end 380.896114 -218.79052)
				)
			)
		)
	)
	(zone
		(layers "F.Cu" "B.Cu" "In1.Cu" "In2.Cu" "In3.Cu" "In4.Cu" "In5.Cu" "In6.Cu"
			"In7.Cu" "In8.Cu" "In9.Cu" "In10.Cu" "In11.Cu" "In12.Cu" "In13.Cu" "In14.Cu"
			"In15.Cu" "In16.Cu"
		)
		(hatch none 0.5)
		(connect_pads
			(clearance 0)
		)
		(min_thickness 0.25)
		(keepout
			(tracks not_allowed)
			(vias allowed)
			(pads allowed)
			(copperpour not_allowed)
			(footprints allowed)
		)
		(placement
			(enabled no)
			(sheetname "")
		)
		(fill
			(thermal_gap 0.5)
			(thermal_bridge_width 0.5)
			(island_removal_mode 0)
		)
		(polygon
			(pts
				(arc
					(start 110.559342 -225.203258)
					(mid 109.901482 -225.203258)
					(end 110.559342 -225.203258)
				)
			)
		)
	)
	(zone
		(layers "F.Cu" "B.Cu" "In1.Cu" "In2.Cu" "In3.Cu" "In4.Cu" "In5.Cu" "In6.Cu"
			"In7.Cu" "In8.Cu" "In9.Cu" "In10.Cu" "In11.Cu" "In12.Cu" "In13.Cu" "In14.Cu"
			"In15.Cu" "In16.Cu"
		)
		(hatch none 0.5)
		(connect_pads
			(clearance 0)
		)
		(min_thickness 0.25)
		(keepout
			(tracks not_allowed)
			(vias allowed)
			(pads allowed)
			(copperpour not_allowed)
			(footprints allowed)
		)
		(placement
			(enabled no)
			(sheetname "")
		)
		(fill
			(thermal_gap 0.5)
			(thermal_bridge_width 0.5)
			(island_removal_mode 0)
		)
		(polygon
			(pts
				(arc
					(start 363.039914 -223.67367)
					(mid 363.059598 -223.62626)
					(end 363.06633 -223.575372)
				)
				(arc
					(start 363.06633 -223.575372)
					(mid 363.008674 -223.436178)
					(end 362.86948 -223.378522)
				)
				(arc
					(start 362.86948 -223.378522)
					(mid 362.771049 -223.404938)
					(end 362.699046 -223.477074)
				)
				(arc
					(start 362.2294 -224.291144)
					(mid 362.209716 -224.338554)
					(end 362.202984 -224.389442)
				)
				(arc
					(start 362.202984 -224.389442)
					(mid 362.26064 -224.528636)
					(end 362.399834 -224.586292)
				)
				(arc
					(start 362.399834 -224.586292)
					(mid 362.498265 -224.559876)
					(end 362.570268 -224.48774)
				)
			)
		)
	)
	(zone
		(layers "F.Cu" "B.Cu" "In1.Cu" "In2.Cu" "In3.Cu" "In4.Cu" "In5.Cu" "In6.Cu"
			"In7.Cu" "In8.Cu" "In9.Cu" "In10.Cu" "In11.Cu" "In12.Cu" "In13.Cu" "In14.Cu"
			"In15.Cu" "In16.Cu"
		)
		(hatch none 0.5)
		(connect_pads
			(clearance 0)
		)
		(min_thickness 0.25)
		(keepout
			(tracks not_allowed)
			(vias allowed)
			(pads allowed)
			(copperpour not_allowed)
			(footprints allowed)
		)
		(placement
			(enabled no)
			(sheetname "")
		)
		(fill
			(thermal_gap 0.5)
			(thermal_bridge_width 0.5)
			(island_removal_mode 0)
		)
		(polygon
			(pts
				(arc
					(start 95.992696 -221.133924)
					(mid 95.334836 -221.133924)
					(end 95.992696 -221.133924)
				)
			)
		)
	)
	(zone
		(layers "F.Cu" "B.Cu" "In1.Cu" "In2.Cu" "In3.Cu" "In4.Cu" "In5.Cu" "In6.Cu"
			"In7.Cu" "In8.Cu" "In9.Cu" "In10.Cu" "In11.Cu" "In12.Cu" "In13.Cu" "In14.Cu"
			"In15.Cu" "In16.Cu"
		)
		(hatch none 0.5)
		(connect_pads
			(clearance 0)
		)
		(min_thickness 0.25)
		(keepout
			(tracks not_allowed)
			(vias allowed)
			(pads allowed)
			(copperpour not_allowed)
			(footprints allowed)
		)
		(placement
			(enabled no)
			(sheetname "")
		)
		(fill
			(thermal_gap 0.5)
			(thermal_bridge_width 0.5)
			(island_removal_mode 0)
		)
		(polygon
			(pts
				(arc
					(start 122.228864 -285.661354)
					(mid 122.886724 -285.661354)
					(end 122.228864 -285.661354)
				)
			)
		)
	)
	(zone
		(layers "F.Cu" "B.Cu" "In1.Cu" "In2.Cu" "In3.Cu" "In4.Cu" "In5.Cu" "In6.Cu"
			"In7.Cu" "In8.Cu" "In9.Cu" "In10.Cu" "In11.Cu" "In12.Cu" "In13.Cu" "In14.Cu"
			"In15.Cu" "In16.Cu"
		)
		(hatch none 0.5)
		(connect_pads
			(clearance 0)
		)
		(min_thickness 0.25)
		(keepout
			(tracks not_allowed)
			(vias allowed)
			(pads allowed)
			(copperpour not_allowed)
			(footprints allowed)
		)
		(placement
			(enabled no)
			(sheetname "")
		)
		(fill
			(thermal_gap 0.5)
			(thermal_bridge_width 0.5)
			(island_removal_mode 0)
		)
		(polygon
			(pts
				(arc
					(start 121.501154 -406.62352)
					(mid 121.120154 -407.00452)
					(end 121.501154 -407.38552)
				)
				(arc
					(start 122.364754 -407.38552)
					(mid 122.745754 -407.00452)
					(end 122.364754 -406.62352)
				)
			)
		)
	)
	(zone
		(layers "F.Cu" "B.Cu" "In1.Cu" "In2.Cu" "In3.Cu" "In4.Cu" "In5.Cu" "In6.Cu"
			"In7.Cu" "In8.Cu" "In9.Cu" "In10.Cu" "In11.Cu" "In12.Cu" "In13.Cu" "In14.Cu"
			"In15.Cu" "In16.Cu"
		)
		(hatch none 0.5)
		(connect_pads
			(clearance 0)
		)
		(min_thickness 0.25)
		(keepout
			(tracks not_allowed)
			(vias allowed)
			(pads allowed)
			(copperpour not_allowed)
			(footprints allowed)
		)
		(placement
			(enabled no)
			(sheetname "")
		)
		(fill
			(thermal_gap 0.5)
			(thermal_bridge_width 0.5)
			(island_removal_mode 0)
		)
		(polygon
			(pts
				(arc
					(start 396.10284 -251.76988)
					(mid 391.656824 -251.76988)
					(end 396.10284 -251.76988)
				)
			)
		)
	)
	(zone
		(layers "F.Cu" "B.Cu" "In1.Cu" "In2.Cu" "In3.Cu" "In4.Cu" "In5.Cu" "In6.Cu"
			"In7.Cu" "In8.Cu" "In9.Cu" "In10.Cu" "In11.Cu" "In12.Cu" "In13.Cu" "In14.Cu"
			"In15.Cu" "In16.Cu"
		)
		(hatch none 0.5)
		(connect_pads
			(clearance 0)
		)
		(min_thickness 0.25)
		(keepout
			(tracks not_allowed)
			(vias allowed)
			(pads allowed)
			(copperpour not_allowed)
			(footprints allowed)
		)
		(placement
			(enabled no)
			(sheetname "")
		)
		(fill
			(thermal_gap 0.5)
			(thermal_bridge_width 0.5)
			(island_removal_mode 0)
		)
		(polygon
			(pts
				(arc
					(start 342.053164 -224.389442)
					(mid 341.395304 -224.389442)
					(end 342.053164 -224.389442)
				)
			)
		)
	)
	(zone
		(layers "F.Cu" "B.Cu" "In1.Cu" "In2.Cu" "In3.Cu" "In4.Cu" "In5.Cu" "In6.Cu"
			"In7.Cu" "In8.Cu" "In9.Cu" "In10.Cu" "In11.Cu" "In12.Cu" "In13.Cu" "In14.Cu"
			"In15.Cu" "In16.Cu"
		)
		(hatch none 0.5)
		(connect_pads
			(clearance 0)
		)
		(min_thickness 0.25)
		(keepout
			(tracks not_allowed)
			(vias allowed)
			(pads allowed)
			(copperpour not_allowed)
			(footprints allowed)
		)
		(placement
			(enabled no)
			(sheetname "")
		)
		(fill
			(thermal_gap 0.5)
			(thermal_bridge_width 0.5)
			(island_removal_mode 0)
		)
		(polygon
			(pts
				(arc
					(start 90.434414 -285.563056)
					(mid 90.41473 -285.610466)
					(end 90.407998 -285.661354)
				)
				(arc
					(start 90.407998 -285.661354)
					(mid 90.465654 -285.800548)
					(end 90.604848 -285.858204)
				)
				(arc
					(start 90.604848 -285.858204)
					(mid 90.703279 -285.831788)
					(end 90.775282 -285.759652)
				)
				(arc
					(start 91.245182 -284.945582)
					(mid 91.264866 -284.898172)
					(end 91.271598 -284.847284)
				)
				(arc
					(start 91.271598 -284.847284)
					(mid 91.213942 -284.70809)
					(end 91.074748 -284.650434)
				)
				(arc
					(start 91.074748 -284.650434)
					(mid 90.976317 -284.67685)
					(end 90.904314 -284.748986)
				)
			)
		)
	)
	(zone
		(layers "F.Cu" "B.Cu" "In1.Cu" "In2.Cu" "In3.Cu" "In4.Cu" "In5.Cu" "In6.Cu"
			"In7.Cu" "In8.Cu" "In9.Cu" "In10.Cu" "In11.Cu" "In12.Cu" "In13.Cu" "In14.Cu"
			"In15.Cu" "In16.Cu"
		)
		(hatch none 0.5)
		(connect_pads
			(clearance 0)
		)
		(min_thickness 0.25)
		(keepout
			(tracks not_allowed)
			(vias allowed)
			(pads allowed)
			(copperpour not_allowed)
			(footprints allowed)
		)
		(placement
			(enabled no)
			(sheetname "")
		)
		(fill
			(thermal_gap 0.5)
			(thermal_bridge_width 0.5)
			(island_removal_mode 0)
		)
		(polygon
			(pts
				(arc
					(start 370.71681 -220.319854)
					(mid 370.05895 -220.319854)
					(end 370.71681 -220.319854)
				)
			)
		)
	)
	(zone
		(layers "F.Cu" "B.Cu" "In1.Cu" "In2.Cu" "In3.Cu" "In4.Cu" "In5.Cu" "In6.Cu"
			"In7.Cu" "In8.Cu" "In9.Cu" "In10.Cu" "In11.Cu" "In12.Cu" "In13.Cu" "In14.Cu"
			"In15.Cu" "In16.Cu"
		)
		(hatch none 0.5)
		(connect_pads
			(clearance 0)
		)
		(min_thickness 0.25)
		(keepout
			(tracks not_allowed)
			(vias allowed)
			(pads allowed)
			(copperpour not_allowed)
			(footprints allowed)
		)
		(placement
			(enabled no)
			(sheetname "")
		)
		(fill
			(thermal_gap 0.5)
			(thermal_bridge_width 0.5)
			(island_removal_mode 0)
		)
		(polygon
			(pts
				(arc
					(start 103.040942 -225.203258)
					(mid 102.383082 -225.203258)
					(end 103.040942 -225.203258)
				)
			)
		)
	)
	(zone
		(layers "F.Cu" "B.Cu" "In1.Cu" "In2.Cu" "In3.Cu" "In4.Cu" "In5.Cu" "In6.Cu"
			"In7.Cu" "In8.Cu" "In9.Cu" "In10.Cu" "In11.Cu" "In12.Cu" "In13.Cu" "In14.Cu"
			"In15.Cu" "In16.Cu"
		)
		(hatch none 0.5)
		(connect_pads
			(clearance 0)
		)
		(min_thickness 0.25)
		(keepout
			(tracks not_allowed)
			(vias allowed)
			(pads allowed)
			(copperpour not_allowed)
			(footprints allowed)
		)
		(placement
			(enabled no)
			(sheetname "")
		)
		(fill
			(thermal_gap 0.5)
			(thermal_bridge_width 0.5)
			(island_removal_mode 0)
		)
		(polygon
			(pts
				(arc
					(start 103.462328 -276.610064)
					(mid 103.390339 -276.537905)
					(end 103.291894 -276.511512)
				)
				(arc
					(start 103.291894 -276.511512)
					(mid 103.1527 -276.569168)
					(end 103.095044 -276.708362)
				)
				(arc
					(start 103.095044 -276.708362)
					(mid 103.101801 -276.759243)
					(end 103.12146 -276.80666)
				)
				(arc
					(start 103.59136 -277.62073)
					(mid 103.663349 -277.692889)
					(end 103.761794 -277.719282)
				)
				(arc
					(start 103.761794 -277.719282)
					(mid 103.900988 -277.661626)
					(end 103.958644 -277.522432)
				)
				(arc
					(start 103.958644 -277.522432)
					(mid 103.951887 -277.471551)
					(end 103.932228 -277.424134)
				)
			)
		)
	)
	(zone
		(layers "F.Cu" "B.Cu" "In1.Cu" "In2.Cu" "In3.Cu" "In4.Cu" "In5.Cu" "In6.Cu"
			"In7.Cu" "In8.Cu" "In9.Cu" "In10.Cu" "In11.Cu" "In12.Cu" "In13.Cu" "In14.Cu"
			"In15.Cu" "In16.Cu"
		)
		(hatch none 0.5)
		(connect_pads
			(clearance 0)
		)
		(min_thickness 0.25)
		(keepout
			(tracks not_allowed)
			(vias allowed)
			(pads allowed)
			(copperpour not_allowed)
			(footprints allowed)
		)
		(placement
			(enabled no)
			(sheetname "")
		)
		(fill
			(thermal_gap 0.5)
			(thermal_bridge_width 0.5)
			(island_removal_mode 0)
		)
		(polygon
			(pts
				(arc
					(start 101.412548 -283.023056)
					(mid 101.215698 -283.219906)
					(end 101.412548 -283.416756)
				)
				(arc
					(start 102.352348 -283.416756)
					(mid 102.549198 -283.219906)
					(end 102.352348 -283.023056)
				)
			)
		)
	)
	(zone
		(layers "F.Cu" "B.Cu" "In1.Cu" "In2.Cu" "In3.Cu" "In4.Cu" "In5.Cu" "In6.Cu"
			"In7.Cu" "In8.Cu" "In9.Cu" "In10.Cu" "In11.Cu" "In12.Cu" "In13.Cu" "In14.Cu"
			"In15.Cu" "In16.Cu"
		)
		(hatch none 0.5)
		(connect_pads
			(clearance 0)
		)
		(min_thickness 0.25)
		(keepout
			(tracks not_allowed)
			(vias allowed)
			(pads allowed)
			(copperpour not_allowed)
			(footprints allowed)
		)
		(placement
			(enabled no)
			(sheetname "")
		)
		(fill
			(thermal_gap 0.5)
			(thermal_bridge_width 0.5)
			(island_removal_mode 0)
		)
		(polygon
			(pts
				(arc
					(start 346.116148 -213.646766)
					(mid 346.04844 -213.574915)
					(end 345.953334 -213.548468)
				)
				(arc
					(start 345.953334 -213.548468)
					(mid 345.82312 -213.602404)
					(end 345.769184 -213.732618)
				)
				(arc
					(start 345.769184 -213.732618)
					(mid 345.774635 -213.776839)
					(end 345.79052 -213.81847)
				)
				(arc
					(start 346.259912 -214.708486)
					(mid 346.32762 -214.780337)
					(end 346.422726 -214.806784)
				)
				(arc
					(start 346.422726 -214.806784)
					(mid 346.55294 -214.752848)
					(end 346.606876 -214.622634)
				)
				(arc
					(start 346.606876 -214.622634)
					(mid 346.601425 -214.578413)
					(end 346.58554 -214.536782)
				)
			)
		)
	)
	(zone
		(layers "F.Cu" "B.Cu" "In1.Cu" "In2.Cu" "In3.Cu" "In4.Cu" "In5.Cu" "In6.Cu"
			"In7.Cu" "In8.Cu" "In9.Cu" "In10.Cu" "In11.Cu" "In12.Cu" "In13.Cu" "In14.Cu"
			"In15.Cu" "In16.Cu"
		)
		(hatch none 0.5)
		(connect_pads
			(clearance 0)
		)
		(min_thickness 0.25)
		(keepout
			(tracks not_allowed)
			(vias allowed)
			(pads allowed)
			(copperpour not_allowed)
			(footprints allowed)
		)
		(placement
			(enabled no)
			(sheetname "")
		)
		(fill
			(thermal_gap 0.5)
			(thermal_bridge_width 0.5)
			(island_removal_mode 0)
		)
		(polygon
			(pts
				(arc
					(start 110.870746 -221.231968)
					(mid 110.89043 -221.184558)
					(end 110.897162 -221.13367)
				)
				(arc
					(start 110.897162 -221.13367)
					(mid 110.839506 -220.994476)
					(end 110.700312 -220.93682)
				)
				(arc
					(start 110.700312 -220.93682)
					(mid 110.601881 -220.963236)
					(end 110.529878 -221.035372)
				)
				(arc
					(start 110.060232 -221.849442)
					(mid 110.040548 -221.896852)
					(end 110.033816 -221.94774)
				)
				(arc
					(start 110.033816 -221.94774)
					(mid 110.091472 -222.086934)
					(end 110.230666 -222.14459)
				)
				(arc
					(start 110.230666 -222.14459)
					(mid 110.329097 -222.118174)
					(end 110.4011 -222.046038)
				)
			)
		)
	)
	(zone
		(layers "F.Cu" "B.Cu" "In1.Cu" "In2.Cu" "In3.Cu" "In4.Cu" "In5.Cu" "In6.Cu"
			"In7.Cu" "In8.Cu" "In9.Cu" "In10.Cu" "In11.Cu" "In12.Cu" "In13.Cu" "In14.Cu"
			"In15.Cu" "In16.Cu"
		)
		(hatch none 0.5)
		(connect_pads
			(clearance 0)
		)
		(min_thickness 0.25)
		(keepout
			(tracks not_allowed)
			(vias allowed)
			(pads allowed)
			(copperpour not_allowed)
			(footprints allowed)
		)
		(placement
			(enabled no)
			(sheetname "")
		)
		(fill
			(thermal_gap 0.5)
			(thermal_bridge_width 0.5)
			(island_removal_mode 0)
		)
		(polygon
			(pts
				(arc
					(start 100.063046 -217.162634)
					(mid 100.08273 -217.115224)
					(end 100.089462 -217.064336)
				)
				(arc
					(start 100.089462 -217.064336)
					(mid 100.031806 -216.925142)
					(end 99.892612 -216.867486)
				)
				(arc
					(start 99.892612 -216.867486)
					(mid 99.794181 -216.893902)
					(end 99.722178 -216.966038)
				)
				(arc
					(start 99.252532 -217.780108)
					(mid 99.232848 -217.827518)
					(end 99.226116 -217.878406)
				)
				(arc
					(start 99.226116 -217.878406)
					(mid 99.283772 -218.0176)
					(end 99.422966 -218.075256)
				)
				(arc
					(start 99.422966 -218.075256)
					(mid 99.521397 -218.04884)
					(end 99.5934 -217.976704)
				)
			)
		)
	)
	(zone
		(layers "F.Cu" "B.Cu" "In1.Cu" "In2.Cu" "In3.Cu" "In4.Cu" "In5.Cu" "In6.Cu"
			"In7.Cu" "In8.Cu" "In9.Cu" "In10.Cu" "In11.Cu" "In12.Cu" "In13.Cu" "In14.Cu"
			"In15.Cu" "In16.Cu"
		)
		(hatch none 0.5)
		(connect_pads
			(clearance 0)
		)
		(min_thickness 0.25)
		(keepout
			(tracks not_allowed)
			(vias allowed)
			(pads allowed)
			(copperpour not_allowed)
			(footprints allowed)
		)
		(placement
			(enabled no)
			(sheetname "")
		)
		(fill
			(thermal_gap 0.5)
			(thermal_bridge_width 0.5)
			(island_removal_mode 0)
		)
		(polygon
			(pts
				(arc
					(start 90.275918 -288.917126)
					(mid 90.933778 -288.917126)
					(end 90.275918 -288.917126)
				)
			)
		)
	)
	(zone
		(layers "F.Cu" "B.Cu" "In1.Cu" "In2.Cu" "In3.Cu" "In4.Cu" "In5.Cu" "In6.Cu"
			"In7.Cu" "In8.Cu" "In9.Cu" "In10.Cu" "In11.Cu" "In12.Cu" "In13.Cu" "In14.Cu"
			"In15.Cu" "In16.Cu"
		)
		(hatch none 0.5)
		(connect_pads
			(clearance 0)
		)
		(min_thickness 0.25)
		(keepout
			(tracks not_allowed)
			(vias allowed)
			(pads allowed)
			(copperpour not_allowed)
			(footprints allowed)
		)
		(placement
			(enabled no)
			(sheetname "")
		)
		(fill
			(thermal_gap 0.5)
			(thermal_bridge_width 0.5)
			(island_removal_mode 0)
		)
		(polygon
			(pts
				(arc
					(start 88.785446 -215.338406)
					(mid 88.713457 -215.266247)
					(end 88.615012 -215.239854)
				)
				(arc
					(start 88.615012 -215.239854)
					(mid 88.475818 -215.29751)
					(end 88.418162 -215.436704)
				)
				(arc
					(start 88.418162 -215.436704)
					(mid 88.424919 -215.487585)
					(end 88.444578 -215.535002)
				)
				(arc
					(start 88.914224 -216.348818)
					(mid 88.986213 -216.420977)
					(end 89.084658 -216.44737)
				)
				(arc
					(start 89.084658 -216.44737)
					(mid 89.223852 -216.389714)
					(end 89.281508 -216.25052)
				)
				(arc
					(start 89.281508 -216.25052)
					(mid 89.274751 -216.199639)
					(end 89.255092 -216.152222)
				)
			)
		)
	)
	(zone
		(layers "F.Cu" "B.Cu" "In1.Cu" "In2.Cu" "In3.Cu" "In4.Cu" "In5.Cu" "In6.Cu"
			"In7.Cu" "In8.Cu" "In9.Cu" "In10.Cu" "In11.Cu" "In12.Cu" "In13.Cu" "In14.Cu"
			"In15.Cu" "In16.Cu"
		)
		(hatch none 0.5)
		(connect_pads
			(clearance 0)
		)
		(min_thickness 0.25)
		(keepout
			(tracks not_allowed)
			(vias allowed)
			(pads allowed)
			(copperpour not_allowed)
			(footprints allowed)
		)
		(placement
			(enabled no)
			(sheetname "")
		)
		(fill
			(thermal_gap 0.5)
			(thermal_bridge_width 0.5)
			(island_removal_mode 0)
		)
		(polygon
			(pts
				(arc
					(start 103.433118 -288.917126)
					(mid 104.090978 -288.917126)
					(end 103.433118 -288.917126)
				)
			)
		)
	)
	(zone
		(layers "F.Cu" "B.Cu" "In1.Cu" "In2.Cu" "In3.Cu" "In4.Cu" "In5.Cu" "In6.Cu"
			"In7.Cu" "In8.Cu" "In9.Cu" "In10.Cu" "In11.Cu" "In12.Cu" "In13.Cu" "In14.Cu"
			"In15.Cu" "In16.Cu"
		)
		(hatch none 0.5)
		(connect_pads
			(clearance 0)
		)
		(min_thickness 0.25)
		(keepout
			(tracks not_allowed)
			(vias allowed)
			(pads allowed)
			(copperpour not_allowed)
			(footprints allowed)
		)
		(placement
			(enabled no)
			(sheetname "")
		)
		(fill
			(thermal_gap 0.5)
			(thermal_bridge_width 0.5)
			(island_removal_mode 0)
		)
		(polygon
			(pts
				(arc
					(start 339.64753 -288.831274)
					(mid 339.579822 -288.759423)
					(end 339.484716 -288.732976)
				)
				(arc
					(start 339.484716 -288.732976)
					(mid 339.354502 -288.786912)
					(end 339.300566 -288.917126)
				)
				(arc
					(start 339.300566 -288.917126)
					(mid 339.306017 -288.961347)
					(end 339.321902 -289.002978)
				)
				(arc
					(start 339.791548 -289.892994)
					(mid 339.859256 -289.964845)
					(end 339.954362 -289.991292)
				)
				(arc
					(start 339.954362 -289.991292)
					(mid 340.084576 -289.937356)
					(end 340.138512 -289.807142)
				)
				(arc
					(start 340.138512 -289.807142)
					(mid 340.133061 -289.762921)
					(end 340.117176 -289.72129)
				)
			)
		)
	)
	(zone
		(layers "F.Cu" "B.Cu" "In1.Cu" "In2.Cu" "In3.Cu" "In4.Cu" "In5.Cu" "In6.Cu"
			"In7.Cu" "In8.Cu" "In9.Cu" "In10.Cu" "In11.Cu" "In12.Cu" "In13.Cu" "In14.Cu"
			"In15.Cu" "In16.Cu"
		)
		(hatch none 0.5)
		(connect_pads
			(clearance 0)
		)
		(min_thickness 0.25)
		(keepout
			(tracks not_allowed)
			(vias allowed)
			(pads allowed)
			(copperpour not_allowed)
			(footprints allowed)
		)
		(placement
			(enabled no)
			(sheetname "")
		)
		(fill
			(thermal_gap 0.5)
			(thermal_bridge_width 0.5)
			(island_removal_mode 0)
		)
		(polygon
			(pts
				(arc
					(start 124.027692 -217.97645)
					(mid 124.047376 -217.92904)
					(end 124.054108 -217.878152)
				)
				(arc
					(start 124.054108 -217.878152)
					(mid 123.996452 -217.738958)
					(end 123.857258 -217.681302)
				)
				(arc
					(start 123.857258 -217.681302)
					(mid 123.758827 -217.707718)
					(end 123.686824 -217.779854)
				)
				(arc
					(start 123.217178 -218.593924)
					(mid 123.197494 -218.641334)
					(end 123.190762 -218.692222)
				)
				(arc
					(start 123.190762 -218.692222)
					(mid 123.248418 -218.831416)
					(end 123.387612 -218.889072)
				)
				(arc
					(start 123.387612 -218.889072)
					(mid 123.486043 -218.862656)
					(end 123.558046 -218.79052)
				)
			)
		)
	)
	(zone
		(layers "F.Cu" "B.Cu" "In1.Cu" "In2.Cu" "In3.Cu" "In4.Cu" "In5.Cu" "In6.Cu"
			"In7.Cu" "In8.Cu" "In9.Cu" "In10.Cu" "In11.Cu" "In12.Cu" "In13.Cu" "In14.Cu"
			"In15.Cu" "In16.Cu"
		)
		(hatch none 0.5)
		(connect_pads
			(clearance 0)
		)
		(min_thickness 0.25)
		(keepout
			(tracks not_allowed)
			(vias allowed)
			(pads allowed)
			(copperpour not_allowed)
			(footprints allowed)
		)
		(placement
			(enabled no)
			(sheetname "")
		)
		(fill
			(thermal_gap 0.5)
			(thermal_bridge_width 0.5)
			(island_removal_mode 0)
		)
		(polygon
			(pts
				(arc
					(start 116.668296 -224.389442)
					(mid 116.010436 -224.389442)
					(end 116.668296 -224.389442)
				)
			)
		)
	)
	(zone
		(layers "F.Cu" "B.Cu" "In1.Cu" "In2.Cu" "In3.Cu" "In4.Cu" "In5.Cu" "In6.Cu"
			"In7.Cu" "In8.Cu" "In9.Cu" "In10.Cu" "In11.Cu" "In12.Cu" "In13.Cu" "In14.Cu"
			"In15.Cu" "In16.Cu"
		)
		(hatch none 0.5)
		(connect_pads
			(clearance 0)
		)
		(min_thickness 0.25)
		(keepout
			(tracks not_allowed)
			(vias allowed)
			(pads allowed)
			(copperpour not_allowed)
			(footprints allowed)
		)
		(placement
			(enabled no)
			(sheetname "")
		)
		(fill
			(thermal_gap 0.5)
			(thermal_bridge_width 0.5)
			(island_removal_mode 0)
		)
		(polygon
			(pts
				(arc
					(start 128.837182 -284.74924)
					(mid 128.765193 -284.677081)
					(end 128.666748 -284.650688)
				)
				(arc
					(start 128.666748 -284.650688)
					(mid 128.527554 -284.708344)
					(end 128.469898 -284.847538)
				)
				(arc
					(start 128.469898 -284.847538)
					(mid 128.476655 -284.898419)
					(end 128.496314 -284.945836)
				)
				(arc
					(start 128.96596 -285.759652)
					(mid 129.037949 -285.831811)
					(end 129.136394 -285.858204)
				)
				(arc
					(start 129.136394 -285.858204)
					(mid 129.275588 -285.800548)
					(end 129.333244 -285.661354)
				)
				(arc
					(start 129.333244 -285.661354)
					(mid 129.326487 -285.610473)
					(end 129.306828 -285.563056)
				)
			)
		)
	)
	(zone
		(layers "F.Cu" "B.Cu" "In1.Cu" "In2.Cu" "In3.Cu" "In4.Cu" "In5.Cu" "In6.Cu"
			"In7.Cu" "In8.Cu" "In9.Cu" "In10.Cu" "In11.Cu" "In12.Cu" "In13.Cu" "In14.Cu"
			"In15.Cu" "In16.Cu"
		)
		(hatch none 0.5)
		(connect_pads
			(clearance 0)
		)
		(min_thickness 0.25)
		(keepout
			(tracks not_allowed)
			(vias allowed)
			(pads allowed)
			(copperpour not_allowed)
			(footprints allowed)
		)
		(placement
			(enabled no)
			(sheetname "")
		)
		(fill
			(thermal_gap 0.5)
			(thermal_bridge_width 0.5)
			(island_removal_mode 0)
		)
		(polygon
			(pts
				(arc
					(start 344.872564 -224.389442)
					(mid 344.214704 -224.389442)
					(end 344.872564 -224.389442)
				)
			)
		)
	)
	(zone
		(layers "F.Cu" "B.Cu" "In1.Cu" "In2.Cu" "In3.Cu" "In4.Cu" "In5.Cu" "In6.Cu"
			"In7.Cu" "In8.Cu" "In9.Cu" "In10.Cu" "In11.Cu" "In12.Cu" "In13.Cu" "In14.Cu"
			"In15.Cu" "In16.Cu"
		)
		(hatch none 0.5)
		(connect_pads
			(clearance 0)
		)
		(min_thickness 0.25)
		(keepout
			(tracks not_allowed)
			(vias allowed)
			(pads allowed)
			(copperpour not_allowed)
			(footprints allowed)
		)
		(placement
			(enabled no)
			(sheetname "")
		)
		(fill
			(thermal_gap 0.5)
			(thermal_bridge_width 0.5)
			(island_removal_mode 0)
		)
		(polygon
			(pts
				(arc
					(start 346.123514 -217.162634)
					(mid 346.143198 -217.115224)
					(end 346.14993 -217.064336)
				)
				(arc
					(start 346.14993 -217.064336)
					(mid 346.092274 -216.925142)
					(end 345.95308 -216.867486)
				)
				(arc
					(start 345.95308 -216.867486)
					(mid 345.854649 -216.893902)
					(end 345.782646 -216.966038)
				)
				(arc
					(start 345.313 -217.780108)
					(mid 345.293316 -217.827518)
					(end 345.286584 -217.878406)
				)
				(arc
					(start 345.286584 -217.878406)
					(mid 345.34424 -218.0176)
					(end 345.483434 -218.075256)
				)
				(arc
					(start 345.483434 -218.075256)
					(mid 345.581865 -218.04884)
					(end 345.653868 -217.976704)
				)
			)
		)
	)
	(zone
		(layers "F.Cu" "B.Cu" "In1.Cu" "In2.Cu" "In3.Cu" "In4.Cu" "In5.Cu" "In6.Cu"
			"In7.Cu" "In8.Cu" "In9.Cu" "In10.Cu" "In11.Cu" "In12.Cu" "In13.Cu" "In14.Cu"
			"In15.Cu" "In16.Cu"
		)
		(hatch none 0.5)
		(connect_pads
			(clearance 0)
		)
		(min_thickness 0.25)
		(keepout
			(tracks not_allowed)
			(vias allowed)
			(pads allowed)
			(copperpour not_allowed)
			(footprints allowed)
		)
		(placement
			(enabled no)
			(sheetname "")
		)
		(fill
			(thermal_gap 0.5)
			(thermal_bridge_width 0.5)
			(island_removal_mode 0)
		)
		(polygon
			(pts
				(arc
					(start 111.029496 -217.878406)
					(mid 110.371636 -217.878406)
					(end 111.029496 -217.878406)
				)
			)
		)
	)
	(zone
		(layers "F.Cu" "B.Cu" "In1.Cu" "In2.Cu" "In3.Cu" "In4.Cu" "In5.Cu" "In6.Cu"
			"In7.Cu" "In8.Cu" "In9.Cu" "In10.Cu" "In11.Cu" "In12.Cu" "In13.Cu" "In14.Cu"
			"In15.Cu" "In16.Cu"
		)
		(hatch none 0.5)
		(connect_pads
			(clearance 0)
		)
		(min_thickness 0.25)
		(keepout
			(tracks not_allowed)
			(vias allowed)
			(pads allowed)
			(copperpour not_allowed)
			(footprints allowed)
		)
		(placement
			(enabled no)
			(sheetname "")
		)
		(fill
			(thermal_gap 0.5)
			(thermal_bridge_width 0.5)
			(island_removal_mode 0)
		)
		(polygon
			(pts
				(arc
					(start 93.928438 -400.477228)
					(mid 93.547438 -400.858228)
					(end 93.928438 -401.239228)
				)
				(arc
					(start 94.792038 -401.239228)
					(mid 95.173038 -400.858228)
					(end 94.792038 -400.477228)
				)
			)
		)
	)
	(zone
		(layers "F.Cu" "B.Cu" "In1.Cu" "In2.Cu" "In3.Cu" "In4.Cu" "In5.Cu" "In6.Cu"
			"In7.Cu" "In8.Cu" "In9.Cu" "In10.Cu" "In11.Cu" "In12.Cu" "In13.Cu" "In14.Cu"
			"In15.Cu" "In16.Cu"
		)
		(hatch none 0.5)
		(connect_pads
			(clearance 0)
		)
		(min_thickness 0.25)
		(keepout
			(tracks not_allowed)
			(vias allowed)
			(pads allowed)
			(copperpour not_allowed)
			(footprints allowed)
		)
		(placement
			(enabled no)
			(sheetname "")
		)
		(fill
			(thermal_gap 0.5)
			(thermal_bridge_width 0.5)
			(island_removal_mode 0)
		)
		(polygon
			(pts
				(xy 642.264146 -303.165256) (xy 642.264146 -298.16552) (xy 642.568946 -298.47032) (xy 642.568946 -302.860456)
			)
		)
	)
	(zone
		(layers "F.Cu" "B.Cu" "In1.Cu" "In2.Cu" "In3.Cu" "In4.Cu" "In5.Cu" "In6.Cu"
			"In7.Cu" "In8.Cu" "In9.Cu" "In10.Cu" "In11.Cu" "In12.Cu" "In13.Cu" "In14.Cu"
			"In15.Cu" "In16.Cu"
		)
		(hatch none 0.5)
		(connect_pads
			(clearance 0)
		)
		(min_thickness 0.25)
		(keepout
			(tracks not_allowed)
			(vias allowed)
			(pads allowed)
			(copperpour not_allowed)
			(footprints allowed)
		)
		(placement
			(enabled no)
			(sheetname "")
		)
		(fill
			(thermal_gap 0.5)
			(thermal_bridge_width 0.5)
			(island_removal_mode 0)
		)
		(polygon
			(pts
				(arc
					(start 132.596382 -284.74924)
					(mid 132.524393 -284.677081)
					(end 132.425948 -284.650688)
				)
				(arc
					(start 132.425948 -284.650688)
					(mid 132.286754 -284.708344)
					(end 132.229098 -284.847538)
				)
				(arc
					(start 132.229098 -284.847538)
					(mid 132.235855 -284.898419)
					(end 132.255514 -284.945836)
				)
				(arc
					(start 132.72516 -285.759652)
					(mid 132.797149 -285.831811)
					(end 132.895594 -285.858204)
				)
				(arc
					(start 132.895594 -285.858204)
					(mid 133.034788 -285.800548)
					(end 133.092444 -285.661354)
				)
				(arc
					(start 133.092444 -285.661354)
					(mid 133.085687 -285.610473)
					(end 133.066028 -285.563056)
				)
			)
		)
	)
	(zone
		(layers "F.Cu" "B.Cu" "In1.Cu" "In2.Cu" "In3.Cu" "In4.Cu" "In5.Cu" "In6.Cu"
			"In7.Cu" "In8.Cu" "In9.Cu" "In10.Cu" "In11.Cu" "In12.Cu" "In13.Cu" "In14.Cu"
			"In15.Cu" "In16.Cu"
		)
		(hatch none 0.5)
		(connect_pads
			(clearance 0)
		)
		(min_thickness 0.25)
		(keepout
			(tracks not_allowed)
			(vias allowed)
			(pads allowed)
			(copperpour not_allowed)
			(footprints allowed)
		)
		(placement
			(enabled no)
			(sheetname "")
		)
		(fill
			(thermal_gap 0.5)
			(thermal_bridge_width 0.5)
			(island_removal_mode 0)
		)
		(polygon
			(pts
				(arc
					(start 25.7175 -396.742412)
					(mid 25.3365 -396.361412)
					(end 24.9555 -396.742412)
				)
				(arc
					(start 24.9555 -397.606012)
					(mid 25.3365 -397.987012)
					(end 25.7175 -397.606012)
				)
			)
		)
	)
	(zone
		(layers "F.Cu" "B.Cu" "In1.Cu" "In2.Cu" "In3.Cu" "In4.Cu" "In5.Cu" "In6.Cu"
			"In7.Cu" "In8.Cu" "In9.Cu" "In10.Cu" "In11.Cu" "In12.Cu" "In13.Cu" "In14.Cu"
			"In15.Cu" "In16.Cu"
		)
		(hatch none 0.5)
		(connect_pads
			(clearance 0)
		)
		(min_thickness 0.25)
		(keepout
			(tracks not_allowed)
			(vias allowed)
			(pads allowed)
			(copperpour not_allowed)
			(footprints allowed)
		)
		(placement
			(enabled no)
			(sheetname "")
		)
		(fill
			(thermal_gap 0.5)
			(thermal_bridge_width 0.5)
			(island_removal_mode 0)
		)
		(polygon
			(pts
				(arc
					(start 91.293696 -217.878406)
					(mid 90.635836 -217.878406)
					(end 91.293696 -217.878406)
				)
			)
		)
	)
	(zone
		(layers "F.Cu" "B.Cu" "In1.Cu" "In2.Cu" "In3.Cu" "In4.Cu" "In5.Cu" "In6.Cu"
			"In7.Cu" "In8.Cu" "In9.Cu" "In10.Cu" "In11.Cu" "In12.Cu" "In13.Cu" "In14.Cu"
			"In15.Cu" "In16.Cu"
		)
		(hatch none 0.5)
		(connect_pads
			(clearance 0)
		)
		(min_thickness 0.25)
		(keepout
			(tracks not_allowed)
			(vias allowed)
			(pads allowed)
			(copperpour not_allowed)
			(footprints allowed)
		)
		(placement
			(enabled no)
			(sheetname "")
		)
		(fill
			(thermal_gap 0.5)
			(thermal_bridge_width 0.5)
			(island_removal_mode 0)
		)
		(polygon
			(pts
				(arc
					(start 412.393384 -17.220438)
					(mid 412.012384 -17.601438)
					(end 412.393384 -17.982438)
				)
				(arc
					(start 413.256984 -17.982438)
					(mid 413.637984 -17.601438)
					(end 413.256984 -17.220438)
				)
			)
		)
	)
	(zone
		(layers "F.Cu" "B.Cu" "In1.Cu" "In2.Cu" "In3.Cu" "In4.Cu" "In5.Cu" "In6.Cu"
			"In7.Cu" "In8.Cu" "In9.Cu" "In10.Cu" "In11.Cu" "In12.Cu" "In13.Cu" "In14.Cu"
			"In15.Cu" "In16.Cu"
		)
		(hatch none 0.5)
		(connect_pads
			(clearance 0)
		)
		(min_thickness 0.25)
		(keepout
			(tracks not_allowed)
			(vias allowed)
			(pads allowed)
			(copperpour not_allowed)
			(footprints allowed)
		)
		(placement
			(enabled no)
			(sheetname "")
		)
		(fill
			(thermal_gap 0.5)
			(thermal_bridge_width 0.5)
			(island_removal_mode 0)
		)
		(polygon
			(pts
				(arc
					(start 164.386514 -409.649168)
					(mid 164.005514 -410.030168)
					(end 164.386514 -410.411168)
				)
				(arc
					(start 165.250114 -410.411168)
					(mid 165.631114 -410.030168)
					(end 165.250114 -409.649168)
				)
			)
		)
	)
	(zone
		(layers "F.Cu" "B.Cu" "In1.Cu" "In2.Cu" "In3.Cu" "In4.Cu" "In5.Cu" "In6.Cu"
			"In7.Cu" "In8.Cu" "In9.Cu" "In10.Cu" "In11.Cu" "In12.Cu" "In13.Cu" "In14.Cu"
			"In15.Cu" "In16.Cu"
		)
		(hatch none 0.5)
		(connect_pads
			(clearance 0)
		)
		(min_thickness 0.25)
		(keepout
			(tracks not_allowed)
			(vias allowed)
			(pads allowed)
			(copperpour not_allowed)
			(footprints allowed)
		)
		(placement
			(enabled no)
			(sheetname "")
		)
		(fill
			(thermal_gap 0.5)
			(thermal_bridge_width 0.5)
			(island_removal_mode 0)
		)
		(polygon
			(pts
				(arc
					(start 347.331792 -285.661354)
					(mid 346.673932 -285.661354)
					(end 347.331792 -285.661354)
				)
			)
		)
	)
	(zone
		(layers "F.Cu" "B.Cu" "In1.Cu" "In2.Cu" "In3.Cu" "In4.Cu" "In5.Cu" "In6.Cu"
			"In7.Cu" "In8.Cu" "In9.Cu" "In10.Cu" "In11.Cu" "In12.Cu" "In13.Cu" "In14.Cu"
			"In15.Cu" "In16.Cu"
		)
		(hatch none 0.5)
		(connect_pads
			(clearance 0)
		)
		(min_thickness 0.25)
		(keepout
			(tracks not_allowed)
			(vias allowed)
			(pads allowed)
			(copperpour not_allowed)
			(footprints allowed)
		)
		(placement
			(enabled no)
			(sheetname "")
		)
		(fill
			(thermal_gap 0.5)
			(thermal_bridge_width 0.5)
			(island_removal_mode 0)
		)
		(polygon
			(pts
				(arc
					(start 91.215718 -285.661354)
					(mid 91.873578 -285.661354)
					(end 91.215718 -285.661354)
				)
			)
		)
	)
	(zone
		(layers "F.Cu" "B.Cu" "In1.Cu" "In2.Cu" "In3.Cu" "In4.Cu" "In5.Cu" "In6.Cu"
			"In7.Cu" "In8.Cu" "In9.Cu" "In10.Cu" "In11.Cu" "In12.Cu" "In13.Cu" "In14.Cu"
			"In15.Cu" "In16.Cu"
		)
		(hatch none 0.5)
		(connect_pads
			(clearance 0)
		)
		(min_thickness 0.25)
		(keepout
			(tracks not_allowed)
			(vias allowed)
			(pads allowed)
			(copperpour not_allowed)
			(footprints allowed)
		)
		(placement
			(enabled no)
			(sheetname "")
		)
		(fill
			(thermal_gap 0.5)
			(thermal_bridge_width 0.5)
			(island_removal_mode 0)
		)
		(polygon
			(pts
				(arc
					(start 385.02209 -406.62352)
					(mid 384.64109 -407.00452)
					(end 385.02209 -407.38552)
				)
				(arc
					(start 385.88569 -407.38552)
					(mid 386.26669 -407.00452)
					(end 385.88569 -406.62352)
				)
			)
		)
	)
	(zone
		(layers "F.Cu" "B.Cu" "In1.Cu" "In2.Cu" "In3.Cu" "In4.Cu" "In5.Cu" "In6.Cu"
			"In7.Cu" "In8.Cu" "In9.Cu" "In10.Cu" "In11.Cu" "In12.Cu" "In13.Cu" "In14.Cu"
			"In15.Cu" "In16.Cu"
		)
		(hatch none 0.5)
		(connect_pads
			(clearance 0)
		)
		(min_thickness 0.25)
		(keepout
			(tracks not_allowed)
			(vias allowed)
			(pads allowed)
			(copperpour not_allowed)
			(footprints allowed)
		)
		(placement
			(enabled no)
			(sheetname "")
		)
		(fill
			(thermal_gap 0.5)
			(thermal_bridge_width 0.5)
			(island_removal_mode 0)
		)
		(polygon
			(pts
				(xy 28.580842 -441.790074) (xy 23.580852 -441.790074) (xy 23.885652 -441.485274) (xy 28.276042 -441.485274)
			)
		)
	)
	(zone
		(layers "F.Cu" "B.Cu" "In1.Cu" "In2.Cu" "In3.Cu" "In4.Cu" "In5.Cu" "In6.Cu"
			"In7.Cu" "In8.Cu" "In9.Cu" "In10.Cu" "In11.Cu" "In12.Cu" "In13.Cu" "In14.Cu"
			"In15.Cu" "In16.Cu"
		)
		(hatch none 0.5)
		(connect_pads
			(clearance 0)
		)
		(min_thickness 0.25)
		(keepout
			(tracks not_allowed)
			(vias allowed)
			(pads allowed)
			(copperpour not_allowed)
			(footprints allowed)
		)
		(placement
			(enabled no)
			(sheetname "")
		)
		(fill
			(thermal_gap 0.5)
			(thermal_bridge_width 0.5)
			(island_removal_mode 0)
		)
		(polygon
			(pts
				(arc
					(start 348.16161 -223.575626)
					(mid 347.50375 -223.575626)
					(end 348.16161 -223.575626)
				)
			)
		)
	)
	(zone
		(layers "F.Cu" "B.Cu" "In1.Cu" "In2.Cu" "In3.Cu" "In4.Cu" "In5.Cu" "In6.Cu"
			"In7.Cu" "In8.Cu" "In9.Cu" "In10.Cu" "In11.Cu" "In12.Cu" "In13.Cu" "In14.Cu"
			"In15.Cu" "In16.Cu"
		)
		(hatch none 0.5)
		(connect_pads
			(clearance 0)
		)
		(min_thickness 0.25)
		(keepout
			(tracks not_allowed)
			(vias allowed)
			(pads allowed)
			(copperpour not_allowed)
			(footprints allowed)
		)
		(placement
			(enabled no)
			(sheetname "")
		)
		(fill
			(thermal_gap 0.5)
			(thermal_bridge_width 0.5)
			(island_removal_mode 0)
		)
		(polygon
			(pts
				(arc
					(start 335.182972 -81.171542)
					(mid 335.563972 -80.790542)
					(end 335.182972 -80.409542)
				)
				(arc
					(start 334.319372 -80.409542)
					(mid 333.938372 -80.790542)
					(end 334.319372 -81.171542)
				)
			)
		)
	)
	(zone
		(layers "F.Cu" "B.Cu" "In1.Cu" "In2.Cu" "In3.Cu" "In4.Cu" "In5.Cu" "In6.Cu"
			"In7.Cu" "In8.Cu" "In9.Cu" "In10.Cu" "In11.Cu" "In12.Cu" "In13.Cu" "In14.Cu"
			"In15.Cu" "In16.Cu"
		)
		(hatch none 0.5)
		(connect_pads
			(clearance 0)
		)
		(min_thickness 0.25)
		(keepout
			(tracks not_allowed)
			(vias allowed)
			(pads allowed)
			(copperpour not_allowed)
			(footprints allowed)
		)
		(placement
			(enabled no)
			(sheetname "")
		)
		(fill
			(thermal_gap 0.5)
			(thermal_bridge_width 0.5)
			(island_removal_mode 0)
		)
		(polygon
			(pts
				(arc
					(start 103.040942 -221.94774)
					(mid 102.383082 -221.94774)
					(end 103.040942 -221.94774)
				)
			)
		)
	)
	(zone
		(layers "F.Cu" "B.Cu" "In1.Cu" "In2.Cu" "In3.Cu" "In4.Cu" "In5.Cu" "In6.Cu"
			"In7.Cu" "In8.Cu" "In9.Cu" "In10.Cu" "In11.Cu" "In12.Cu" "In13.Cu" "In14.Cu"
			"In15.Cu" "In16.Cu"
		)
		(hatch none 0.5)
		(connect_pads
			(clearance 0)
		)
		(min_thickness 0.25)
		(keepout
			(tracks not_allowed)
			(vias allowed)
			(pads allowed)
			(copperpour not_allowed)
			(footprints allowed)
		)
		(placement
			(enabled no)
			(sheetname "")
		)
		(fill
			(thermal_gap 0.5)
			(thermal_bridge_width 0.5)
			(island_removal_mode 0)
		)
		(polygon
			(pts
				(arc
					(start 135.386318 -288.917126)
					(mid 136.044178 -288.917126)
					(end 135.386318 -288.917126)
				)
			)
		)
	)
	(zone
		(layers "F.Cu" "B.Cu" "In1.Cu" "In2.Cu" "In3.Cu" "In4.Cu" "In5.Cu" "In6.Cu"
			"In7.Cu" "In8.Cu" "In9.Cu" "In10.Cu" "In11.Cu" "In12.Cu" "In13.Cu" "In14.Cu"
			"In15.Cu" "In16.Cu"
		)
		(hatch none 0.5)
		(connect_pads
			(clearance 0)
		)
		(min_thickness 0.25)
		(keepout
			(tracks not_allowed)
			(vias allowed)
			(pads allowed)
			(copperpour not_allowed)
			(footprints allowed)
		)
		(placement
			(enabled no)
			(sheetname "")
		)
		(fill
			(thermal_gap 0.5)
			(thermal_bridge_width 0.5)
			(island_removal_mode 0)
		)
		(polygon
			(pts
				(arc
					(start 344.982546 -279.964134)
					(mid 344.324686 -279.964134)
					(end 344.982546 -279.964134)
				)
			)
		)
	)
	(zone
		(layers "F.Cu" "B.Cu" "In1.Cu" "In2.Cu" "In3.Cu" "In4.Cu" "In5.Cu" "In6.Cu"
			"In7.Cu" "In8.Cu" "In9.Cu" "In10.Cu" "In11.Cu" "In12.Cu" "In13.Cu" "In14.Cu"
			"In15.Cu" "In16.Cu"
		)
		(hatch none 0.5)
		(connect_pads
			(clearance 0)
		)
		(min_thickness 0.25)
		(keepout
			(tracks not_allowed)
			(vias allowed)
			(pads allowed)
			(copperpour not_allowed)
			(footprints allowed)
		)
		(placement
			(enabled no)
			(sheetname "")
		)
		(fill
			(thermal_gap 0.5)
			(thermal_bridge_width 0.5)
			(island_removal_mode 0)
		)
		(polygon
			(pts
				(arc
					(start 355.05136 -214.720932)
					(mid 355.071044 -214.673522)
					(end 355.077776 -214.622634)
				)
				(arc
					(start 355.077776 -214.622634)
					(mid 355.02012 -214.48344)
					(end 354.880926 -214.425784)
				)
				(arc
					(start 354.880926 -214.425784)
					(mid 354.782495 -214.4522)
					(end 354.710492 -214.524336)
				)
				(arc
					(start 354.240846 -215.338406)
					(mid 354.221162 -215.385816)
					(end 354.21443 -215.436704)
				)
				(arc
					(start 354.21443 -215.436704)
					(mid 354.272086 -215.575898)
					(end 354.41128 -215.633554)
				)
				(arc
					(start 354.41128 -215.633554)
					(mid 354.509711 -215.607138)
					(end 354.581714 -215.535002)
				)
			)
		)
	)
	(zone
		(layers "F.Cu" "B.Cu" "In1.Cu" "In2.Cu" "In3.Cu" "In4.Cu" "In5.Cu" "In6.Cu"
			"In7.Cu" "In8.Cu" "In9.Cu" "In10.Cu" "In11.Cu" "In12.Cu" "In13.Cu" "In14.Cu"
			"In15.Cu" "In16.Cu"
		)
		(hatch none 0.5)
		(connect_pads
			(clearance 0)
		)
		(min_thickness 0.25)
		(keepout
			(tracks not_allowed)
			(vias allowed)
			(pads allowed)
			(copperpour not_allowed)
			(footprints allowed)
		)
		(placement
			(enabled no)
			(sheetname "")
		)
		(fill
			(thermal_gap 0.5)
			(thermal_bridge_width 0.5)
			(island_removal_mode 0)
		)
		(polygon
			(pts
				(arc
					(start 112.750092 -221.231968)
					(mid 112.769776 -221.184558)
					(end 112.776508 -221.13367)
				)
				(arc
					(start 112.776508 -221.13367)
					(mid 112.718852 -220.994476)
					(end 112.579658 -220.93682)
				)
				(arc
					(start 112.579658 -220.93682)
					(mid 112.481227 -220.963236)
					(end 112.409224 -221.035372)
				)
				(arc
					(start 111.939578 -221.849442)
					(mid 111.919894 -221.896852)
					(end 111.913162 -221.94774)
				)
				(arc
					(start 111.913162 -221.94774)
					(mid 111.970818 -222.086934)
					(end 112.110012 -222.14459)
				)
				(arc
					(start 112.110012 -222.14459)
					(mid 112.208443 -222.118174)
					(end 112.280446 -222.046038)
				)
			)
		)
	)
	(zone
		(layers "F.Cu" "B.Cu" "In1.Cu" "In2.Cu" "In3.Cu" "In4.Cu" "In5.Cu" "In6.Cu"
			"In7.Cu" "In8.Cu" "In9.Cu" "In10.Cu" "In11.Cu" "In12.Cu" "In13.Cu" "In14.Cu"
			"In15.Cu" "In16.Cu"
		)
		(hatch none 0.5)
		(connect_pads
			(clearance 0)
		)
		(min_thickness 0.25)
		(keepout
			(tracks not_allowed)
			(vias allowed)
			(pads allowed)
			(copperpour not_allowed)
			(footprints allowed)
		)
		(placement
			(enabled no)
			(sheetname "")
		)
		(fill
			(thermal_gap 0.5)
			(thermal_bridge_width 0.5)
			(island_removal_mode 0)
		)
		(polygon
			(pts
				(arc
					(start 128.885188 -214.622634)
					(mid 128.227328 -214.622634)
					(end 128.885188 -214.622634)
				)
			)
		)
	)
	(zone
		(layers "F.Cu" "B.Cu" "In1.Cu" "In2.Cu" "In3.Cu" "In4.Cu" "In5.Cu" "In6.Cu"
			"In7.Cu" "In8.Cu" "In9.Cu" "In10.Cu" "In11.Cu" "In12.Cu" "In13.Cu" "In14.Cu"
			"In15.Cu" "In16.Cu"
		)
		(name "Route Keepin")
		(hatch none 0.5)
		(connect_pads
			(clearance 0)
		)
		(min_thickness 0.25)
		(keepout
			(tracks allowed)
			(vias allowed)
			(pads allowed)
			(copperpour allowed)
			(footprints allowed)
		)
		(placement
			(enabled no)
			(sheetname "")
		)
		(fill
			(thermal_gap 0.5)
			(thermal_bridge_width 0.5)
			(island_removal_mode 0)
		)
		(polygon
			(pts
				(arc
					(start 83.70189 -12.288012)
					(mid 81.928469 -11.553437)
					(end 81.193894 -9.780016)
				)
				(xy 81.193894 -1.107948)
				(arc
					(start 81.193894 -0.999998)
					(mid 81.049791 -0.652103)
					(end 80.701896 -0.508)
				)
				(arc
					(start 14.10208 -0.508)
					(mid 13.754185 -0.652103)
					(end 13.610082 -0.999998)
				)
				(xy 13.610082 -1.107948)
				(arc
					(start 13.610082 -9.780016)
					(mid 12.875507 -11.553437)
					(end 11.102086 -12.288012)
				)
				(arc
					(start 1.999996 -12.288012)
					(mid 0.944996 -12.725008)
					(end 0.508 -13.780008)
				)
				(arc
					(start 0.508 -77.671676)
					(mid 0.621537 -78.242555)
					(end 0.94488 -78.726538)
				)
				(arc
					(start 1.773428 -79.555086)
					(mid 2.317017 -80.368625)
					(end 2.507996 -81.32826)
				)
				(arc
					(start 2.507996 -403.371812)
					(mid 2.621533 -403.942691)
					(end 2.944876 -404.426674)
				)
				(arc
					(start 6.273292 -407.75509)
					(mid 6.817101 -408.568585)
					(end 7.008114 -409.528264)
				)
				(xy 7.008114 -425.53382) (xy 7.008114 -425.829984)
				(arc
					(start 7.008114 -439.989976)
					(mid 7.44511 -441.044976)
					(end 8.50011 -441.481972)
				)
				(xy 194.496944 -441.481972)
				(arc
					(start 194.496944 -441.17006)
					(mid 194.792217 -440.457207)
					(end 195.50507 -440.161934)
				)
				(arc
					(start 276.314916 -440.161934)
					(mid 277.027769 -440.457207)
					(end 277.323042 -441.17006)
				)
				(xy 277.323042 -441.481972) (xy 450.202554 -441.481972) (xy 450.683884 -441.481972)
				(arc
					(start 463.300064 -441.481972)
					(mid 464.355064 -441.044976)
					(end 464.79206 -439.989976)
				)
				(xy 464.79206 -425.174664) (xy 464.79206 -424.86834) (xy 464.79206 -419.237668) (xy 467.52256 -419.237668)
				(xy 467.52256 -440.568588) (xy 468.68334 -441.729368) (xy 472.63304 -441.729368) (xy 474.07322 -443.169548)
				(xy 474.07322 -461.582008) (xy 475.24416 -462.752948) (xy 532.3205 -462.752948) (xy 533.48636 -461.587088)
				(xy 533.48636 -454.218548) (xy 532.4602 -453.192388) (xy 515.17042 -453.192388) (xy 513.86994 -451.891908)
				(xy 513.86994 -311.480708) (xy 515.24154 -310.109108) (xy 532.4221 -310.109108) (xy 533.5651 -308.966108)
				(xy 533.5651 11.033252) (xy 532.45512 12.143232) (xy 475.2086 12.143232) (xy 473.95892 10.893552)
				(xy 473.95892 -79.390748) (xy 470.47404 -82.875628) (xy 470.47404 -406.542748) (xy 467.54542 -409.471368)
				(xy 467.54542 -418.851588) (xy 464.79206 -418.851588)
				(arc
					(start 464.79206 -409.528264)
					(mid 464.98295 -408.568593)
					(end 465.526628 -407.75509)
				)
				(arc
					(start 467.355174 -405.926544)
					(mid 467.678502 -405.442555)
					(end 467.792054 -404.871682)
				)
				(arc
					(start 467.792054 -82.82813)
					(mid 467.983012 -81.868498)
					(end 468.526622 -81.054956)
				)
				(arc
					(start 470.85504 -78.726538)
					(mid 471.178368 -78.242549)
					(end 471.29192 -77.671676)
				)
				(arc
					(start 471.29192 -13.780008)
					(mid 470.854924 -12.725008)
					(end 469.799924 -12.288012)
				)
				(xy 464.61426 -12.288012) (xy 464.61426 -9.451848) (xy 470.50198 -9.451848) (xy 471.52052 -8.433308)
				(xy 471.52052 10.959592) (xy 470.28862 12.191492) (xy 1.37668 12.191492) (xy 0.26416 11.078972)
				(xy 0.26416 -8.410448) (xy 1.35128 -9.497568) (xy 9.77138 -9.497568) (xy 10.86104 -8.407908) (xy 10.86104 1.170432)
				(xy 12.34948 2.658872) (xy 82.4738 2.658872) (xy 84.0105 1.122172) (xy 84.0105 -8.527288) (xy 85.0519 -9.568688)
				(xy 122.65152 -9.568688) (xy 123.88342 -8.336788) (xy 123.88342 -4.059428) (xy 125.30582 -2.637028)
				(xy 195.47332 -2.637028) (xy 197.05828 -4.221988) (xy 197.05828 -8.504428) (xy 198.05142 -9.497568)
				(xy 224.06864 -9.497568) (xy 225.53422 -10.963148) (xy 225.53422 -30.925008) (xy 227.667058 -33.057846)
				(xy 254.356362 -33.057846) (xy 256.49174 -30.922468) (xy 256.49174 -11.067288) (xy 258.0386 -9.520428)
				(xy 384.20294 -9.520428) (xy 385.36118 -8.362188) (xy 385.36118 1.193292) (xy 386.87502 2.707132)
				(xy 456.95108 2.707132) (xy 458.41666 1.241552) (xy 458.41666 -8.242808) (xy 459.62316 -9.449308)
				(xy 464.27136 -9.449308) (xy 464.27136 -12.288012)
				(arc
					(start 458.20203 -12.288012)
					(mid 456.428609 -11.553437)
					(end 455.694034 -9.780016)
				)
				(xy 455.694034 -1.107948)
				(arc
					(start 455.694034 -0.999998)
					(mid 455.549931 -0.652103)
					(end 455.202036 -0.508)
				)
				(arc
					(start 388.601966 -0.508)
					(mid 388.254071 -0.652103)
					(end 388.109968 -0.999998)
				)
				(xy 388.109968 -1.107948)
				(arc
					(start 388.109968 -9.780016)
					(mid 387.375393 -11.553437)
					(end 385.601972 -12.288012)
				)
				(arc
					(start 260.800088 -12.288012)
					(mid 259.745088 -12.725008)
					(end 259.308092 -13.780008)
				)
				(xy 259.308092 -32.275018)
				(arc
					(start 259.308092 -33.275016)
					(mid 258.573517 -35.048437)
					(end 256.800096 -35.783012)
				)
				(arc
					(start 225.300032 -35.783012)
					(mid 223.526611 -35.048437)
					(end 222.792036 -33.275016)
				)
				(xy 222.792036 -32.275018)
				(arc
					(start 222.792036 -13.780008)
					(mid 222.35504 -12.725008)
					(end 221.30004 -12.288012)
				)
				(arc
					(start 196.701918 -12.288012)
					(mid 194.928497 -11.553437)
					(end 194.193922 -9.780016)
				)
				(xy 194.193922 -6.387846)
				(arc
					(start 194.193922 -6.279896)
					(mid 194.049819 -5.932001)
					(end 193.701924 -5.787898)
				)
				(arc
					(start 127.102108 -5.787898)
					(mid 126.754213 -5.932001)
					(end 126.61011 -6.279896)
				)
				(xy 126.61011 -6.387846)
				(arc
					(start 126.61011 -9.780016)
					(mid 125.875535 -11.553437)
					(end 124.102114 -12.288012)
				)
			)
		)
	)
	(zone
		(layers "F.Cu" "B.Cu" "In1.Cu" "In2.Cu" "In3.Cu" "In4.Cu" "In5.Cu" "In6.Cu"
			"In7.Cu" "In8.Cu" "In9.Cu" "In10.Cu" "In11.Cu" "In12.Cu" "In13.Cu" "In14.Cu"
			"In15.Cu" "In16.Cu"
		)
		(hatch none 0.5)
		(connect_pads
			(clearance 0)
		)
		(min_thickness 0.25)
		(keepout
			(tracks not_allowed)
			(vias allowed)
			(pads allowed)
			(copperpour not_allowed)
			(footprints allowed)
		)
		(placement
			(enabled no)
			(sheetname "")
		)
		(fill
			(thermal_gap 0.5)
			(thermal_bridge_width 0.5)
			(island_removal_mode 0)
		)
		(polygon
			(pts
				(arc
					(start 378.815346 -288.103056)
					(mid 378.157486 -288.103056)
					(end 378.815346 -288.103056)
				)
			)
		)
	)
	(zone
		(layers "F.Cu" "B.Cu" "In1.Cu" "In2.Cu" "In3.Cu" "In4.Cu" "In5.Cu" "In6.Cu"
			"In7.Cu" "In8.Cu" "In9.Cu" "In10.Cu" "In11.Cu" "In12.Cu" "In13.Cu" "In14.Cu"
			"In15.Cu" "In16.Cu"
		)
		(hatch none 0.5)
		(connect_pads
			(clearance 0)
		)
		(min_thickness 0.25)
		(keepout
			(tracks not_allowed)
			(vias allowed)
			(pads allowed)
			(copperpour not_allowed)
			(footprints allowed)
		)
		(placement
			(enabled no)
			(sheetname "")
		)
		(fill
			(thermal_gap 0.5)
			(thermal_bridge_width 0.5)
			(island_removal_mode 0)
		)
		(polygon
			(pts
				(arc
					(start 378.23521 -223.575626)
					(mid 377.57735 -223.575626)
					(end 378.23521 -223.575626)
				)
			)
		)
	)
	(zone
		(layers "F.Cu" "B.Cu" "In1.Cu" "In2.Cu" "In3.Cu" "In4.Cu" "In5.Cu" "In6.Cu"
			"In7.Cu" "In8.Cu" "In9.Cu" "In10.Cu" "In11.Cu" "In12.Cu" "In13.Cu" "In14.Cu"
			"In15.Cu" "In16.Cu"
		)
		(hatch none 0.5)
		(connect_pads
			(clearance 0)
		)
		(min_thickness 0.25)
		(keepout
			(tracks not_allowed)
			(vias allowed)
			(pads allowed)
			(copperpour not_allowed)
			(footprints allowed)
		)
		(placement
			(enabled no)
			(sheetname "")
		)
		(fill
			(thermal_gap 0.5)
			(thermal_bridge_width 0.5)
			(island_removal_mode 0)
		)
		(polygon
			(pts
				(arc
					(start 378.546868 -224.291144)
					(mid 378.474879 -224.218985)
					(end 378.376434 -224.192592)
				)
				(arc
					(start 378.376434 -224.192592)
					(mid 378.23724 -224.250248)
					(end 378.179584 -224.389442)
				)
				(arc
					(start 378.179584 -224.389442)
					(mid 378.186341 -224.440323)
					(end 378.206 -224.48774)
				)
				(arc
					(start 378.675646 -225.301556)
					(mid 378.747635 -225.373715)
					(end 378.84608 -225.400108)
				)
				(arc
					(start 378.84608 -225.400108)
					(mid 378.985274 -225.342452)
					(end 379.04293 -225.203258)
				)
				(arc
					(start 379.04293 -225.203258)
					(mid 379.036173 -225.152377)
					(end 379.016514 -225.10496)
				)
			)
		)
	)
	(zone
		(layers "F.Cu" "B.Cu" "In1.Cu" "In2.Cu" "In3.Cu" "In4.Cu" "In5.Cu" "In6.Cu"
			"In7.Cu" "In8.Cu" "In9.Cu" "In10.Cu" "In11.Cu" "In12.Cu" "In13.Cu" "In14.Cu"
			"In15.Cu" "In16.Cu"
		)
		(hatch none 0.5)
		(connect_pads
			(clearance 0)
		)
		(min_thickness 0.25)
		(keepout
			(tracks not_allowed)
			(vias allowed)
			(pads allowed)
			(copperpour not_allowed)
			(footprints allowed)
		)
		(placement
			(enabled no)
			(sheetname "")
		)
		(fill
			(thermal_gap 0.5)
			(thermal_bridge_width 0.5)
			(island_removal_mode 0)
		)
		(polygon
			(pts
				(arc
					(start 431.855118 -6.339586)
					(mid 431.474118 -6.720586)
					(end 431.855118 -7.101586)
				)
				(arc
					(start 432.718718 -7.101586)
					(mid 433.099718 -6.720586)
					(end 432.718718 -6.339586)
				)
			)
		)
	)
	(zone
		(layers "F.Cu" "B.Cu" "In1.Cu" "In2.Cu" "In3.Cu" "In4.Cu" "In5.Cu" "In6.Cu"
			"In7.Cu" "In8.Cu" "In9.Cu" "In10.Cu" "In11.Cu" "In12.Cu" "In13.Cu" "In14.Cu"
			"In15.Cu" "In16.Cu"
		)
		(hatch none 0.5)
		(connect_pads
			(clearance 0)
		)
		(min_thickness 0.25)
		(keepout
			(tracks not_allowed)
			(vias allowed)
			(pads allowed)
			(copperpour not_allowed)
			(footprints allowed)
		)
		(placement
			(enabled no)
			(sheetname "")
		)
		(fill
			(thermal_gap 0.5)
			(thermal_bridge_width 0.5)
			(island_removal_mode 0)
		)
		(polygon
			(pts
				(arc
					(start 94.582996 -213.732618)
					(mid 93.925136 -213.732618)
					(end 94.582996 -213.732618)
				)
			)
		)
	)
	(zone
		(layers "F.Cu" "B.Cu" "In1.Cu" "In2.Cu" "In3.Cu" "In4.Cu" "In5.Cu" "In6.Cu"
			"In7.Cu" "In8.Cu" "In9.Cu" "In10.Cu" "In11.Cu" "In12.Cu" "In13.Cu" "In14.Cu"
			"In15.Cu" "In16.Cu"
		)
		(hatch none 0.5)
		(connect_pads
			(clearance 0)
		)
		(min_thickness 0.25)
		(keepout
			(tracks not_allowed)
			(vias allowed)
			(pads allowed)
			(copperpour not_allowed)
			(footprints allowed)
		)
		(placement
			(enabled no)
			(sheetname "")
		)
		(fill
			(thermal_gap 0.5)
			(thermal_bridge_width 0.5)
			(island_removal_mode 0)
		)
		(polygon
			(pts
				(arc
					(start 348.16161 -220.319854)
					(mid 347.50375 -220.319854)
					(end 348.16161 -220.319854)
				)
			)
		)
	)
	(zone
		(layers "F.Cu" "B.Cu" "In1.Cu" "In2.Cu" "In3.Cu" "In4.Cu" "In5.Cu" "In6.Cu"
			"In7.Cu" "In8.Cu" "In9.Cu" "In10.Cu" "In11.Cu" "In12.Cu" "In13.Cu" "In14.Cu"
			"In15.Cu" "In16.Cu"
		)
		(hatch none 0.5)
		(connect_pads
			(clearance 0)
		)
		(min_thickness 0.25)
		(keepout
			(tracks not_allowed)
			(vias allowed)
			(pads allowed)
			(copperpour not_allowed)
			(footprints allowed)
		)
		(placement
			(enabled no)
			(sheetname "")
		)
		(fill
			(thermal_gap 0.5)
			(thermal_bridge_width 0.5)
			(island_removal_mode 0)
		)
		(polygon
			(pts
				(arc
					(start 125.078236 -288.005012)
					(mid 125.006247 -287.932853)
					(end 124.907802 -287.90646)
				)
				(arc
					(start 124.907802 -287.90646)
					(mid 124.768608 -287.964116)
					(end 124.710952 -288.10331)
				)
				(arc
					(start 124.710952 -288.10331)
					(mid 124.717709 -288.154191)
					(end 124.737368 -288.201608)
				)
				(arc
					(start 125.207014 -289.015424)
					(mid 125.279003 -289.087583)
					(end 125.377448 -289.113976)
				)
				(arc
					(start 125.377448 -289.113976)
					(mid 125.516642 -289.05632)
					(end 125.574298 -288.917126)
				)
				(arc
					(start 125.574298 -288.917126)
					(mid 125.567541 -288.866245)
					(end 125.547882 -288.818828)
				)
			)
		)
	)
	(zone
		(layers "F.Cu" "B.Cu" "In1.Cu" "In2.Cu" "In3.Cu" "In4.Cu" "In5.Cu" "In6.Cu"
			"In7.Cu" "In8.Cu" "In9.Cu" "In10.Cu" "In11.Cu" "In12.Cu" "In13.Cu" "In14.Cu"
			"In15.Cu" "In16.Cu"
		)
		(hatch none 0.5)
		(connect_pads
			(clearance 0)
		)
		(min_thickness 0.25)
		(keepout
			(tracks not_allowed)
			(vias allowed)
			(pads allowed)
			(copperpour not_allowed)
			(footprints allowed)
		)
		(placement
			(enabled no)
			(sheetname "")
		)
		(fill
			(thermal_gap 0.5)
			(thermal_bridge_width 0.5)
			(island_removal_mode 0)
		)
		(polygon
			(pts
				(arc
					(start 120.739154 -220.22181)
					(mid 120.667165 -220.149651)
					(end 120.56872 -220.123258)
				)
				(arc
					(start 120.56872 -220.123258)
					(mid 120.429526 -220.180914)
					(end 120.37187 -220.320108)
				)
				(arc
					(start 120.37187 -220.320108)
					(mid 120.378627 -220.370989)
					(end 120.398286 -220.418406)
				)
				(arc
					(start 120.867932 -221.232222)
					(mid 120.939921 -221.304381)
					(end 121.038366 -221.330774)
				)
				(arc
					(start 121.038366 -221.330774)
					(mid 121.17756 -221.273118)
					(end 121.235216 -221.133924)
				)
				(arc
					(start 121.235216 -221.133924)
					(mid 121.228459 -221.083043)
					(end 121.2088 -221.035626)
				)
			)
		)
	)
	(zone
		(layers "F.Cu" "B.Cu" "In1.Cu" "In2.Cu" "In3.Cu" "In4.Cu" "In5.Cu" "In6.Cu"
			"In7.Cu" "In8.Cu" "In9.Cu" "In10.Cu" "In11.Cu" "In12.Cu" "In13.Cu" "In14.Cu"
			"In15.Cu" "In16.Cu"
		)
		(hatch none 0.5)
		(connect_pads
			(clearance 0)
		)
		(min_thickness 0.25)
		(keepout
			(tracks not_allowed)
			(vias allowed)
			(pads allowed)
			(copperpour not_allowed)
			(footprints allowed)
		)
		(placement
			(enabled no)
			(sheetname "")
		)
		(fill
			(thermal_gap 0.5)
			(thermal_bridge_width 0.5)
			(island_removal_mode 0)
		)
		(polygon
			(pts
				(arc
					(start 126.066296 -221.133924)
					(mid 125.408436 -221.133924)
					(end 126.066296 -221.133924)
				)
			)
		)
	)
	(zone
		(layers "F.Cu" "B.Cu" "In1.Cu" "In2.Cu" "In3.Cu" "In4.Cu" "In5.Cu" "In6.Cu"
			"In7.Cu" "In8.Cu" "In9.Cu" "In10.Cu" "In11.Cu" "In12.Cu" "In13.Cu" "In14.Cu"
			"In15.Cu" "In16.Cu"
		)
		(hatch none 0.5)
		(connect_pads
			(clearance 0)
		)
		(min_thickness 0.25)
		(keepout
			(tracks not_allowed)
			(vias allowed)
			(pads allowed)
			(copperpour not_allowed)
			(footprints allowed)
		)
		(placement
			(enabled no)
			(sheetname "")
		)
		(fill
			(thermal_gap 0.5)
			(thermal_bridge_width 0.5)
			(island_removal_mode 0)
		)
		(polygon
			(pts
				(arc
					(start 347.53296 -214.720932)
					(mid 347.552644 -214.673522)
					(end 347.559376 -214.622634)
				)
				(arc
					(start 347.559376 -214.622634)
					(mid 347.50172 -214.48344)
					(end 347.362526 -214.425784)
				)
				(arc
					(start 347.362526 -214.425784)
					(mid 347.264095 -214.4522)
					(end 347.192092 -214.524336)
				)
				(arc
					(start 346.722446 -215.338406)
					(mid 346.702762 -215.385816)
					(end 346.69603 -215.436704)
				)
				(arc
					(start 346.69603 -215.436704)
					(mid 346.753686 -215.575898)
					(end 346.89288 -215.633554)
				)
				(arc
					(start 346.89288 -215.633554)
					(mid 346.991311 -215.607138)
					(end 347.063314 -215.535002)
				)
			)
		)
	)
	(zone
		(layers "F.Cu" "B.Cu" "In1.Cu" "In2.Cu" "In3.Cu" "In4.Cu" "In5.Cu" "In6.Cu"
			"In7.Cu" "In8.Cu" "In9.Cu" "In10.Cu" "In11.Cu" "In12.Cu" "In13.Cu" "In14.Cu"
			"In15.Cu" "In16.Cu"
		)
		(hatch none 0.5)
		(connect_pads
			(clearance 0)
		)
		(min_thickness 0.25)
		(keepout
			(tracks not_allowed)
			(vias allowed)
			(pads allowed)
			(copperpour not_allowed)
			(footprints allowed)
		)
		(placement
			(enabled no)
			(sheetname "")
		)
		(fill
			(thermal_gap 0.5)
			(thermal_bridge_width 0.5)
			(island_removal_mode 0)
		)
		(polygon
			(pts
				(arc
					(start 378.89561 -409.649168)
					(mid 378.51461 -410.030168)
					(end 378.89561 -410.411168)
				)
				(arc
					(start 379.75921 -410.411168)
					(mid 380.14021 -410.030168)
					(end 379.75921 -409.649168)
				)
			)
		)
	)
	(zone
		(layers "F.Cu" "B.Cu" "In1.Cu" "In2.Cu" "In3.Cu" "In4.Cu" "In5.Cu" "In6.Cu"
			"In7.Cu" "In8.Cu" "In9.Cu" "In10.Cu" "In11.Cu" "In12.Cu" "In13.Cu" "In14.Cu"
			"In15.Cu" "In16.Cu"
		)
		(hatch none 0.5)
		(connect_pads
			(clearance 0)
		)
		(min_thickness 0.25)
		(keepout
			(tracks not_allowed)
			(vias allowed)
			(pads allowed)
			(copperpour not_allowed)
			(footprints allowed)
		)
		(placement
			(enabled no)
			(sheetname "")
		)
		(fill
			(thermal_gap 0.5)
			(thermal_bridge_width 0.5)
			(island_removal_mode 0)
		)
		(polygon
			(pts
				(arc
					(start 356.61981 -225.203258)
					(mid 355.96195 -225.203258)
					(end 356.61981 -225.203258)
				)
			)
		)
	)
	(zone
		(layers "F.Cu" "B.Cu" "In1.Cu" "In2.Cu" "In3.Cu" "In4.Cu" "In5.Cu" "In6.Cu"
			"In7.Cu" "In8.Cu" "In9.Cu" "In10.Cu" "In11.Cu" "In12.Cu" "In13.Cu" "In14.Cu"
			"In15.Cu" "In16.Cu"
		)
		(hatch none 0.5)
		(connect_pads
			(clearance 0)
		)
		(min_thickness 0.25)
		(keepout
			(tracks not_allowed)
			(vias allowed)
			(pads allowed)
			(copperpour not_allowed)
			(footprints allowed)
		)
		(placement
			(enabled no)
			(sheetname "")
		)
		(fill
			(thermal_gap 0.5)
			(thermal_bridge_width 0.5)
			(island_removal_mode 0)
		)
		(polygon
			(pts
				(arc
					(start 91.707462 -288.831274)
					(mid 91.639754 -288.759423)
					(end 91.544648 -288.732976)
				)
				(arc
					(start 91.544648 -288.732976)
					(mid 91.414434 -288.786912)
					(end 91.360498 -288.917126)
				)
				(arc
					(start 91.360498 -288.917126)
					(mid 91.365949 -288.961347)
					(end 91.381834 -289.002978)
				)
				(arc
					(start 91.85148 -289.892994)
					(mid 91.919188 -289.964845)
					(end 92.014294 -289.991292)
				)
				(arc
					(start 92.014294 -289.991292)
					(mid 92.144508 -289.937356)
					(end 92.198444 -289.807142)
				)
				(arc
					(start 92.198444 -289.807142)
					(mid 92.192993 -289.762921)
					(end 92.177108 -289.72129)
				)
			)
		)
	)
	(zone
		(layers "F.Cu" "B.Cu" "In1.Cu" "In2.Cu" "In3.Cu" "In4.Cu" "In5.Cu" "In6.Cu"
			"In7.Cu" "In8.Cu" "In9.Cu" "In10.Cu" "In11.Cu" "In12.Cu" "In13.Cu" "In14.Cu"
			"In15.Cu" "In16.Cu"
		)
		(hatch none 0.5)
		(connect_pads
			(clearance 0)
		)
		(min_thickness 0.25)
		(keepout
			(tracks not_allowed)
			(vias allowed)
			(pads allowed)
			(copperpour not_allowed)
			(footprints allowed)
		)
		(placement
			(enabled no)
			(sheetname "")
		)
		(fill
			(thermal_gap 0.5)
			(thermal_bridge_width 0.5)
			(island_removal_mode 0)
		)
		(polygon
			(pts
				(arc
					(start 130.246628 -285.759652)
					(mid 130.266312 -285.712242)
					(end 130.273044 -285.661354)
				)
				(arc
					(start 130.273044 -285.661354)
					(mid 130.215388 -285.52216)
					(end 130.076194 -285.464504)
				)
				(arc
					(start 130.076194 -285.464504)
					(mid 129.977763 -285.49092)
					(end 129.90576 -285.563056)
				)
				(arc
					(start 129.436114 -286.377126)
					(mid 129.41643 -286.424536)
					(end 129.409698 -286.475424)
				)
				(arc
					(start 129.409698 -286.475424)
					(mid 129.467354 -286.614618)
					(end 129.606548 -286.672274)
				)
				(arc
					(start 129.606548 -286.672274)
					(mid 129.704979 -286.645858)
					(end 129.776982 -286.573722)
				)
			)
		)
	)
	(zone
		(layers "F.Cu" "B.Cu" "In1.Cu" "In2.Cu" "In3.Cu" "In4.Cu" "In5.Cu" "In6.Cu"
			"In7.Cu" "In8.Cu" "In9.Cu" "In10.Cu" "In11.Cu" "In12.Cu" "In13.Cu" "In14.Cu"
			"In15.Cu" "In16.Cu"
		)
		(hatch none 0.5)
		(connect_pads
			(clearance 0)
		)
		(min_thickness 0.25)
		(keepout
			(tracks not_allowed)
			(vias allowed)
			(pads allowed)
			(copperpour not_allowed)
			(footprints allowed)
		)
		(placement
			(enabled no)
			(sheetname "")
		)
		(fill
			(thermal_gap 0.5)
			(thermal_bridge_width 0.5)
			(island_removal_mode 0)
		)
		(polygon
			(pts
				(arc
					(start 127.867664 -285.661354)
					(mid 128.525524 -285.661354)
					(end 127.867664 -285.661354)
				)
			)
		)
	)
	(zone
		(layers "F.Cu" "B.Cu" "In1.Cu" "In2.Cu" "In3.Cu" "In4.Cu" "In5.Cu" "In6.Cu"
			"In7.Cu" "In8.Cu" "In9.Cu" "In10.Cu" "In11.Cu" "In12.Cu" "In13.Cu" "In14.Cu"
			"In15.Cu" "In16.Cu"
		)
		(hatch none 0.5)
		(connect_pads
			(clearance 0)
		)
		(min_thickness 0.25)
		(keepout
			(tracks not_allowed)
			(vias allowed)
			(pads allowed)
			(copperpour not_allowed)
			(footprints allowed)
		)
		(placement
			(enabled no)
			(sheetname "")
		)
		(fill
			(thermal_gap 0.5)
			(thermal_bridge_width 0.5)
			(island_removal_mode 0)
		)
		(polygon
			(pts
				(arc
					(start 125.907292 -214.720932)
					(mid 125.926976 -214.673522)
					(end 125.933708 -214.622634)
				)
				(arc
					(start 125.933708 -214.622634)
					(mid 125.876052 -214.48344)
					(end 125.736858 -214.425784)
				)
				(arc
					(start 125.736858 -214.425784)
					(mid 125.638427 -214.4522)
					(end 125.566424 -214.524336)
				)
				(arc
					(start 125.096778 -215.338406)
					(mid 125.077094 -215.385816)
					(end 125.070362 -215.436704)
				)
				(arc
					(start 125.070362 -215.436704)
					(mid 125.128018 -215.575898)
					(end 125.267212 -215.633554)
				)
				(arc
					(start 125.267212 -215.633554)
					(mid 125.365643 -215.607138)
					(end 125.437646 -215.535002)
				)
			)
		)
	)
	(zone
		(layers "F.Cu" "B.Cu" "In1.Cu" "In2.Cu" "In3.Cu" "In4.Cu" "In5.Cu" "In6.Cu"
			"In7.Cu" "In8.Cu" "In9.Cu" "In10.Cu" "In11.Cu" "In12.Cu" "In13.Cu" "In14.Cu"
			"In15.Cu" "In16.Cu"
		)
		(hatch none 0.5)
		(connect_pads
			(clearance 0)
		)
		(min_thickness 0.25)
		(keepout
			(tracks not_allowed)
			(vias allowed)
			(pads allowed)
			(copperpour not_allowed)
			(footprints allowed)
		)
		(placement
			(enabled no)
			(sheetname "")
		)
		(fill
			(thermal_gap 0.5)
			(thermal_bridge_width 0.5)
			(island_removal_mode 0)
		)
		(polygon
			(pts
				(arc
					(start 86.084918 -409.649168)
					(mid 85.703918 -410.030168)
					(end 86.084918 -410.411168)
				)
				(arc
					(start 86.948518 -410.411168)
					(mid 87.329518 -410.030168)
					(end 86.948518 -409.649168)
				)
			)
		)
	)
	(zone
		(layers "F.Cu" "B.Cu" "In1.Cu" "In2.Cu" "In3.Cu" "In4.Cu" "In5.Cu" "In6.Cu"
			"In7.Cu" "In8.Cu" "In9.Cu" "In10.Cu" "In11.Cu" "In12.Cu" "In13.Cu" "In14.Cu"
			"In15.Cu" "In16.Cu"
		)
		(hatch none 0.5)
		(connect_pads
			(clearance 0)
		)
		(min_thickness 0.25)
		(keepout
			(tracks not_allowed)
			(vias allowed)
			(pads allowed)
			(copperpour not_allowed)
			(footprints allowed)
		)
		(placement
			(enabled no)
			(sheetname "")
		)
		(fill
			(thermal_gap 0.5)
			(thermal_bridge_width 0.5)
			(island_removal_mode 0)
		)
		(polygon
			(pts
				(arc
					(start 132.407914 -400.477228)
					(mid 132.026914 -400.858228)
					(end 132.407914 -401.239228)
				)
				(arc
					(start 133.271514 -401.239228)
					(mid 133.652514 -400.858228)
					(end 133.271514 -400.477228)
				)
			)
		)
	)
	(zone
		(layers "F.Cu" "B.Cu" "In1.Cu" "In2.Cu" "In3.Cu" "In4.Cu" "In5.Cu" "In6.Cu"
			"In7.Cu" "In8.Cu" "In9.Cu" "In10.Cu" "In11.Cu" "In12.Cu" "In13.Cu" "In14.Cu"
			"In15.Cu" "In16.Cu"
		)
		(hatch none 0.5)
		(connect_pads
			(clearance 0)
		)
		(min_thickness 0.25)
		(keepout
			(tracks not_allowed)
			(vias allowed)
			(pads allowed)
			(copperpour not_allowed)
			(footprints allowed)
		)
		(placement
			(enabled no)
			(sheetname "")
		)
		(fill
			(thermal_gap 0.5)
			(thermal_bridge_width 0.5)
			(island_removal_mode 0)
		)
		(polygon
			(pts
				(arc
					(start 350.121728 -276.610318)
					(mid 350.102044 -276.657728)
					(end 350.095312 -276.708616)
				)
				(arc
					(start 350.095312 -276.708616)
					(mid 350.152968 -276.84781)
					(end 350.292162 -276.905466)
				)
				(arc
					(start 350.292162 -276.905466)
					(mid 350.390593 -276.87905)
					(end 350.462596 -276.806914)
				)
				(arc
					(start 350.932496 -275.992844)
					(mid 350.95218 -275.945434)
					(end 350.958912 -275.894546)
				)
				(arc
					(start 350.958912 -275.894546)
					(mid 350.901256 -275.755352)
					(end 350.762062 -275.697696)
				)
				(arc
					(start 350.762062 -275.697696)
					(mid 350.663631 -275.724112)
					(end 350.591628 -275.796248)
				)
			)
		)
	)
	(zone
		(layers "F.Cu" "B.Cu" "In1.Cu" "In2.Cu" "In3.Cu" "In4.Cu" "In5.Cu" "In6.Cu"
			"In7.Cu" "In8.Cu" "In9.Cu" "In10.Cu" "In11.Cu" "In12.Cu" "In13.Cu" "In14.Cu"
			"In15.Cu" "In16.Cu"
		)
		(hatch none 0.5)
		(connect_pads
			(clearance 0)
		)
		(min_thickness 0.25)
		(keepout
			(tracks not_allowed)
			(vias allowed)
			(pads allowed)
			(copperpour not_allowed)
			(footprints allowed)
		)
		(placement
			(enabled no)
			(sheetname "")
		)
		(fill
			(thermal_gap 0.5)
			(thermal_bridge_width 0.5)
			(island_removal_mode 0)
		)
		(polygon
			(pts
				(arc
					(start 86.516464 -287.28924)
					(mid 87.174324 -287.28924)
					(end 86.516464 -287.28924)
				)
			)
		)
	)
	(zone
		(layers "F.Cu" "B.Cu" "In1.Cu" "In2.Cu" "In3.Cu" "In4.Cu" "In5.Cu" "In6.Cu"
			"In7.Cu" "In8.Cu" "In9.Cu" "In10.Cu" "In11.Cu" "In12.Cu" "In13.Cu" "In14.Cu"
			"In15.Cu" "In16.Cu"
		)
		(hatch none 0.5)
		(connect_pads
			(clearance 0)
		)
		(min_thickness 0.25)
		(keepout
			(tracks not_allowed)
			(vias allowed)
			(pads allowed)
			(copperpour not_allowed)
			(footprints allowed)
		)
		(placement
			(enabled no)
			(sheetname "")
		)
		(fill
			(thermal_gap 0.5)
			(thermal_bridge_width 0.5)
			(island_removal_mode 0)
		)
		(polygon
			(pts
				(arc
					(start 95.914718 -280.778204)
					(mid 96.572578 -280.778204)
					(end 95.914718 -280.778204)
				)
			)
		)
	)
	(zone
		(layers "F.Cu" "B.Cu" "In1.Cu" "In2.Cu" "In3.Cu" "In4.Cu" "In5.Cu" "In6.Cu"
			"In7.Cu" "In8.Cu" "In9.Cu" "In10.Cu" "In11.Cu" "In12.Cu" "In13.Cu" "In14.Cu"
			"In15.Cu" "In16.Cu"
		)
		(hatch none 0.5)
		(connect_pads
			(clearance 0)
		)
		(min_thickness 0.25)
		(keepout
			(tracks not_allowed)
			(vias allowed)
			(pads allowed)
			(copperpour not_allowed)
			(footprints allowed)
		)
		(placement
			(enabled no)
			(sheetname "")
		)
		(fill
			(thermal_gap 0.5)
			(thermal_bridge_width 0.5)
			(island_removal_mode 0)
		)
		(polygon
			(pts
				(arc
					(start 119.597678 -284.847538)
					(mid 118.939818 -284.847538)
					(end 119.597678 -284.847538)
				)
			)
		)
	)
	(zone
		(layers "F.Cu" "B.Cu" "In1.Cu" "In2.Cu" "In3.Cu" "In4.Cu" "In5.Cu" "In6.Cu"
			"In7.Cu" "In8.Cu" "In9.Cu" "In10.Cu" "In11.Cu" "In12.Cu" "In13.Cu" "In14.Cu"
			"In15.Cu" "In16.Cu"
		)
		(hatch none 0.5)
		(connect_pads
			(clearance 0)
		)
		(min_thickness 0.25)
		(keepout
			(tracks not_allowed)
			(vias allowed)
			(pads allowed)
			(copperpour not_allowed)
			(footprints allowed)
		)
		(placement
			(enabled no)
			(sheetname "")
		)
		(fill
			(thermal_gap 0.5)
			(thermal_bridge_width 0.5)
			(island_removal_mode 0)
		)
		(polygon
			(pts
				(arc
					(start 128.885696 -221.133924)
					(mid 128.227836 -221.133924)
					(end 128.885696 -221.133924)
				)
			)
		)
	)
	(zone
		(layers "F.Cu" "B.Cu" "In1.Cu" "In2.Cu" "In3.Cu" "In4.Cu" "In5.Cu" "In6.Cu"
			"In7.Cu" "In8.Cu" "In9.Cu" "In10.Cu" "In11.Cu" "In12.Cu" "In13.Cu" "In14.Cu"
			"In15.Cu" "In16.Cu"
		)
		(hatch none 0.5)
		(connect_pads
			(clearance 0)
		)
		(min_thickness 0.25)
		(keepout
			(tracks not_allowed)
			(vias allowed)
			(pads allowed)
			(copperpour not_allowed)
			(footprints allowed)
		)
		(placement
			(enabled no)
			(sheetname "")
		)
		(fill
			(thermal_gap 0.5)
			(thermal_bridge_width 0.5)
			(island_removal_mode 0)
		)
		(polygon
			(pts
				(arc
					(start 323.705728 -406.62352)
					(mid 323.324728 -407.00452)
					(end 323.705728 -407.38552)
				)
				(arc
					(start 324.569328 -407.38552)
					(mid 324.950328 -407.00452)
					(end 324.569328 -406.62352)
				)
			)
		)
	)
	(zone
		(layers "F.Cu" "B.Cu" "In1.Cu" "In2.Cu" "In3.Cu" "In4.Cu" "In5.Cu" "In6.Cu"
			"In7.Cu" "In8.Cu" "In9.Cu" "In10.Cu" "In11.Cu" "In12.Cu" "In13.Cu" "In14.Cu"
			"In15.Cu" "In16.Cu"
		)
		(hatch none 0.5)
		(connect_pads
			(clearance 0)
		)
		(min_thickness 0.25)
		(keepout
			(tracks not_allowed)
			(vias allowed)
			(pads allowed)
			(copperpour not_allowed)
			(footprints allowed)
		)
		(placement
			(enabled no)
			(sheetname "")
		)
		(fill
			(thermal_gap 0.5)
			(thermal_bridge_width 0.5)
			(island_removal_mode 0)
		)
		(polygon
			(pts
				(arc
					(start 129.666492 -214.720932)
					(mid 129.686176 -214.673522)
					(end 129.692908 -214.622634)
				)
				(arc
					(start 129.692908 -214.622634)
					(mid 129.635252 -214.48344)
					(end 129.496058 -214.425784)
				)
				(arc
					(start 129.496058 -214.425784)
					(mid 129.397627 -214.4522)
					(end 129.325624 -214.524336)
				)
				(arc
					(start 128.855978 -215.338406)
					(mid 128.836294 -215.385816)
					(end 128.829562 -215.436704)
				)
				(arc
					(start 128.829562 -215.436704)
					(mid 128.887218 -215.575898)
					(end 129.026412 -215.633554)
				)
				(arc
					(start 129.026412 -215.633554)
					(mid 129.124843 -215.607138)
					(end 129.196846 -215.535002)
				)
			)
		)
	)
	(zone
		(layers "F.Cu" "B.Cu" "In1.Cu" "In2.Cu" "In3.Cu" "In4.Cu" "In5.Cu" "In6.Cu"
			"In7.Cu" "In8.Cu" "In9.Cu" "In10.Cu" "In11.Cu" "In12.Cu" "In13.Cu" "In14.Cu"
			"In15.Cu" "In16.Cu"
		)
		(hatch none 0.5)
		(connect_pads
			(clearance 0)
		)
		(min_thickness 0.25)
		(keepout
			(tracks not_allowed)
			(vias allowed)
			(pads allowed)
			(copperpour not_allowed)
			(footprints allowed)
		)
		(placement
			(enabled no)
			(sheetname "")
		)
		(fill
			(thermal_gap 0.5)
			(thermal_bridge_width 0.5)
			(island_removal_mode 0)
		)
		(polygon
			(pts
				(arc
					(start 99.532948 -281.39517)
					(mid 99.336098 -281.59202)
					(end 99.532948 -281.78887)
				)
				(arc
					(start 100.472748 -281.78887)
					(mid 100.669598 -281.59202)
					(end 100.472748 -281.39517)
				)
			)
		)
	)
	(zone
		(layers "F.Cu" "B.Cu" "In1.Cu" "In2.Cu" "In3.Cu" "In4.Cu" "In5.Cu" "In6.Cu"
			"In7.Cu" "In8.Cu" "In9.Cu" "In10.Cu" "In11.Cu" "In12.Cu" "In13.Cu" "In14.Cu"
			"In15.Cu" "In16.Cu"
		)
		(hatch none 0.5)
		(connect_pads
			(clearance 0)
		)
		(min_thickness 0.25)
		(keepout
			(tracks not_allowed)
			(vias allowed)
			(pads allowed)
			(copperpour not_allowed)
			(footprints allowed)
		)
		(placement
			(enabled no)
			(sheetname "")
		)
		(fill
			(thermal_gap 0.5)
			(thermal_bridge_width 0.5)
			(island_removal_mode 0)
		)
		(polygon
			(pts
				(arc
					(start 93.095064 -285.661354)
					(mid 93.752924 -285.661354)
					(end 93.095064 -285.661354)
				)
			)
		)
	)
	(zone
		(layers "F.Cu" "B.Cu" "In1.Cu" "In2.Cu" "In3.Cu" "In4.Cu" "In5.Cu" "In6.Cu"
			"In7.Cu" "In8.Cu" "In9.Cu" "In10.Cu" "In11.Cu" "In12.Cu" "In13.Cu" "In14.Cu"
			"In15.Cu" "In16.Cu"
		)
		(hatch none 0.5)
		(connect_pads
			(clearance 0)
		)
		(min_thickness 0.25)
		(keepout
			(tracks not_allowed)
			(vias allowed)
			(pads allowed)
			(copperpour not_allowed)
			(footprints allowed)
		)
		(placement
			(enabled no)
			(sheetname "")
		)
		(fill
			(thermal_gap 0.5)
			(thermal_bridge_width 0.5)
			(island_removal_mode 0)
		)
		(polygon
			(pts
				(arc
					(start 381.634746 -286.475424)
					(mid 380.976886 -286.475424)
					(end 381.634746 -286.475424)
				)
			)
		)
	)
	(zone
		(layers "F.Cu" "B.Cu" "In1.Cu" "In2.Cu" "In3.Cu" "In4.Cu" "In5.Cu" "In6.Cu"
			"In7.Cu" "In8.Cu" "In9.Cu" "In10.Cu" "In11.Cu" "In12.Cu" "In13.Cu" "In14.Cu"
			"In15.Cu" "In16.Cu"
		)
		(hatch none 0.5)
		(connect_pads
			(clearance 0)
		)
		(min_thickness 0.25)
		(keepout
			(tracks not_allowed)
			(vias allowed)
			(pads allowed)
			(copperpour not_allowed)
			(footprints allowed)
		)
		(placement
			(enabled no)
			(sheetname "")
		)
		(fill
			(thermal_gap 0.5)
			(thermal_bridge_width 0.5)
			(island_removal_mode 0)
		)
		(polygon
			(pts
				(arc
					(start 135.471154 -400.477228)
					(mid 135.090154 -400.858228)
					(end 135.471154 -401.239228)
				)
				(arc
					(start 136.334754 -401.239228)
					(mid 136.715754 -400.858228)
					(end 136.334754 -400.477228)
				)
			)
		)
	)
	(zone
		(layers "F.Cu" "B.Cu" "In1.Cu" "In2.Cu" "In3.Cu" "In4.Cu" "In5.Cu" "In6.Cu"
			"In7.Cu" "In8.Cu" "In9.Cu" "In10.Cu" "In11.Cu" "In12.Cu" "In13.Cu" "In14.Cu"
			"In15.Cu" "In16.Cu"
		)
		(hatch none 0.5)
		(connect_pads
			(clearance 0)
		)
		(min_thickness 0.25)
		(keepout
			(tracks not_allowed)
			(vias allowed)
			(pads allowed)
			(copperpour not_allowed)
			(footprints allowed)
		)
		(placement
			(enabled no)
			(sheetname "")
		)
		(fill
			(thermal_gap 0.5)
			(thermal_bridge_width 0.5)
			(island_removal_mode 0)
		)
		(polygon
			(pts
				(arc
					(start 361.31881 -217.064336)
					(mid 360.66095 -217.064336)
					(end 361.31881 -217.064336)
				)
			)
		)
	)
	(zone
		(layers "F.Cu" "B.Cu" "In1.Cu" "In2.Cu" "In3.Cu" "In4.Cu" "In5.Cu" "In6.Cu"
			"In7.Cu" "In8.Cu" "In9.Cu" "In10.Cu" "In11.Cu" "In12.Cu" "In13.Cu" "In14.Cu"
			"In15.Cu" "In16.Cu"
		)
		(hatch none 0.5)
		(connect_pads
			(clearance 0)
		)
		(min_thickness 0.25)
		(keepout
			(tracks not_allowed)
			(vias allowed)
			(pads allowed)
			(copperpour not_allowed)
			(footprints allowed)
		)
		(placement
			(enabled no)
			(sheetname "")
		)
		(fill
			(thermal_gap 0.5)
			(thermal_bridge_width 0.5)
			(island_removal_mode 0)
		)
		(polygon
			(pts
				(xy 639.864354 -298.16552) (xy 639.864354 -303.165256) (xy 639.559554 -302.860456) (xy 639.559554 -298.47032)
			)
		)
	)
	(zone
		(layers "F.Cu" "B.Cu" "In1.Cu" "In2.Cu" "In3.Cu" "In4.Cu" "In5.Cu" "In6.Cu"
			"In7.Cu" "In8.Cu" "In9.Cu" "In10.Cu" "In11.Cu" "In12.Cu" "In13.Cu" "In14.Cu"
			"In15.Cu" "In16.Cu"
		)
		(hatch none 0.5)
		(connect_pads
			(clearance 0)
		)
		(min_thickness 0.25)
		(keepout
			(tracks not_allowed)
			(vias allowed)
			(pads allowed)
			(copperpour not_allowed)
			(footprints allowed)
		)
		(placement
			(enabled no)
			(sheetname "")
		)
		(fill
			(thermal_gap 0.5)
			(thermal_bridge_width 0.5)
			(island_removal_mode 0)
		)
		(polygon
			(pts
				(arc
					(start 374.006364 -224.389442)
					(mid 373.348504 -224.389442)
					(end 374.006364 -224.389442)
				)
			)
		)
	)
	(zone
		(layers "F.Cu" "B.Cu" "In1.Cu" "In2.Cu" "In3.Cu" "In4.Cu" "In5.Cu" "In6.Cu"
			"In7.Cu" "In8.Cu" "In9.Cu" "In10.Cu" "In11.Cu" "In12.Cu" "In13.Cu" "In14.Cu"
			"In15.Cu" "In16.Cu"
		)
		(hatch none 0.5)
		(connect_pads
			(clearance 0)
		)
		(min_thickness 0.25)
		(keepout
			(tracks not_allowed)
			(vias allowed)
			(pads allowed)
			(copperpour not_allowed)
			(footprints allowed)
		)
		(placement
			(enabled no)
			(sheetname "")
		)
		(fill
			(thermal_gap 0.5)
			(thermal_bridge_width 0.5)
			(island_removal_mode 0)
		)
		(polygon
			(pts
				(arc
					(start 91.715082 -285.563056)
					(mid 91.643093 -285.490897)
					(end 91.544648 -285.464504)
				)
				(arc
					(start 91.544648 -285.464504)
					(mid 91.405454 -285.52216)
					(end 91.347798 -285.661354)
				)
				(arc
					(start 91.347798 -285.661354)
					(mid 91.354555 -285.712235)
					(end 91.374214 -285.759652)
				)
				(arc
					(start 91.844114 -286.573722)
					(mid 91.916103 -286.645881)
					(end 92.014548 -286.672274)
				)
				(arc
					(start 92.014548 -286.672274)
					(mid 92.153742 -286.614618)
					(end 92.211398 -286.475424)
				)
				(arc
					(start 92.211398 -286.475424)
					(mid 92.204641 -286.424543)
					(end 92.184982 -286.377126)
				)
			)
		)
	)
	(zone
		(layers "F.Cu" "B.Cu" "In1.Cu" "In2.Cu" "In3.Cu" "In4.Cu" "In5.Cu" "In6.Cu"
			"In7.Cu" "In8.Cu" "In9.Cu" "In10.Cu" "In11.Cu" "In12.Cu" "In13.Cu" "In14.Cu"
			"In15.Cu" "In16.Cu"
		)
		(hatch none 0.5)
		(connect_pads
			(clearance 0)
		)
		(min_thickness 0.25)
		(keepout
			(tracks not_allowed)
			(vias allowed)
			(pads allowed)
			(copperpour not_allowed)
			(footprints allowed)
		)
		(placement
			(enabled no)
			(sheetname "")
		)
		(fill
			(thermal_gap 0.5)
			(thermal_bridge_width 0.5)
			(island_removal_mode 0)
		)
		(polygon
			(pts
				(arc
					(start 348.657672 -176.709832)
					(mid 348.806462 -177.069042)
					(end 349.165672 -177.217832)
				)
				(arc
					(start 349.16618 -177.217832)
					(mid 349.297389 -177.200595)
					(end 349.419672 -177.150014)
				)
				(arc
					(start 350.343724 -176.61636)
					(mid 350.529657 -176.430424)
					(end 350.597724 -176.176432)
				)
				(arc
					(start 350.597724 -176.176432)
					(mid 350.448934 -175.817222)
					(end 350.089724 -175.668432)
				)
				(arc
					(start 350.089216 -175.668432)
					(mid 349.958007 -175.685669)
					(end 349.835724 -175.73625)
				)
				(arc
					(start 348.911672 -176.269904)
					(mid 348.725739 -176.45584)
					(end 348.657672 -176.709832)
				)
			)
		)
	)
	(zone
		(layers "F.Cu" "B.Cu" "In1.Cu" "In2.Cu" "In3.Cu" "In4.Cu" "In5.Cu" "In6.Cu"
			"In7.Cu" "In8.Cu" "In9.Cu" "In10.Cu" "In11.Cu" "In12.Cu" "In13.Cu" "In14.Cu"
			"In15.Cu" "In16.Cu"
		)
		(hatch none 0.5)
		(connect_pads
			(clearance 0)
		)
		(min_thickness 0.25)
		(keepout
			(tracks not_allowed)
			(vias allowed)
			(pads allowed)
			(copperpour not_allowed)
			(footprints allowed)
		)
		(placement
			(enabled no)
			(sheetname "")
		)
		(fill
			(thermal_gap 0.5)
			(thermal_bridge_width 0.5)
			(island_removal_mode 0)
		)
		(polygon
			(pts
				(arc
					(start 376.77725 -284.74924)
					(mid 376.705261 -284.677081)
					(end 376.606816 -284.650688)
				)
				(arc
					(start 376.606816 -284.650688)
					(mid 376.467622 -284.708344)
					(end 376.409966 -284.847538)
				)
				(arc
					(start 376.409966 -284.847538)
					(mid 376.416723 -284.898419)
					(end 376.436382 -284.945836)
				)
				(arc
					(start 376.906028 -285.759652)
					(mid 376.978017 -285.831811)
					(end 377.076462 -285.858204)
				)
				(arc
					(start 377.076462 -285.858204)
					(mid 377.215656 -285.800548)
					(end 377.273312 -285.661354)
				)
				(arc
					(start 377.273312 -285.661354)
					(mid 377.266555 -285.610473)
					(end 377.246896 -285.563056)
				)
			)
		)
	)
	(zone
		(layers "F.Cu" "B.Cu" "In1.Cu" "In2.Cu" "In3.Cu" "In4.Cu" "In5.Cu" "In6.Cu"
			"In7.Cu" "In8.Cu" "In9.Cu" "In10.Cu" "In11.Cu" "In12.Cu" "In13.Cu" "In14.Cu"
			"In15.Cu" "In16.Cu"
		)
		(hatch none 0.5)
		(connect_pads
			(clearance 0)
		)
		(min_thickness 0.25)
		(keepout
			(tracks not_allowed)
			(vias allowed)
			(pads allowed)
			(copperpour not_allowed)
			(footprints allowed)
		)
		(placement
			(enabled no)
			(sheetname "")
		)
		(fill
			(thermal_gap 0.5)
			(thermal_bridge_width 0.5)
			(island_removal_mode 0)
		)
		(polygon
			(pts
				(arc
					(start 16.335502 -104.8004)
					(mid 15.954502 -104.4194)
					(end 15.573502 -104.8004)
				)
				(arc
					(start 15.573502 -105.664)
					(mid 15.954502 -106.045)
					(end 16.335502 -105.664)
				)
			)
		)
	)
	(zone
		(layers "F.Cu" "B.Cu" "In1.Cu" "In2.Cu" "In3.Cu" "In4.Cu" "In5.Cu" "In6.Cu"
			"In7.Cu" "In8.Cu" "In9.Cu" "In10.Cu" "In11.Cu" "In12.Cu" "In13.Cu" "In14.Cu"
			"In15.Cu" "In16.Cu"
		)
		(hatch none 0.5)
		(connect_pads
			(clearance 0)
		)
		(min_thickness 0.25)
		(keepout
			(tracks not_allowed)
			(vias allowed)
			(pads allowed)
			(copperpour not_allowed)
			(footprints allowed)
		)
		(placement
			(enabled no)
			(sheetname "")
		)
		(fill
			(thermal_gap 0.5)
			(thermal_bridge_width 0.5)
			(island_removal_mode 0)
		)
		(polygon
			(pts
				(arc
					(start 375.995692 -289.807142)
					(mid 375.337832 -289.807142)
					(end 375.995692 -289.807142)
				)
			)
		)
	)
	(zone
		(layers "F.Cu" "B.Cu" "In1.Cu" "In2.Cu" "In3.Cu" "In4.Cu" "In5.Cu" "In6.Cu"
			"In7.Cu" "In8.Cu" "In9.Cu" "In10.Cu" "In11.Cu" "In12.Cu" "In13.Cu" "In14.Cu"
			"In15.Cu" "In16.Cu"
		)
		(hatch none 0.5)
		(connect_pads
			(clearance 0)
		)
		(min_thickness 0.25)
		(keepout
			(tracks not_allowed)
			(vias allowed)
			(pads allowed)
			(copperpour not_allowed)
			(footprints allowed)
		)
		(placement
			(enabled no)
			(sheetname "")
		)
		(fill
			(thermal_gap 0.5)
			(thermal_bridge_width 0.5)
			(island_removal_mode 0)
		)
		(polygon
			(pts
				(arc
					(start 397.27505 -406.62352)
					(mid 396.89405 -407.00452)
					(end 397.27505 -407.38552)
				)
				(arc
					(start 398.13865 -407.38552)
					(mid 398.51965 -407.00452)
					(end 398.13865 -406.62352)
				)
			)
		)
	)
	(zone
		(layers "F.Cu" "B.Cu" "In1.Cu" "In2.Cu" "In3.Cu" "In4.Cu" "In5.Cu" "In6.Cu"
			"In7.Cu" "In8.Cu" "In9.Cu" "In10.Cu" "In11.Cu" "In12.Cu" "In13.Cu" "In14.Cu"
			"In15.Cu" "In16.Cu"
		)
		(hatch none 0.5)
		(connect_pads
			(clearance 0)
		)
		(min_thickness 0.25)
		(keepout
			(tracks not_allowed)
			(vias allowed)
			(pads allowed)
			(copperpour not_allowed)
			(footprints allowed)
		)
		(placement
			(enabled no)
			(sheetname "")
		)
		(fill
			(thermal_gap 0.5)
			(thermal_bridge_width 0.5)
			(island_removal_mode 0)
		)
		(polygon
			(pts
				(arc
					(start 393.524232 -6.332474)
					(mid 393.143232 -6.713474)
					(end 393.524232 -7.094474)
				)
				(arc
					(start 394.387832 -7.094474)
					(mid 394.768832 -6.713474)
					(end 394.387832 -6.332474)
				)
			)
		)
	)
	(zone
		(layers "F.Cu" "B.Cu" "In1.Cu" "In2.Cu" "In3.Cu" "In4.Cu" "In5.Cu" "In6.Cu"
			"In7.Cu" "In8.Cu" "In9.Cu" "In10.Cu" "In11.Cu" "In12.Cu" "In13.Cu" "In14.Cu"
			"In15.Cu" "In16.Cu"
		)
		(hatch none 0.5)
		(connect_pads
			(clearance 0)
		)
		(min_thickness 0.25)
		(keepout
			(tracks not_allowed)
			(vias allowed)
			(pads allowed)
			(copperpour not_allowed)
			(footprints allowed)
		)
		(placement
			(enabled no)
			(sheetname "")
		)
		(fill
			(thermal_gap 0.5)
			(thermal_bridge_width 0.5)
			(island_removal_mode 0)
		)
		(polygon
			(pts
				(arc
					(start 108.679742 -225.203258)
					(mid 108.021882 -225.203258)
					(end 108.679742 -225.203258)
				)
			)
		)
	)
	(zone
		(layers "F.Cu" "B.Cu" "In1.Cu" "In2.Cu" "In3.Cu" "In4.Cu" "In5.Cu" "In6.Cu"
			"In7.Cu" "In8.Cu" "In9.Cu" "In10.Cu" "In11.Cu" "In12.Cu" "In13.Cu" "In14.Cu"
			"In15.Cu" "In16.Cu"
		)
		(hatch none 0.5)
		(connect_pads
			(clearance 0)
		)
		(min_thickness 0.25)
		(keepout
			(tracks not_allowed)
			(vias allowed)
			(pads allowed)
			(copperpour not_allowed)
			(footprints allowed)
		)
		(placement
			(enabled no)
			(sheetname "")
		)
		(fill
			(thermal_gap 0.5)
			(thermal_bridge_width 0.5)
			(island_removal_mode 0)
		)
		(polygon
			(pts
				(arc
					(start 355.991668 -224.291144)
					(mid 355.919679 -224.218985)
					(end 355.821234 -224.192592)
				)
				(arc
					(start 355.821234 -224.192592)
					(mid 355.68204 -224.250248)
					(end 355.624384 -224.389442)
				)
				(arc
					(start 355.624384 -224.389442)
					(mid 355.631141 -224.440323)
					(end 355.6508 -224.48774)
				)
				(arc
					(start 356.120446 -225.301556)
					(mid 356.192435 -225.373715)
					(end 356.29088 -225.400108)
				)
				(arc
					(start 356.29088 -225.400108)
					(mid 356.430074 -225.342452)
					(end 356.48773 -225.203258)
				)
				(arc
					(start 356.48773 -225.203258)
					(mid 356.480973 -225.152377)
					(end 356.461314 -225.10496)
				)
			)
		)
	)
	(zone
		(layers "F.Cu" "B.Cu" "In1.Cu" "In2.Cu" "In3.Cu" "In4.Cu" "In5.Cu" "In6.Cu"
			"In7.Cu" "In8.Cu" "In9.Cu" "In10.Cu" "In11.Cu" "In12.Cu" "In13.Cu" "In14.Cu"
			"In15.Cu" "In16.Cu"
		)
		(hatch none 0.5)
		(connect_pads
			(clearance 0)
		)
		(min_thickness 0.25)
		(keepout
			(tracks not_allowed)
			(vias allowed)
			(pads allowed)
			(copperpour not_allowed)
			(footprints allowed)
		)
		(placement
			(enabled no)
			(sheetname "")
		)
		(fill
			(thermal_gap 0.5)
			(thermal_bridge_width 0.5)
			(island_removal_mode 0)
		)
		(polygon
			(pts
				(arc
					(start 344.402664 -213.732618)
					(mid 343.744804 -213.732618)
					(end 344.402664 -213.732618)
				)
			)
		)
	)
	(zone
		(layers "F.Cu" "B.Cu" "In1.Cu" "In2.Cu" "In3.Cu" "In4.Cu" "In5.Cu" "In6.Cu"
			"In7.Cu" "In8.Cu" "In9.Cu" "In10.Cu" "In11.Cu" "In12.Cu" "In13.Cu" "In14.Cu"
			"In15.Cu" "In16.Cu"
		)
		(hatch none 0.5)
		(connect_pads
			(clearance 0)
		)
		(min_thickness 0.25)
		(keepout
			(tracks not_allowed)
			(vias allowed)
			(pads allowed)
			(copperpour not_allowed)
			(footprints allowed)
		)
		(placement
			(enabled no)
			(sheetname "")
		)
		(fill
			(thermal_gap 0.5)
			(thermal_bridge_width 0.5)
			(island_removal_mode 0)
		)
		(polygon
			(pts
				(arc
					(start 102.493064 -279.150318)
					(mid 103.150924 -279.150318)
					(end 102.493064 -279.150318)
				)
			)
		)
	)
	(zone
		(layers "F.Cu" "B.Cu" "In1.Cu" "In2.Cu" "In3.Cu" "In4.Cu" "In5.Cu" "In6.Cu"
			"In7.Cu" "In8.Cu" "In9.Cu" "In10.Cu" "In11.Cu" "In12.Cu" "In13.Cu" "In14.Cu"
			"In15.Cu" "In16.Cu"
		)
		(hatch none 0.5)
		(connect_pads
			(clearance 0)
		)
		(min_thickness 0.25)
		(keepout
			(tracks not_allowed)
			(vias allowed)
			(pads allowed)
			(copperpour not_allowed)
			(footprints allowed)
		)
		(placement
			(enabled no)
			(sheetname "")
		)
		(fill
			(thermal_gap 0.5)
			(thermal_bridge_width 0.5)
			(island_removal_mode 0)
		)
		(polygon
			(pts
				(arc
					(start 101.631496 -221.133924)
					(mid 100.973636 -221.133924)
					(end 101.631496 -221.133924)
				)
			)
		)
	)
	(zone
		(layers "F.Cu" "B.Cu" "In1.Cu" "In2.Cu" "In3.Cu" "In4.Cu" "In5.Cu" "In6.Cu"
			"In7.Cu" "In8.Cu" "In9.Cu" "In10.Cu" "In11.Cu" "In12.Cu" "In13.Cu" "In14.Cu"
			"In15.Cu" "In16.Cu"
		)
		(hatch none 0.5)
		(connect_pads
			(clearance 0)
		)
		(min_thickness 0.25)
		(keepout
			(tracks not_allowed)
			(vias allowed)
			(pads allowed)
			(copperpour not_allowed)
			(footprints allowed)
		)
		(placement
			(enabled no)
			(sheetname "")
		)
		(fill
			(thermal_gap 0.5)
			(thermal_bridge_width 0.5)
			(island_removal_mode 0)
		)
		(polygon
			(pts
				(arc
					(start 344.512392 -285.661354)
					(mid 343.854532 -285.661354)
					(end 344.512392 -285.661354)
				)
			)
		)
	)
	(zone
		(layers "F.Cu" "B.Cu" "In1.Cu" "In2.Cu" "In3.Cu" "In4.Cu" "In5.Cu" "In6.Cu"
			"In7.Cu" "In8.Cu" "In9.Cu" "In10.Cu" "In11.Cu" "In12.Cu" "In13.Cu" "In14.Cu"
			"In15.Cu" "In16.Cu"
		)
		(hatch none 0.5)
		(connect_pads
			(clearance 0)
		)
		(min_thickness 0.25)
		(keepout
			(tracks not_allowed)
			(vias allowed)
			(pads allowed)
			(copperpour not_allowed)
			(footprints allowed)
		)
		(placement
			(enabled no)
			(sheetname "")
		)
		(fill
			(thermal_gap 0.5)
			(thermal_bridge_width 0.5)
			(island_removal_mode 0)
		)
		(polygon
			(pts
				(arc
					(start 370.152422 -361.133136)
					(mid 369.387374 -361.133136)
					(end 370.152422 -361.133136)
				)
			)
		)
	)
	(zone
		(layers "F.Cu" "B.Cu" "In1.Cu" "In2.Cu" "In3.Cu" "In4.Cu" "In5.Cu" "In6.Cu"
			"In7.Cu" "In8.Cu" "In9.Cu" "In10.Cu" "In11.Cu" "In12.Cu" "In13.Cu" "In14.Cu"
			"In15.Cu" "In16.Cu"
		)
		(hatch none 0.5)
		(connect_pads
			(clearance 0)
		)
		(min_thickness 0.25)
		(keepout
			(tracks not_allowed)
			(vias allowed)
			(pads allowed)
			(copperpour not_allowed)
			(footprints allowed)
		)
		(placement
			(enabled no)
			(sheetname "")
		)
		(fill
			(thermal_gap 0.5)
			(thermal_bridge_width 0.5)
			(island_removal_mode 0)
		)
		(polygon
			(pts
				(arc
					(start 93.283278 -284.847538)
					(mid 92.625418 -284.847538)
					(end 93.283278 -284.847538)
				)
			)
		)
	)
	(zone
		(layers "F.Cu" "B.Cu" "In1.Cu" "In2.Cu" "In3.Cu" "In4.Cu" "In5.Cu" "In6.Cu"
			"In7.Cu" "In8.Cu" "In9.Cu" "In10.Cu" "In11.Cu" "In12.Cu" "In13.Cu" "In14.Cu"
			"In15.Cu" "In16.Cu"
		)
		(hatch none 0.5)
		(connect_pads
			(clearance 0)
		)
		(min_thickness 0.25)
		(keepout
			(tracks allowed)
			(vias allowed)
			(pads allowed)
			(copperpour allowed)
			(footprints not_allowed)
		)
		(placement
			(enabled no)
			(sheetname "")
		)
		(fill
			(thermal_gap 0.5)
			(thermal_bridge_width 0.5)
			(island_removal_mode 0)
		)
		(polygon
			(pts
				(arc
					(start 172.847 -74.767948)
					(mid 178.86299 -80.783938)
					(end 184.87898 -74.767948)
				)
				(arc
					(start 184.87898 -66.06794)
					(mid 178.86299 -60.05195)
					(end 172.847 -66.06794)
				)
			)
		)
	)
	(zone
		(layers "F.Cu" "B.Cu" "In1.Cu" "In2.Cu" "In3.Cu" "In4.Cu" "In5.Cu" "In6.Cu"
			"In7.Cu" "In8.Cu" "In9.Cu" "In10.Cu" "In11.Cu" "In12.Cu" "In13.Cu" "In14.Cu"
			"In15.Cu" "In16.Cu"
		)
		(hatch none 0.5)
		(connect_pads
			(clearance 0)
		)
		(min_thickness 0.25)
		(keepout
			(tracks not_allowed)
			(vias allowed)
			(pads allowed)
			(copperpour not_allowed)
			(footprints allowed)
		)
		(placement
			(enabled no)
			(sheetname "")
		)
		(fill
			(thermal_gap 0.5)
			(thermal_bridge_width 0.5)
			(island_removal_mode 0)
		)
		(polygon
			(pts
				(arc
					(start 109.9312 -224.291144)
					(mid 109.859211 -224.218985)
					(end 109.760766 -224.192592)
				)
				(arc
					(start 109.760766 -224.192592)
					(mid 109.621572 -224.250248)
					(end 109.563916 -224.389442)
				)
				(arc
					(start 109.563916 -224.389442)
					(mid 109.570673 -224.440323)
					(end 109.590332 -224.48774)
				)
				(arc
					(start 110.059978 -225.301556)
					(mid 110.131967 -225.373715)
					(end 110.230412 -225.400108)
				)
				(arc
					(start 110.230412 -225.400108)
					(mid 110.369606 -225.342452)
					(end 110.427262 -225.203258)
				)
				(arc
					(start 110.427262 -225.203258)
					(mid 110.420505 -225.152377)
					(end 110.400846 -225.10496)
				)
			)
		)
	)
	(zone
		(layers "F.Cu" "B.Cu" "In1.Cu" "In2.Cu" "In3.Cu" "In4.Cu" "In5.Cu" "In6.Cu"
			"In7.Cu" "In8.Cu" "In9.Cu" "In10.Cu" "In11.Cu" "In12.Cu" "In13.Cu" "In14.Cu"
			"In15.Cu" "In16.Cu"
		)
		(hatch none 0.5)
		(connect_pads
			(clearance 0)
		)
		(min_thickness 0.25)
		(keepout
			(tracks not_allowed)
			(vias allowed)
			(pads allowed)
			(copperpour not_allowed)
			(footprints allowed)
		)
		(placement
			(enabled no)
			(sheetname "")
		)
		(fill
			(thermal_gap 0.5)
			(thermal_bridge_width 0.5)
			(island_removal_mode 0)
		)
		(polygon
			(pts
				(arc
					(start 349.681292 -289.807142)
					(mid 349.023432 -289.807142)
					(end 349.681292 -289.807142)
				)
			)
		)
	)
	(zone
		(layers "F.Cu" "B.Cu" "In1.Cu" "In2.Cu" "In3.Cu" "In4.Cu" "In5.Cu" "In6.Cu"
			"In7.Cu" "In8.Cu" "In9.Cu" "In10.Cu" "In11.Cu" "In12.Cu" "In13.Cu" "In14.Cu"
			"In15.Cu" "In16.Cu"
		)
		(hatch none 0.5)
		(connect_pads
			(clearance 0)
		)
		(min_thickness 0.25)
		(keepout
			(tracks not_allowed)
			(vias allowed)
			(pads allowed)
			(copperpour not_allowed)
			(footprints allowed)
		)
		(placement
			(enabled no)
			(sheetname "")
		)
		(fill
			(thermal_gap 0.5)
			(thermal_bridge_width 0.5)
			(island_removal_mode 0)
		)
		(polygon
			(pts
				(arc
					(start 115.258342 -217.064336)
					(mid 114.600482 -217.064336)
					(end 115.258342 -217.064336)
				)
			)
		)
	)
	(zone
		(layers "F.Cu" "B.Cu" "In1.Cu" "In2.Cu" "In3.Cu" "In4.Cu" "In5.Cu" "In6.Cu"
			"In7.Cu" "In8.Cu" "In9.Cu" "In10.Cu" "In11.Cu" "In12.Cu" "In13.Cu" "In14.Cu"
			"In15.Cu" "In16.Cu"
		)
		(hatch none 0.5)
		(connect_pads
			(clearance 0)
		)
		(min_thickness 0.25)
		(keepout
			(tracks not_allowed)
			(vias allowed)
			(pads allowed)
			(copperpour not_allowed)
			(footprints allowed)
		)
		(placement
			(enabled no)
			(sheetname "")
		)
		(fill
			(thermal_gap 0.5)
			(thermal_bridge_width 0.5)
			(island_removal_mode 0)
		)
		(polygon
			(pts
				(arc
					(start 353.874324 -169.343832)
					(mid 354.233534 -169.195042)
					(end 354.382324 -168.835832)
				)
				(arc
					(start 354.382324 -168.835832)
					(mid 354.314267 -168.581835)
					(end 354.128324 -168.395904)
				)
				(arc
					(start 353.204272 -167.86225)
					(mid 353.081978 -167.811713)
					(end 352.95078 -167.794432)
				)
				(arc
					(start 352.950272 -167.794432)
					(mid 352.591062 -167.943222)
					(end 352.442272 -168.302432)
				)
				(arc
					(start 352.442272 -168.302432)
					(mid 352.510329 -168.556429)
					(end 352.696272 -168.74236)
				)
				(arc
					(start 353.620324 -169.276014)
					(mid 353.742618 -169.326551)
					(end 353.873816 -169.343832)
				)
			)
		)
	)
	(zone
		(layers "F.Cu" "B.Cu" "In1.Cu" "In2.Cu" "In3.Cu" "In4.Cu" "In5.Cu" "In6.Cu"
			"In7.Cu" "In8.Cu" "In9.Cu" "In10.Cu" "In11.Cu" "In12.Cu" "In13.Cu" "In14.Cu"
			"In15.Cu" "In16.Cu"
		)
		(hatch none 0.5)
		(connect_pads
			(clearance 0)
		)
		(min_thickness 0.25)
		(keepout
			(tracks not_allowed)
			(vias allowed)
			(pads allowed)
			(copperpour not_allowed)
			(footprints allowed)
		)
		(placement
			(enabled no)
			(sheetname "")
		)
		(fill
			(thermal_gap 0.5)
			(thermal_bridge_width 0.5)
			(island_removal_mode 0)
		)
		(polygon
			(pts
				(arc
					(start 92.625164 -283.219906)
					(mid 93.283024 -283.219906)
					(end 92.625164 -283.219906)
				)
			)
		)
	)
	(zone
		(layers "F.Cu" "B.Cu" "In1.Cu" "In2.Cu" "In3.Cu" "In4.Cu" "In5.Cu" "In6.Cu"
			"In7.Cu" "In8.Cu" "In9.Cu" "In10.Cu" "In11.Cu" "In12.Cu" "In13.Cu" "In14.Cu"
			"In15.Cu" "In16.Cu"
		)
		(hatch none 0.5)
		(connect_pads
			(clearance 0)
		)
		(min_thickness 0.25)
		(keepout
			(tracks not_allowed)
			(vias allowed)
			(pads allowed)
			(copperpour not_allowed)
			(footprints allowed)
		)
		(placement
			(enabled no)
			(sheetname "")
		)
		(fill
			(thermal_gap 0.5)
			(thermal_bridge_width 0.5)
			(island_removal_mode 0)
		)
		(polygon
			(pts
				(arc
					(start 91.074494 -281.39517)
					(mid 90.877644 -281.59202)
					(end 91.074494 -281.78887)
				)
				(arc
					(start 92.014294 -281.78887)
					(mid 92.211144 -281.59202)
					(end 92.014294 -281.39517)
				)
			)
		)
	)
	(zone
		(layers "F.Cu" "B.Cu" "In1.Cu" "In2.Cu" "In3.Cu" "In4.Cu" "In5.Cu" "In6.Cu"
			"In7.Cu" "In8.Cu" "In9.Cu" "In10.Cu" "In11.Cu" "In12.Cu" "In13.Cu" "In14.Cu"
			"In15.Cu" "In16.Cu"
		)
		(hatch none 0.5)
		(connect_pads
			(clearance 0)
		)
		(min_thickness 0.25)
		(keepout
			(tracks not_allowed)
			(vias allowed)
			(pads allowed)
			(copperpour not_allowed)
			(footprints allowed)
		)
		(placement
			(enabled no)
			(sheetname "")
		)
		(fill
			(thermal_gap 0.5)
			(thermal_bridge_width 0.5)
			(island_removal_mode 0)
		)
		(polygon
			(pts
				(arc
					(start 92.314014 -288.818828)
					(mid 92.29433 -288.866238)
					(end 92.287598 -288.917126)
				)
				(arc
					(start 92.287598 -288.917126)
					(mid 92.345254 -289.05632)
					(end 92.484448 -289.113976)
				)
				(arc
					(start 92.484448 -289.113976)
					(mid 92.582879 -289.08756)
					(end 92.654882 -289.015424)
				)
				(arc
					(start 93.124782 -288.201354)
					(mid 93.144466 -288.153944)
					(end 93.151198 -288.103056)
				)
				(arc
					(start 93.151198 -288.103056)
					(mid 93.093542 -287.963862)
					(end 92.954348 -287.906206)
				)
				(arc
					(start 92.954348 -287.906206)
					(mid 92.855917 -287.932622)
					(end 92.783914 -288.004758)
				)
			)
		)
	)
	(zone
		(layers "F.Cu" "B.Cu" "In1.Cu" "In2.Cu" "In3.Cu" "In4.Cu" "In5.Cu" "In6.Cu"
			"In7.Cu" "In8.Cu" "In9.Cu" "In10.Cu" "In11.Cu" "In12.Cu" "In13.Cu" "In14.Cu"
			"In15.Cu" "In16.Cu"
		)
		(hatch none 0.5)
		(connect_pads
			(clearance 0)
		)
		(min_thickness 0.25)
		(keepout
			(tracks not_allowed)
			(vias allowed)
			(pads allowed)
			(copperpour not_allowed)
			(footprints allowed)
		)
		(placement
			(enabled no)
			(sheetname "")
		)
		(fill
			(thermal_gap 0.5)
			(thermal_bridge_width 0.5)
			(island_removal_mode 0)
		)
		(polygon
			(pts
				(arc
					(start 368.007392 -285.661354)
					(mid 367.349532 -285.661354)
					(end 368.007392 -285.661354)
				)
			)
		)
	)
	(zone
		(layers "F.Cu" "B.Cu" "In1.Cu" "In2.Cu" "In3.Cu" "In4.Cu" "In5.Cu" "In6.Cu"
			"In7.Cu" "In8.Cu" "In9.Cu" "In10.Cu" "In11.Cu" "In12.Cu" "In13.Cu" "In14.Cu"
			"In15.Cu" "In16.Cu"
		)
		(hatch none 0.5)
		(connect_pads
			(clearance 0)
		)
		(min_thickness 0.25)
		(keepout
			(tracks not_allowed)
			(vias allowed)
			(pads allowed)
			(copperpour not_allowed)
			(footprints allowed)
		)
		(placement
			(enabled no)
			(sheetname "")
		)
		(fill
			(thermal_gap 0.5)
			(thermal_bridge_width 0.5)
			(island_removal_mode 0)
		)
		(polygon
			(pts
				(arc
					(start 351.92081 -217.064336)
					(mid 351.26295 -217.064336)
					(end 351.92081 -217.064336)
				)
			)
		)
	)
	(zone
		(layers "F.Cu" "B.Cu" "In1.Cu" "In2.Cu" "In3.Cu" "In4.Cu" "In5.Cu" "In6.Cu"
			"In7.Cu" "In8.Cu" "In9.Cu" "In10.Cu" "In11.Cu" "In12.Cu" "In13.Cu" "In14.Cu"
			"In15.Cu" "In16.Cu"
		)
		(hatch none 0.5)
		(connect_pads
			(clearance 0)
		)
		(min_thickness 0.25)
		(keepout
			(tracks not_allowed)
			(vias allowed)
			(pads allowed)
			(copperpour not_allowed)
			(footprints allowed)
		)
		(placement
			(enabled no)
			(sheetname "")
		)
		(fill
			(thermal_gap 0.5)
			(thermal_bridge_width 0.5)
			(island_removal_mode 0)
		)
		(polygon
			(pts
				(arc
					(start 117.4496 -224.291144)
					(mid 117.377611 -224.218985)
					(end 117.279166 -224.192592)
				)
				(arc
					(start 117.279166 -224.192592)
					(mid 117.139972 -224.250248)
					(end 117.082316 -224.389442)
				)
				(arc
					(start 117.082316 -224.389442)
					(mid 117.089073 -224.440323)
					(end 117.108732 -224.48774)
				)
				(arc
					(start 117.578378 -225.301556)
					(mid 117.650367 -225.373715)
					(end 117.748812 -225.400108)
				)
				(arc
					(start 117.748812 -225.400108)
					(mid 117.888006 -225.342452)
					(end 117.945662 -225.203258)
				)
				(arc
					(start 117.945662 -225.203258)
					(mid 117.938905 -225.152377)
					(end 117.919246 -225.10496)
				)
			)
		)
	)
	(zone
		(layers "F.Cu" "B.Cu" "In1.Cu" "In2.Cu" "In3.Cu" "In4.Cu" "In5.Cu" "In6.Cu"
			"In7.Cu" "In8.Cu" "In9.Cu" "In10.Cu" "In11.Cu" "In12.Cu" "In13.Cu" "In14.Cu"
			"In15.Cu" "In16.Cu"
		)
		(hatch none 0.5)
		(connect_pads
			(clearance 0)
		)
		(min_thickness 0.25)
		(keepout
			(tracks not_allowed)
			(vias allowed)
			(pads allowed)
			(copperpour not_allowed)
			(footprints allowed)
		)
		(placement
			(enabled no)
			(sheetname "")
		)
		(fill
			(thermal_gap 0.5)
			(thermal_bridge_width 0.5)
			(island_removal_mode 0)
		)
		(polygon
			(pts
				(arc
					(start 372.76913 -406.62352)
					(mid 372.38813 -407.00452)
					(end 372.76913 -407.38552)
				)
				(arc
					(start 373.63273 -407.38552)
					(mid 374.01373 -407.00452)
					(end 373.63273 -406.62352)
				)
			)
		)
	)
	(zone
		(layers "F.Cu" "B.Cu" "In1.Cu" "In2.Cu" "In3.Cu" "In4.Cu" "In5.Cu" "In6.Cu"
			"In7.Cu" "In8.Cu" "In9.Cu" "In10.Cu" "In11.Cu" "In12.Cu" "In13.Cu" "In14.Cu"
			"In15.Cu" "In16.Cu"
		)
		(hatch none 0.5)
		(connect_pads
			(clearance 0)
		)
		(min_thickness 0.25)
		(keepout
			(tracks not_allowed)
			(vias allowed)
			(pads allowed)
			(copperpour not_allowed)
			(footprints allowed)
		)
		(placement
			(enabled no)
			(sheetname "")
		)
		(fill
			(thermal_gap 0.5)
			(thermal_bridge_width 0.5)
			(island_removal_mode 0)
		)
		(polygon
			(pts
				(arc
					(start 95.052896 -221.133924)
					(mid 94.395036 -221.133924)
					(end 95.052896 -221.133924)
				)
			)
		)
	)
	(zone
		(layers "F.Cu" "B.Cu" "In1.Cu" "In2.Cu" "In3.Cu" "In4.Cu" "In5.Cu" "In6.Cu"
			"In7.Cu" "In8.Cu" "In9.Cu" "In10.Cu" "In11.Cu" "In12.Cu" "In13.Cu" "In14.Cu"
			"In15.Cu" "In16.Cu"
		)
		(hatch none 0.5)
		(connect_pads
			(clearance 0)
		)
		(min_thickness 0.25)
		(keepout
			(tracks not_allowed)
			(vias allowed)
			(pads allowed)
			(copperpour not_allowed)
			(footprints allowed)
		)
		(placement
			(enabled no)
			(sheetname "")
		)
		(fill
			(thermal_gap 0.5)
			(thermal_bridge_width 0.5)
			(island_removal_mode 0)
		)
		(polygon
			(pts
				(arc
					(start 124.327412 -213.545928)
					(mid 124.206179 -213.596145)
					(end 124.155962 -213.717378)
				)
				(arc
					(start 124.155962 -213.717886)
					(mid 124.160786 -213.758272)
					(end 124.175012 -213.796372)
				)
				(arc
					(start 124.644658 -214.701628)
					(mid 124.707949 -214.769116)
					(end 124.797058 -214.794084)
				)
				(arc
					(start 124.797058 -214.794084)
					(mid 124.918291 -214.743867)
					(end 124.968508 -214.622634)
				)
				(arc
					(start 124.968508 -214.622126)
					(mid 124.963684 -214.58174)
					(end 124.949458 -214.54364)
				)
				(arc
					(start 124.479812 -213.638384)
					(mid 124.416521 -213.570896)
					(end 124.327412 -213.545928)
				)
			)
		)
	)
	(zone
		(layers "F.Cu" "B.Cu" "In1.Cu" "In2.Cu" "In3.Cu" "In4.Cu" "In5.Cu" "In6.Cu"
			"In7.Cu" "In8.Cu" "In9.Cu" "In10.Cu" "In11.Cu" "In12.Cu" "In13.Cu" "In14.Cu"
			"In15.Cu" "In16.Cu"
		)
		(hatch none 0.5)
		(connect_pads
			(clearance 0)
		)
		(min_thickness 0.25)
		(keepout
			(tracks not_allowed)
			(vias allowed)
			(pads allowed)
			(copperpour not_allowed)
			(footprints allowed)
		)
		(placement
			(enabled no)
			(sheetname "")
		)
		(fill
			(thermal_gap 0.5)
			(thermal_bridge_width 0.5)
			(island_removal_mode 0)
		)
		(polygon
			(pts
				(arc
					(start 353.80041 -217.064336)
					(mid 353.14255 -217.064336)
					(end 353.80041 -217.064336)
				)
			)
		)
	)
	(zone
		(layers "F.Cu" "B.Cu" "In1.Cu" "In2.Cu" "In3.Cu" "In4.Cu" "In5.Cu" "In6.Cu"
			"In7.Cu" "In8.Cu" "In9.Cu" "In10.Cu" "In11.Cu" "In12.Cu" "In13.Cu" "In14.Cu"
			"In15.Cu" "In16.Cu"
		)
		(hatch none 0.5)
		(connect_pads
			(clearance 0)
		)
		(min_thickness 0.25)
		(keepout
			(tracks not_allowed)
			(vias allowed)
			(pads allowed)
			(copperpour not_allowed)
			(footprints allowed)
		)
		(placement
			(enabled no)
			(sheetname "")
		)
		(fill
			(thermal_gap 0.5)
			(thermal_bridge_width 0.5)
			(island_removal_mode 0)
		)
		(polygon
			(pts
				(arc
					(start 339.184996 -288.201354)
					(mid 339.20468 -288.153944)
					(end 339.211412 -288.103056)
				)
				(arc
					(start 339.211412 -288.103056)
					(mid 339.153756 -287.963862)
					(end 339.014562 -287.906206)
				)
				(arc
					(start 339.014562 -287.906206)
					(mid 338.916131 -287.932622)
					(end 338.844128 -288.004758)
				)
				(arc
					(start 338.374482 -288.818828)
					(mid 338.354798 -288.866238)
					(end 338.348066 -288.917126)
				)
				(arc
					(start 338.348066 -288.917126)
					(mid 338.405722 -289.05632)
					(end 338.544916 -289.113976)
				)
				(arc
					(start 338.544916 -289.113976)
					(mid 338.643347 -289.08756)
					(end 338.71535 -289.015424)
				)
			)
		)
	)
	(zone
		(layers "F.Cu" "B.Cu" "In1.Cu" "In2.Cu" "In3.Cu" "In4.Cu" "In5.Cu" "In6.Cu"
			"In7.Cu" "In8.Cu" "In9.Cu" "In10.Cu" "In11.Cu" "In12.Cu" "In13.Cu" "In14.Cu"
			"In15.Cu" "In16.Cu"
		)
		(hatch none 0.5)
		(connect_pads
			(clearance 0)
		)
		(min_thickness 0.25)
		(keepout
			(tracks not_allowed)
			(vias allowed)
			(pads allowed)
			(copperpour not_allowed)
			(footprints allowed)
		)
		(placement
			(enabled no)
			(sheetname "")
		)
		(fill
			(thermal_gap 0.5)
			(thermal_bridge_width 0.5)
			(island_removal_mode 0)
		)
		(polygon
			(pts
				(arc
					(start 369.614704 -182.115968)
					(mid 369.763494 -182.475178)
					(end 370.122704 -182.623968)
				)
				(arc
					(start 370.123212 -182.623968)
					(mid 370.254421 -182.606731)
					(end 370.376704 -182.55615)
				)
				(arc
					(start 371.300756 -182.022496)
					(mid 371.486689 -181.83656)
					(end 371.554756 -181.582568)
				)
				(arc
					(start 371.554756 -181.582568)
					(mid 371.405966 -181.223358)
					(end 371.046756 -181.074568)
				)
				(arc
					(start 371.046248 -181.074568)
					(mid 370.915039 -181.091805)
					(end 370.792756 -181.142386)
				)
				(arc
					(start 369.868704 -181.67604)
					(mid 369.682771 -181.861976)
					(end 369.614704 -182.115968)
				)
			)
		)
	)
	(zone
		(layers "F.Cu" "B.Cu" "In1.Cu" "In2.Cu" "In3.Cu" "In4.Cu" "In5.Cu" "In6.Cu"
			"In7.Cu" "In8.Cu" "In9.Cu" "In10.Cu" "In11.Cu" "In12.Cu" "In13.Cu" "In14.Cu"
			"In15.Cu" "In16.Cu"
		)
		(hatch none 0.5)
		(connect_pads
			(clearance 0)
		)
		(min_thickness 0.25)
		(keepout
			(tracks not_allowed)
			(vias allowed)
			(pads allowed)
			(copperpour not_allowed)
			(footprints allowed)
		)
		(placement
			(enabled no)
			(sheetname "")
		)
		(fill
			(thermal_gap 0.5)
			(thermal_bridge_width 0.5)
			(island_removal_mode 0)
		)
		(polygon
			(pts
				(arc
					(start 106.142282 -215.436704)
					(mid 106.800142 -215.436704)
					(end 106.142282 -215.436704)
				)
			)
		)
	)
	(zone
		(layers "F.Cu" "B.Cu" "In1.Cu" "In2.Cu" "In3.Cu" "In4.Cu" "In5.Cu" "In6.Cu"
			"In7.Cu" "In8.Cu" "In9.Cu" "In10.Cu" "In11.Cu" "In12.Cu" "In13.Cu" "In14.Cu"
			"In15.Cu" "In16.Cu"
		)
		(hatch none 0.5)
		(connect_pads
			(clearance 0)
		)
		(min_thickness 0.25)
		(keepout
			(tracks not_allowed)
			(vias allowed)
			(pads allowed)
			(copperpour not_allowed)
			(footprints allowed)
		)
		(placement
			(enabled no)
			(sheetname "")
		)
		(fill
			(thermal_gap 0.5)
			(thermal_bridge_width 0.5)
			(island_removal_mode 0)
		)
		(polygon
			(pts
				(arc
					(start 98.341942 -217.064336)
					(mid 97.684082 -217.064336)
					(end 98.341942 -217.064336)
				)
			)
		)
	)
	(zone
		(layers "F.Cu" "B.Cu" "In1.Cu" "In2.Cu" "In3.Cu" "In4.Cu" "In5.Cu" "In6.Cu"
			"In7.Cu" "In8.Cu" "In9.Cu" "In10.Cu" "In11.Cu" "In12.Cu" "In13.Cu" "In14.Cu"
			"In15.Cu" "In16.Cu"
		)
		(hatch none 0.5)
		(connect_pads
			(clearance 0)
		)
		(min_thickness 0.25)
		(keepout
			(tracks not_allowed)
			(vias allowed)
			(pads allowed)
			(copperpour not_allowed)
			(footprints allowed)
		)
		(placement
			(enabled no)
			(sheetname "")
		)
		(fill
			(thermal_gap 0.5)
			(thermal_bridge_width 0.5)
			(island_removal_mode 0)
		)
		(polygon
			(pts
				(arc
					(start 92.211398 -406.62352)
					(mid 91.830398 -407.00452)
					(end 92.211398 -407.38552)
				)
				(arc
					(start 93.074998 -407.38552)
					(mid 93.455998 -407.00452)
					(end 93.074998 -406.62352)
				)
			)
		)
	)
	(zone
		(layers "F.Cu" "B.Cu" "In1.Cu" "In2.Cu" "In3.Cu" "In4.Cu" "In5.Cu" "In6.Cu"
			"In7.Cu" "In8.Cu" "In9.Cu" "In10.Cu" "In11.Cu" "In12.Cu" "In13.Cu" "In14.Cu"
			"In15.Cu" "In16.Cu"
		)
		(hatch none 0.5)
		(connect_pads
			(clearance 0)
		)
		(min_thickness 0.25)
		(keepout
			(tracks not_allowed)
			(vias allowed)
			(pads allowed)
			(copperpour not_allowed)
			(footprints allowed)
		)
		(placement
			(enabled no)
			(sheetname "")
		)
		(fill
			(thermal_gap 0.5)
			(thermal_bridge_width 0.5)
			(island_removal_mode 0)
		)
		(polygon
			(pts
				(arc
					(start 170.335448 -11.624056)
					(mid 169.954448 -12.005056)
					(end 170.335448 -12.386056)
				)
				(arc
					(start 171.199048 -12.386056)
					(mid 171.580048 -12.005056)
					(end 171.199048 -11.624056)
				)
			)
		)
	)
	(zone
		(layers "F.Cu" "B.Cu" "In1.Cu" "In2.Cu" "In3.Cu" "In4.Cu" "In5.Cu" "In6.Cu"
			"In7.Cu" "In8.Cu" "In9.Cu" "In10.Cu" "In11.Cu" "In12.Cu" "In13.Cu" "In14.Cu"
			"In15.Cu" "In16.Cu"
		)
		(hatch none 0.5)
		(connect_pads
			(clearance 0)
		)
		(min_thickness 0.25)
		(keepout
			(tracks not_allowed)
			(vias allowed)
			(pads allowed)
			(copperpour not_allowed)
			(footprints allowed)
		)
		(placement
			(enabled no)
			(sheetname "")
		)
		(fill
			(thermal_gap 0.5)
			(thermal_bridge_width 0.5)
			(island_removal_mode 0)
		)
		(polygon
			(pts
				(arc
					(start 96.774 -224.291144)
					(mid 96.702011 -224.218985)
					(end 96.603566 -224.192592)
				)
				(arc
					(start 96.603566 -224.192592)
					(mid 96.464372 -224.250248)
					(end 96.406716 -224.389442)
				)
				(arc
					(start 96.406716 -224.389442)
					(mid 96.413473 -224.440323)
					(end 96.433132 -224.48774)
				)
				(arc
					(start 96.902778 -225.301556)
					(mid 96.974767 -225.373715)
					(end 97.073212 -225.400108)
				)
				(arc
					(start 97.073212 -225.400108)
					(mid 97.212406 -225.342452)
					(end 97.270062 -225.203258)
				)
				(arc
					(start 97.270062 -225.203258)
					(mid 97.263305 -225.152377)
					(end 97.243646 -225.10496)
				)
			)
		)
	)
	(zone
		(layers "F.Cu" "B.Cu" "In1.Cu" "In2.Cu" "In3.Cu" "In4.Cu" "In5.Cu" "In6.Cu"
			"In7.Cu" "In8.Cu" "In9.Cu" "In10.Cu" "In11.Cu" "In12.Cu" "In13.Cu" "In14.Cu"
			"In15.Cu" "In16.Cu"
		)
		(hatch none 0.5)
		(connect_pads
			(clearance 0)
		)
		(min_thickness 0.25)
		(keepout
			(tracks not_allowed)
			(vias allowed)
			(pads allowed)
			(copperpour not_allowed)
			(footprints allowed)
		)
		(placement
			(enabled no)
			(sheetname "")
		)
		(fill
			(thermal_gap 0.5)
			(thermal_bridge_width 0.5)
			(island_removal_mode 0)
		)
		(polygon
			(pts
				(arc
					(start 105.312464 -282.405836)
					(mid 105.970324 -282.405836)
					(end 105.312464 -282.405836)
				)
			)
		)
	)
	(zone
		(layers "F.Cu" "B.Cu" "In1.Cu" "In2.Cu" "In3.Cu" "In4.Cu" "In5.Cu" "In6.Cu"
			"In7.Cu" "In8.Cu" "In9.Cu" "In10.Cu" "In11.Cu" "In12.Cu" "In13.Cu" "In14.Cu"
			"In15.Cu" "In16.Cu"
		)
		(hatch none 0.5)
		(connect_pads
			(clearance 0)
		)
		(min_thickness 0.25)
		(keepout
			(tracks not_allowed)
			(vias allowed)
			(pads allowed)
			(copperpour not_allowed)
			(footprints allowed)
		)
		(placement
			(enabled no)
			(sheetname "")
		)
		(fill
			(thermal_gap 0.5)
			(thermal_bridge_width 0.5)
			(island_removal_mode 0)
		)
		(polygon
			(pts
				(arc
					(start 368.83721 -217.064336)
					(mid 368.17935 -217.064336)
					(end 368.83721 -217.064336)
				)
			)
		)
	)
	(zone
		(layers "F.Cu" "B.Cu" "In1.Cu" "In2.Cu" "In3.Cu" "In4.Cu" "In5.Cu" "In6.Cu"
			"In7.Cu" "In8.Cu" "In9.Cu" "In10.Cu" "In11.Cu" "In12.Cu" "In13.Cu" "In14.Cu"
			"In15.Cu" "In16.Cu"
		)
		(hatch none 0.5)
		(connect_pads
			(clearance 0)
		)
		(min_thickness 0.25)
		(keepout
			(tracks not_allowed)
			(vias allowed)
			(pads allowed)
			(copperpour not_allowed)
			(footprints allowed)
		)
		(placement
			(enabled no)
			(sheetname "")
		)
		(fill
			(thermal_gap 0.5)
			(thermal_bridge_width 0.5)
			(island_removal_mode 0)
		)
		(polygon
			(pts
				(arc
					(start 126.957582 -284.74924)
					(mid 126.885593 -284.677081)
					(end 126.787148 -284.650688)
				)
				(arc
					(start 126.787148 -284.650688)
					(mid 126.647954 -284.708344)
					(end 126.590298 -284.847538)
				)
				(arc
					(start 126.590298 -284.847538)
					(mid 126.597055 -284.898419)
					(end 126.616714 -284.945836)
				)
				(arc
					(start 127.08636 -285.759652)
					(mid 127.158349 -285.831811)
					(end 127.256794 -285.858204)
				)
				(arc
					(start 127.256794 -285.858204)
					(mid 127.395988 -285.800548)
					(end 127.453644 -285.661354)
				)
				(arc
					(start 127.453644 -285.661354)
					(mid 127.446887 -285.610473)
					(end 127.427228 -285.563056)
				)
			)
		)
	)
	(zone
		(layers "F.Cu" "B.Cu" "In1.Cu" "In2.Cu" "In3.Cu" "In4.Cu" "In5.Cu" "In6.Cu"
			"In7.Cu" "In8.Cu" "In9.Cu" "In10.Cu" "In11.Cu" "In12.Cu" "In13.Cu" "In14.Cu"
			"In15.Cu" "In16.Cu"
		)
		(hatch none 0.5)
		(connect_pads
			(clearance 0)
		)
		(min_thickness 0.25)
		(keepout
			(tracks not_allowed)
			(vias allowed)
			(pads allowed)
			(copperpour not_allowed)
			(footprints allowed)
		)
		(placement
			(enabled no)
			(sheetname "")
		)
		(fill
			(thermal_gap 0.5)
			(thermal_bridge_width 0.5)
			(island_removal_mode 0)
		)
		(polygon
			(pts
				(arc
					(start 298.51096 -66.060828)
					(mid 293.00297 -60.552838)
					(end 287.49498 -66.060828)
				)
				(arc
					(start 287.49498 -74.760836)
					(mid 293.00297 -80.268826)
					(end 298.51096 -74.760836)
				)
			)
		)
	)
	(zone
		(layers "F.Cu" "B.Cu" "In1.Cu" "In2.Cu" "In3.Cu" "In4.Cu" "In5.Cu" "In6.Cu"
			"In7.Cu" "In8.Cu" "In9.Cu" "In10.Cu" "In11.Cu" "In12.Cu" "In13.Cu" "In14.Cu"
			"In15.Cu" "In16.Cu"
		)
		(hatch none 0.5)
		(connect_pads
			(clearance 0)
		)
		(min_thickness 0.25)
		(keepout
			(tracks not_allowed)
			(vias allowed)
			(pads allowed)
			(copperpour not_allowed)
			(footprints allowed)
		)
		(placement
			(enabled no)
			(sheetname "")
		)
		(fill
			(thermal_gap 0.5)
			(thermal_bridge_width 0.5)
			(island_removal_mode 0)
		)
		(polygon
			(pts
				(arc
					(start 119.957342 -225.203258)
					(mid 119.299482 -225.203258)
					(end 119.957342 -225.203258)
				)
			)
		)
	)
	(zone
		(layers "F.Cu" "B.Cu" "In1.Cu" "In2.Cu" "In3.Cu" "In4.Cu" "In5.Cu" "In6.Cu"
			"In7.Cu" "In8.Cu" "In9.Cu" "In10.Cu" "In11.Cu" "In12.Cu" "In13.Cu" "In14.Cu"
			"In15.Cu" "In16.Cu"
		)
		(hatch none 0.5)
		(connect_pads
			(clearance 0)
		)
		(min_thickness 0.25)
		(keepout
			(tracks not_allowed)
			(vias allowed)
			(pads allowed)
			(copperpour not_allowed)
			(footprints allowed)
		)
		(placement
			(enabled no)
			(sheetname "")
		)
		(fill
			(thermal_gap 0.5)
			(thermal_bridge_width 0.5)
			(island_removal_mode 0)
		)
		(polygon
			(pts
				(arc
					(start 241.044984 -57.43829)
					(mid 240.663984 -57.05729)
					(end 240.282984 -57.43829)
				)
				(arc
					(start 240.282984 -58.30189)
					(mid 240.663984 -58.68289)
					(end 241.044984 -58.30189)
				)
			)
		)
	)
	(zone
		(layers "F.Cu" "B.Cu" "In1.Cu" "In2.Cu" "In3.Cu" "In4.Cu" "In5.Cu" "In6.Cu"
			"In7.Cu" "In8.Cu" "In9.Cu" "In10.Cu" "In11.Cu" "In12.Cu" "In13.Cu" "In14.Cu"
			"In15.Cu" "In16.Cu"
		)
		(hatch none 0.5)
		(connect_pads
			(clearance 0)
		)
		(min_thickness 0.25)
		(keepout
			(tracks not_allowed)
			(vias allowed)
			(pads allowed)
			(copperpour not_allowed)
			(footprints allowed)
		)
		(placement
			(enabled no)
			(sheetname "")
		)
		(fill
			(thermal_gap 0.5)
			(thermal_bridge_width 0.5)
			(island_removal_mode 0)
		)
		(polygon
			(pts
				(arc
					(start 357.089456 -214.622634)
					(mid 356.431596 -214.622634)
					(end 357.089456 -214.622634)
				)
			)
		)
	)
	(zone
		(layers "F.Cu" "B.Cu" "In1.Cu" "In2.Cu" "In3.Cu" "In4.Cu" "In5.Cu" "In6.Cu"
			"In7.Cu" "In8.Cu" "In9.Cu" "In10.Cu" "In11.Cu" "In12.Cu" "In13.Cu" "In14.Cu"
			"In15.Cu" "In16.Cu"
		)
		(hatch none 0.5)
		(connect_pads
			(clearance 0)
		)
		(min_thickness 0.25)
		(keepout
			(tracks not_allowed)
			(vias allowed)
			(pads allowed)
			(copperpour not_allowed)
			(footprints allowed)
		)
		(placement
			(enabled no)
			(sheetname "")
		)
		(fill
			(thermal_gap 0.5)
			(thermal_bridge_width 0.5)
			(island_removal_mode 0)
		)
		(polygon
			(pts
				(arc
					(start 341.89416 -214.720932)
					(mid 341.913844 -214.673522)
					(end 341.920576 -214.622634)
				)
				(arc
					(start 341.920576 -214.622634)
					(mid 341.86292 -214.48344)
					(end 341.723726 -214.425784)
				)
				(arc
					(start 341.723726 -214.425784)
					(mid 341.625295 -214.4522)
					(end 341.553292 -214.524336)
				)
				(arc
					(start 341.083646 -215.338406)
					(mid 341.063962 -215.385816)
					(end 341.05723 -215.436704)
				)
				(arc
					(start 341.05723 -215.436704)
					(mid 341.114886 -215.575898)
					(end 341.25408 -215.633554)
				)
				(arc
					(start 341.25408 -215.633554)
					(mid 341.352511 -215.607138)
					(end 341.424514 -215.535002)
				)
			)
		)
	)
	(zone
		(layers "F.Cu" "B.Cu" "In1.Cu" "In2.Cu" "In3.Cu" "In4.Cu" "In5.Cu" "In6.Cu"
			"In7.Cu" "In8.Cu" "In9.Cu" "In10.Cu" "In11.Cu" "In12.Cu" "In13.Cu" "In14.Cu"
			"In15.Cu" "In16.Cu"
		)
		(hatch none 0.5)
		(connect_pads
			(clearance 0)
		)
		(min_thickness 0.25)
		(keepout
			(tracks not_allowed)
			(vias allowed)
			(pads allowed)
			(copperpour not_allowed)
			(footprints allowed)
		)
		(placement
			(enabled no)
			(sheetname "")
		)
		(fill
			(thermal_gap 0.5)
			(thermal_bridge_width 0.5)
			(island_removal_mode 0)
		)
		(polygon
			(pts
				(arc
					(start 103.980996 -213.732618)
					(mid 103.323136 -213.732618)
					(end 103.980996 -213.732618)
				)
			)
		)
	)
	(zone
		(layers "F.Cu" "B.Cu" "In1.Cu" "In2.Cu" "In3.Cu" "In4.Cu" "In5.Cu" "In6.Cu"
			"In7.Cu" "In8.Cu" "In9.Cu" "In10.Cu" "In11.Cu" "In12.Cu" "In13.Cu" "In14.Cu"
			"In15.Cu" "In16.Cu"
		)
		(hatch none 0.5)
		(connect_pads
			(clearance 0)
		)
		(min_thickness 0.25)
		(keepout
			(tracks not_allowed)
			(vias allowed)
			(pads allowed)
			(copperpour not_allowed)
			(footprints allowed)
		)
		(placement
			(enabled no)
			(sheetname "")
		)
		(fill
			(thermal_gap 0.5)
			(thermal_bridge_width 0.5)
			(island_removal_mode 0)
		)
		(polygon
			(pts
				(arc
					(start 96.932496 -221.133924)
					(mid 96.274636 -221.133924)
					(end 96.932496 -221.133924)
				)
			)
		)
	)
	(zone
		(layers "F.Cu" "B.Cu" "In1.Cu" "In2.Cu" "In3.Cu" "In4.Cu" "In5.Cu" "In6.Cu"
			"In7.Cu" "In8.Cu" "In9.Cu" "In10.Cu" "In11.Cu" "In12.Cu" "In13.Cu" "In14.Cu"
			"In15.Cu" "In16.Cu"
		)
		(hatch none 0.5)
		(connect_pads
			(clearance 0)
		)
		(min_thickness 0.25)
		(keepout
			(tracks not_allowed)
			(vias allowed)
			(pads allowed)
			(copperpour not_allowed)
			(footprints allowed)
		)
		(placement
			(enabled no)
			(sheetname "")
		)
		(fill
			(thermal_gap 0.5)
			(thermal_bridge_width 0.5)
			(island_removal_mode 0)
		)
		(polygon
			(pts
				(arc
					(start 105.390696 -221.133924)
					(mid 104.732836 -221.133924)
					(end 105.390696 -221.133924)
				)
			)
		)
	)
	(zone
		(layers "F.Cu" "B.Cu" "In1.Cu" "In2.Cu" "In3.Cu" "In4.Cu" "In5.Cu" "In6.Cu"
			"In7.Cu" "In8.Cu" "In9.Cu" "In10.Cu" "In11.Cu" "In12.Cu" "In13.Cu" "In14.Cu"
			"In15.Cu" "In16.Cu"
		)
		(hatch none 0.5)
		(connect_pads
			(clearance 0)
		)
		(min_thickness 0.25)
		(keepout
			(tracks not_allowed)
			(vias allowed)
			(pads allowed)
			(copperpour not_allowed)
			(footprints allowed)
		)
		(placement
			(enabled no)
			(sheetname "")
		)
		(fill
			(thermal_gap 0.5)
			(thermal_bridge_width 0.5)
			(island_removal_mode 0)
		)
		(polygon
			(pts
				(arc
					(start 347.605096 -72.197976)
					(mid 347.986096 -71.816976)
					(end 347.605096 -71.435976)
				)
				(arc
					(start 346.741496 -71.435976)
					(mid 346.360496 -71.816976)
					(end 346.741496 -72.197976)
				)
			)
		)
	)
	(zone
		(layers "F.Cu" "B.Cu" "In1.Cu" "In2.Cu" "In3.Cu" "In4.Cu" "In5.Cu" "In6.Cu"
			"In7.Cu" "In8.Cu" "In9.Cu" "In10.Cu" "In11.Cu" "In12.Cu" "In13.Cu" "In14.Cu"
			"In15.Cu" "In16.Cu"
		)
		(hatch none 0.5)
		(connect_pads
			(clearance 0)
		)
		(min_thickness 0.25)
		(keepout
			(tracks not_allowed)
			(vias allowed)
			(pads allowed)
			(copperpour not_allowed)
			(footprints allowed)
		)
		(placement
			(enabled no)
			(sheetname "")
		)
		(fill
			(thermal_gap 0.5)
			(thermal_bridge_width 0.5)
			(island_removal_mode 0)
		)
		(polygon
			(pts
				(arc
					(start 60.232798 -403.502876)
					(mid 59.851798 -403.883876)
					(end 60.232798 -404.264876)
				)
				(arc
					(start 61.096398 -404.264876)
					(mid 61.477398 -403.883876)
					(end 61.096398 -403.502876)
				)
			)
		)
	)
	(zone
		(layers "F.Cu" "B.Cu" "In1.Cu" "In2.Cu" "In3.Cu" "In4.Cu" "In5.Cu" "In6.Cu"
			"In7.Cu" "In8.Cu" "In9.Cu" "In10.Cu" "In11.Cu" "In12.Cu" "In13.Cu" "In14.Cu"
			"In15.Cu" "In16.Cu"
		)
		(hatch none 0.5)
		(connect_pads
			(clearance 0)
		)
		(min_thickness 0.25)
		(keepout
			(tracks not_allowed)
			(vias allowed)
			(pads allowed)
			(copperpour not_allowed)
			(footprints allowed)
		)
		(placement
			(enabled no)
			(sheetname "")
		)
		(fill
			(thermal_gap 0.5)
			(thermal_bridge_width 0.5)
			(island_removal_mode 0)
		)
		(polygon
			(pts
				(arc
					(start 352.030792 -274.266914)
					(mid 351.372932 -274.266914)
					(end 352.030792 -274.266914)
				)
			)
		)
	)
	(zone
		(layers "F.Cu" "B.Cu" "In1.Cu" "In2.Cu" "In3.Cu" "In4.Cu" "In5.Cu" "In6.Cu"
			"In7.Cu" "In8.Cu" "In9.Cu" "In10.Cu" "In11.Cu" "In12.Cu" "In13.Cu" "In14.Cu"
			"In15.Cu" "In16.Cu"
		)
		(hatch none 0.5)
		(connect_pads
			(clearance 0)
		)
		(min_thickness 0.25)
		(keepout
			(tracks not_allowed)
			(vias allowed)
			(pads allowed)
			(copperpour not_allowed)
			(footprints allowed)
		)
		(placement
			(enabled no)
			(sheetname "")
		)
		(fill
			(thermal_gap 0.5)
			(thermal_bridge_width 0.5)
			(island_removal_mode 0)
		)
		(polygon
			(pts
				(arc
					(start 224.32518 -128.209548)
					(mid 223.94418 -127.828548)
					(end 223.56318 -128.209548)
				)
				(arc
					(start 223.56318 -129.073148)
					(mid 223.94418 -129.454148)
					(end 224.32518 -129.073148)
				)
			)
		)
	)
	(zone
		(layers "F.Cu" "B.Cu" "In1.Cu" "In2.Cu" "In3.Cu" "In4.Cu" "In5.Cu" "In6.Cu"
			"In7.Cu" "In8.Cu" "In9.Cu" "In10.Cu" "In11.Cu" "In12.Cu" "In13.Cu" "In14.Cu"
			"In15.Cu" "In16.Cu"
		)
		(hatch none 0.5)
		(connect_pads
			(clearance 0)
		)
		(min_thickness 0.25)
		(keepout
			(tracks not_allowed)
			(vias allowed)
			(pads allowed)
			(copperpour not_allowed)
			(footprints allowed)
		)
		(placement
			(enabled no)
			(sheetname "")
		)
		(fill
			(thermal_gap 0.5)
			(thermal_bridge_width 0.5)
			(island_removal_mode 0)
		)
		(polygon
			(pts
				(arc
					(start 108.679742 -221.94774)
					(mid 108.021882 -221.94774)
					(end 108.679742 -221.94774)
				)
			)
		)
	)
	(zone
		(layers "F.Cu" "B.Cu" "In1.Cu" "In2.Cu" "In3.Cu" "In4.Cu" "In5.Cu" "In6.Cu"
			"In7.Cu" "In8.Cu" "In9.Cu" "In10.Cu" "In11.Cu" "In12.Cu" "In13.Cu" "In14.Cu"
			"In15.Cu" "In16.Cu"
		)
		(hatch none 0.5)
		(connect_pads
			(clearance 0)
		)
		(min_thickness 0.25)
		(keepout
			(tracks not_allowed)
			(vias allowed)
			(pads allowed)
			(copperpour not_allowed)
			(footprints allowed)
		)
		(placement
			(enabled no)
			(sheetname "")
		)
		(fill
			(thermal_gap 0.5)
			(thermal_bridge_width 0.5)
			(island_removal_mode 0)
		)
		(polygon
			(pts
				(arc
					(start 72.485758 -403.502876)
					(mid 72.104758 -403.883876)
					(end 72.485758 -404.264876)
				)
				(arc
					(start 73.349358 -404.264876)
					(mid 73.730358 -403.883876)
					(end 73.349358 -403.502876)
				)
			)
		)
	)
	(zone
		(layers "F.Cu" "B.Cu" "In1.Cu" "In2.Cu" "In3.Cu" "In4.Cu" "In5.Cu" "In6.Cu"
			"In7.Cu" "In8.Cu" "In9.Cu" "In10.Cu" "In11.Cu" "In12.Cu" "In13.Cu" "In14.Cu"
			"In15.Cu" "In16.Cu"
		)
		(hatch none 0.5)
		(connect_pads
			(clearance 0)
		)
		(min_thickness 0.25)
		(keepout
			(tracks not_allowed)
			(vias allowed)
			(pads allowed)
			(copperpour not_allowed)
			(footprints allowed)
		)
		(placement
			(enabled no)
			(sheetname "")
		)
		(fill
			(thermal_gap 0.5)
			(thermal_bridge_width 0.5)
			(island_removal_mode 0)
		)
		(polygon
			(pts
				(arc
					(start 102.571296 -224.389442)
					(mid 101.913436 -224.389442)
					(end 102.571296 -224.389442)
				)
			)
		)
	)
	(zone
		(layers "F.Cu" "B.Cu" "In1.Cu" "In2.Cu" "In3.Cu" "In4.Cu" "In5.Cu" "In6.Cu"
			"In7.Cu" "In8.Cu" "In9.Cu" "In10.Cu" "In11.Cu" "In12.Cu" "In13.Cu" "In14.Cu"
			"In15.Cu" "In16.Cu"
		)
		(hatch none 0.5)
		(connect_pads
			(clearance 0)
		)
		(min_thickness 0.25)
		(keepout
			(tracks not_allowed)
			(vias allowed)
			(pads allowed)
			(copperpour not_allowed)
			(footprints allowed)
		)
		(placement
			(enabled no)
			(sheetname "")
		)
		(fill
			(thermal_gap 0.5)
			(thermal_bridge_width 0.5)
			(island_removal_mode 0)
		)
		(polygon
			(pts
				(arc
					(start 339.075268 -221.035626)
					(mid 339.003279 -220.963467)
					(end 338.904834 -220.937074)
				)
				(arc
					(start 338.904834 -220.937074)
					(mid 338.76564 -220.99473)
					(end 338.707984 -221.133924)
				)
				(arc
					(start 338.707984 -221.133924)
					(mid 338.714741 -221.184805)
					(end 338.7344 -221.232222)
				)
				(arc
					(start 339.204046 -222.046038)
					(mid 339.276035 -222.118197)
					(end 339.37448 -222.14459)
				)
				(arc
					(start 339.37448 -222.14459)
					(mid 339.513674 -222.086934)
					(end 339.57133 -221.94774)
				)
				(arc
					(start 339.57133 -221.94774)
					(mid 339.564573 -221.896859)
					(end 339.544914 -221.849442)
				)
			)
		)
	)
	(zone
		(layers "F.Cu" "B.Cu" "In1.Cu" "In2.Cu" "In3.Cu" "In4.Cu" "In5.Cu" "In6.Cu"
			"In7.Cu" "In8.Cu" "In9.Cu" "In10.Cu" "In11.Cu" "In12.Cu" "In13.Cu" "In14.Cu"
			"In15.Cu" "In16.Cu"
		)
		(hatch none 0.5)
		(connect_pads
			(clearance 0)
		)
		(min_thickness 0.25)
		(keepout
			(tracks not_allowed)
			(vias allowed)
			(pads allowed)
			(copperpour not_allowed)
			(footprints allowed)
		)
		(placement
			(enabled no)
			(sheetname "")
		)
		(fill
			(thermal_gap 0.5)
			(thermal_bridge_width 0.5)
			(island_removal_mode 0)
		)
		(polygon
			(pts
				(arc
					(start 121.289318 -288.917126)
					(mid 121.947178 -288.917126)
					(end 121.289318 -288.917126)
				)
			)
		)
	)
	(zone
		(layers "F.Cu" "B.Cu" "In1.Cu" "In2.Cu" "In3.Cu" "In4.Cu" "In5.Cu" "In6.Cu"
			"In7.Cu" "In8.Cu" "In9.Cu" "In10.Cu" "In11.Cu" "In12.Cu" "In13.Cu" "In14.Cu"
			"In15.Cu" "In16.Cu"
		)
		(hatch none 0.5)
		(connect_pads
			(clearance 0)
		)
		(min_thickness 0.25)
		(keepout
			(tracks not_allowed)
			(vias allowed)
			(pads allowed)
			(copperpour not_allowed)
			(footprints allowed)
		)
		(placement
			(enabled no)
			(sheetname "")
		)
		(fill
			(thermal_gap 0.5)
			(thermal_bridge_width 0.5)
			(island_removal_mode 0)
		)
		(polygon
			(pts
				(arc
					(start 332.895448 -409.649168)
					(mid 332.514448 -410.030168)
					(end 332.895448 -410.411168)
				)
				(arc
					(start 333.759048 -410.411168)
					(mid 334.140048 -410.030168)
					(end 333.759048 -409.649168)
				)
			)
		)
	)
	(zone
		(layers "F.Cu" "B.Cu" "In1.Cu" "In2.Cu" "In3.Cu" "In4.Cu" "In5.Cu" "In6.Cu"
			"In7.Cu" "In8.Cu" "In9.Cu" "In10.Cu" "In11.Cu" "In12.Cu" "In13.Cu" "In14.Cu"
			"In15.Cu" "In16.Cu"
		)
		(hatch none 0.5)
		(connect_pads
			(clearance 0)
		)
		(min_thickness 0.25)
		(keepout
			(tracks not_allowed)
			(vias allowed)
			(pads allowed)
			(copperpour not_allowed)
			(footprints allowed)
		)
		(placement
			(enabled no)
			(sheetname "")
		)
		(fill
			(thermal_gap 0.5)
			(thermal_bridge_width 0.5)
			(island_removal_mode 0)
		)
		(polygon
			(pts
				(arc
					(start 120.841262 -289.003232)
					(mid 120.857186 -288.961481)
					(end 120.862598 -288.917126)
				)
				(arc
					(start 120.862598 -288.917126)
					(mid 120.808662 -288.786912)
					(end 120.678448 -288.732976)
				)
				(arc
					(start 120.678448 -288.732976)
					(mid 120.583428 -288.759384)
					(end 120.515634 -288.83102)
				)
				(arc
					(start 120.04548 -289.721036)
					(mid 120.029556 -289.762787)
					(end 120.024144 -289.807142)
				)
				(arc
					(start 120.024144 -289.807142)
					(mid 120.07808 -289.937356)
					(end 120.208294 -289.991292)
				)
				(arc
					(start 120.208294 -289.991292)
					(mid 120.303314 -289.964884)
					(end 120.371108 -289.893248)
				)
			)
		)
	)
	(zone
		(layers "F.Cu" "B.Cu" "In1.Cu" "In2.Cu" "In3.Cu" "In4.Cu" "In5.Cu" "In6.Cu"
			"In7.Cu" "In8.Cu" "In9.Cu" "In10.Cu" "In11.Cu" "In12.Cu" "In13.Cu" "In14.Cu"
			"In15.Cu" "In16.Cu"
		)
		(hatch none 0.5)
		(connect_pads
			(clearance 0)
		)
		(min_thickness 0.25)
		(keepout
			(tracks not_allowed)
			(vias allowed)
			(pads allowed)
			(copperpour not_allowed)
			(footprints allowed)
		)
		(placement
			(enabled no)
			(sheetname "")
		)
		(fill
			(thermal_gap 0.5)
			(thermal_bridge_width 0.5)
			(island_removal_mode 0)
		)
		(polygon
			(pts
				(arc
					(start 353.641914 -217.162634)
					(mid 353.661598 -217.115224)
					(end 353.66833 -217.064336)
				)
				(arc
					(start 353.66833 -217.064336)
					(mid 353.610674 -216.925142)
					(end 353.47148 -216.867486)
				)
				(arc
					(start 353.47148 -216.867486)
					(mid 353.373049 -216.893902)
					(end 353.301046 -216.966038)
				)
				(arc
					(start 352.8314 -217.780108)
					(mid 352.811716 -217.827518)
					(end 352.804984 -217.878406)
				)
				(arc
					(start 352.804984 -217.878406)
					(mid 352.86264 -218.0176)
					(end 353.001834 -218.075256)
				)
				(arc
					(start 353.001834 -218.075256)
					(mid 353.100265 -218.04884)
					(end 353.172268 -217.976704)
				)
			)
		)
	)
	(zone
		(layers "F.Cu" "B.Cu" "In1.Cu" "In2.Cu" "In3.Cu" "In4.Cu" "In5.Cu" "In6.Cu"
			"In7.Cu" "In8.Cu" "In9.Cu" "In10.Cu" "In11.Cu" "In12.Cu" "In13.Cu" "In14.Cu"
			"In15.Cu" "In16.Cu"
		)
		(hatch none 0.5)
		(connect_pads
			(clearance 0)
		)
		(min_thickness 0.25)
		(keepout
			(tracks not_allowed)
			(vias allowed)
			(pads allowed)
			(copperpour not_allowed)
			(footprints allowed)
		)
		(placement
			(enabled no)
			(sheetname "")
		)
		(fill
			(thermal_gap 0.5)
			(thermal_bridge_width 0.5)
			(island_removal_mode 0)
		)
		(polygon
			(pts
				(arc
					(start 99.751896 -221.133924)
					(mid 99.094036 -221.133924)
					(end 99.751896 -221.133924)
				)
			)
		)
	)
	(zone
		(layers "F.Cu" "B.Cu" "In1.Cu" "In2.Cu" "In3.Cu" "In4.Cu" "In5.Cu" "In6.Cu"
			"In7.Cu" "In8.Cu" "In9.Cu" "In10.Cu" "In11.Cu" "In12.Cu" "In13.Cu" "In14.Cu"
			"In15.Cu" "In16.Cu"
		)
		(hatch none 0.5)
		(connect_pads
			(clearance 0)
		)
		(min_thickness 0.25)
		(keepout
			(tracks not_allowed)
			(vias allowed)
			(pads allowed)
			(copperpour not_allowed)
			(footprints allowed)
		)
		(placement
			(enabled no)
			(sheetname "")
		)
		(fill
			(thermal_gap 0.5)
			(thermal_bridge_width 0.5)
			(island_removal_mode 0)
		)
		(polygon
			(pts
				(arc
					(start 357.669592 -277.522432)
					(mid 357.011732 -277.522432)
					(end 357.669592 -277.522432)
				)
			)
		)
	)
	(zone
		(layers "F.Cu" "B.Cu" "In1.Cu" "In2.Cu" "In3.Cu" "In4.Cu" "In5.Cu" "In6.Cu"
			"In7.Cu" "In8.Cu" "In9.Cu" "In10.Cu" "In11.Cu" "In12.Cu" "In13.Cu" "In14.Cu"
			"In15.Cu" "In16.Cu"
		)
		(hatch none 0.5)
		(connect_pads
			(clearance 0)
		)
		(min_thickness 0.25)
		(keepout
			(tracks not_allowed)
			(vias allowed)
			(pads allowed)
			(copperpour not_allowed)
			(footprints allowed)
		)
		(placement
			(enabled no)
			(sheetname "")
		)
		(fill
			(thermal_gap 0.5)
			(thermal_bridge_width 0.5)
			(island_removal_mode 0)
		)
		(polygon
			(pts
				(arc
					(start 349.882714 -220.418152)
					(mid 349.902398 -220.370742)
					(end 349.90913 -220.319854)
				)
				(arc
					(start 349.90913 -220.319854)
					(mid 349.851474 -220.18066)
					(end 349.71228 -220.123004)
				)
				(arc
					(start 349.71228 -220.123004)
					(mid 349.613849 -220.14942)
					(end 349.541846 -220.221556)
				)
				(arc
					(start 349.0722 -221.035626)
					(mid 349.052516 -221.083036)
					(end 349.045784 -221.133924)
				)
				(arc
					(start 349.045784 -221.133924)
					(mid 349.10344 -221.273118)
					(end 349.242634 -221.330774)
				)
				(arc
					(start 349.242634 -221.330774)
					(mid 349.341065 -221.304358)
					(end 349.413068 -221.232222)
				)
			)
		)
	)
	(zone
		(layers "F.Cu" "B.Cu" "In1.Cu" "In2.Cu" "In3.Cu" "In4.Cu" "In5.Cu" "In6.Cu"
			"In7.Cu" "In8.Cu" "In9.Cu" "In10.Cu" "In11.Cu" "In12.Cu" "In13.Cu" "In14.Cu"
			"In15.Cu" "In16.Cu"
		)
		(hatch none 0.5)
		(connect_pads
			(clearance 0)
		)
		(min_thickness 0.25)
		(keepout
			(tracks not_allowed)
			(vias allowed)
			(pads allowed)
			(copperpour not_allowed)
			(footprints allowed)
		)
		(placement
			(enabled no)
			(sheetname "")
		)
		(fill
			(thermal_gap 0.5)
			(thermal_bridge_width 0.5)
			(island_removal_mode 0)
		)
		(polygon
			(pts
				(arc
					(start 100.691696 -224.389442)
					(mid 100.033836 -224.389442)
					(end 100.691696 -224.389442)
				)
			)
		)
	)
	(zone
		(layers "F.Cu" "B.Cu" "In1.Cu" "In2.Cu" "In3.Cu" "In4.Cu" "In5.Cu" "In6.Cu"
			"In7.Cu" "In8.Cu" "In9.Cu" "In10.Cu" "In11.Cu" "In12.Cu" "In13.Cu" "In14.Cu"
			"In15.Cu" "In16.Cu"
		)
		(hatch none 0.5)
		(connect_pads
			(clearance 0)
		)
		(min_thickness 0.25)
		(keepout
			(tracks not_allowed)
			(vias allowed)
			(pads allowed)
			(copperpour not_allowed)
			(footprints allowed)
		)
		(placement
			(enabled no)
			(sheetname "")
		)
		(fill
			(thermal_gap 0.5)
			(thermal_bridge_width 0.5)
			(island_removal_mode 0)
		)
		(polygon
			(pts
				(arc
					(start 91.685364 -289.807142)
					(mid 92.343224 -289.807142)
					(end 91.685364 -289.807142)
				)
			)
		)
	)
	(zone
		(layers "F.Cu" "B.Cu" "In1.Cu" "In2.Cu" "In3.Cu" "In4.Cu" "In5.Cu" "In6.Cu"
			"In7.Cu" "In8.Cu" "In9.Cu" "In10.Cu" "In11.Cu" "In12.Cu" "In13.Cu" "In14.Cu"
			"In15.Cu" "In16.Cu"
		)
		(hatch none 0.5)
		(connect_pads
			(clearance 0)
		)
		(min_thickness 0.25)
		(keepout
			(tracks not_allowed)
			(vias allowed)
			(pads allowed)
			(copperpour not_allowed)
			(footprints allowed)
		)
		(placement
			(enabled no)
			(sheetname "")
		)
		(fill
			(thermal_gap 0.5)
			(thermal_bridge_width 0.5)
			(island_removal_mode 0)
		)
		(polygon
			(pts
				(arc
					(start 60.232798 -400.477228)
					(mid 59.851798 -400.858228)
					(end 60.232798 -401.239228)
				)
				(arc
					(start 61.096398 -401.239228)
					(mid 61.477398 -400.858228)
					(end 61.096398 -400.477228)
				)
			)
		)
	)
	(zone
		(layers "F.Cu" "B.Cu" "In1.Cu" "In2.Cu" "In3.Cu" "In4.Cu" "In5.Cu" "In6.Cu"
			"In7.Cu" "In8.Cu" "In9.Cu" "In10.Cu" "In11.Cu" "In12.Cu" "In13.Cu" "In14.Cu"
			"In15.Cu" "In16.Cu"
		)
		(hatch none 0.5)
		(connect_pads
			(clearance 0)
		)
		(min_thickness 0.25)
		(keepout
			(tracks not_allowed)
			(vias allowed)
			(pads allowed)
			(copperpour not_allowed)
			(footprints allowed)
		)
		(placement
			(enabled no)
			(sheetname "")
		)
		(fill
			(thermal_gap 0.5)
			(thermal_bridge_width 0.5)
			(island_removal_mode 0)
		)
		(polygon
			(pts
				(arc
					(start 99.592892 -214.720932)
					(mid 99.612576 -214.673522)
					(end 99.619308 -214.622634)
				)
				(arc
					(start 99.619308 -214.622634)
					(mid 99.561652 -214.48344)
					(end 99.422458 -214.425784)
				)
				(arc
					(start 99.422458 -214.425784)
					(mid 99.324027 -214.4522)
					(end 99.252024 -214.524336)
				)
				(arc
					(start 98.782378 -215.338406)
					(mid 98.762694 -215.385816)
					(end 98.755962 -215.436704)
				)
				(arc
					(start 98.755962 -215.436704)
					(mid 98.813618 -215.575898)
					(end 98.952812 -215.633554)
				)
				(arc
					(start 98.952812 -215.633554)
					(mid 99.051243 -215.607138)
					(end 99.123246 -215.535002)
				)
			)
		)
	)
	(zone
		(layers "F.Cu" "B.Cu" "In1.Cu" "In2.Cu" "In3.Cu" "In4.Cu" "In5.Cu" "In6.Cu"
			"In7.Cu" "In8.Cu" "In9.Cu" "In10.Cu" "In11.Cu" "In12.Cu" "In13.Cu" "In14.Cu"
			"In15.Cu" "In16.Cu"
		)
		(hatch none 0.5)
		(connect_pads
			(clearance 0)
		)
		(min_thickness 0.25)
		(keepout
			(tracks not_allowed)
			(vias allowed)
			(pads allowed)
			(copperpour not_allowed)
			(footprints allowed)
		)
		(placement
			(enabled no)
			(sheetname "")
		)
		(fill
			(thermal_gap 0.5)
			(thermal_bridge_width 0.5)
			(island_removal_mode 0)
		)
		(polygon
			(pts
				(arc
					(start 292.95598 -161.719768)
					(mid 292.57498 -162.100768)
					(end 292.95598 -162.481768)
				)
				(arc
					(start 293.81958 -162.481768)
					(mid 294.20058 -162.100768)
					(end 293.81958 -161.719768)
				)
			)
		)
	)
	(zone
		(layers "F.Cu" "B.Cu" "In1.Cu" "In2.Cu" "In3.Cu" "In4.Cu" "In5.Cu" "In6.Cu"
			"In7.Cu" "In8.Cu" "In9.Cu" "In10.Cu" "In11.Cu" "In12.Cu" "In13.Cu" "In14.Cu"
			"In15.Cu" "In16.Cu"
		)
		(hatch none 0.5)
		(connect_pads
			(clearance 0)
		)
		(min_thickness 0.25)
		(keepout
			(tracks not_allowed)
			(vias allowed)
			(pads allowed)
			(copperpour not_allowed)
			(footprints allowed)
		)
		(placement
			(enabled no)
			(sheetname "")
		)
		(fill
			(thermal_gap 0.5)
			(thermal_bridge_width 0.5)
			(island_removal_mode 0)
		)
		(polygon
			(pts
				(arc
					(start 111.499142 -223.575626)
					(mid 110.841282 -223.575626)
					(end 111.499142 -223.575626)
				)
			)
		)
	)
	(zone
		(layers "F.Cu" "B.Cu" "In1.Cu" "In2.Cu" "In3.Cu" "In4.Cu" "In5.Cu" "In6.Cu"
			"In7.Cu" "In8.Cu" "In9.Cu" "In10.Cu" "In11.Cu" "In12.Cu" "In13.Cu" "In14.Cu"
			"In15.Cu" "In16.Cu"
		)
		(hatch none 0.5)
		(connect_pads
			(clearance 0)
		)
		(min_thickness 0.25)
		(keepout
			(tracks not_allowed)
			(vias allowed)
			(pads allowed)
			(copperpour not_allowed)
			(footprints allowed)
		)
		(placement
			(enabled no)
			(sheetname "")
		)
		(fill
			(thermal_gap 0.5)
			(thermal_bridge_width 0.5)
			(island_removal_mode 0)
		)
		(polygon
			(pts
				(arc
					(start 147.724114 -403.502876)
					(mid 147.343114 -403.883876)
					(end 147.724114 -404.264876)
				)
				(arc
					(start 148.587714 -404.264876)
					(mid 148.968714 -403.883876)
					(end 148.587714 -403.502876)
				)
			)
		)
	)
	(zone
		(layers "F.Cu" "B.Cu" "In1.Cu" "In2.Cu" "In3.Cu" "In4.Cu" "In5.Cu" "In6.Cu"
			"In7.Cu" "In8.Cu" "In9.Cu" "In10.Cu" "In11.Cu" "In12.Cu" "In13.Cu" "In14.Cu"
			"In15.Cu" "In16.Cu"
		)
		(hatch none 0.5)
		(connect_pads
			(clearance 0)
		)
		(min_thickness 0.25)
		(keepout
			(tracks not_allowed)
			(vias allowed)
			(pads allowed)
			(copperpour not_allowed)
			(footprints allowed)
		)
		(placement
			(enabled no)
			(sheetname "")
		)
		(fill
			(thermal_gap 0.5)
			(thermal_bridge_width 0.5)
			(island_removal_mode 0)
		)
		(polygon
			(pts
				(arc
					(start 108.021882 -215.436704)
					(mid 108.679742 -215.436704)
					(end 108.021882 -215.436704)
				)
			)
		)
	)
	(zone
		(layers "F.Cu" "B.Cu" "In1.Cu" "In2.Cu" "In3.Cu" "In4.Cu" "In5.Cu" "In6.Cu"
			"In7.Cu" "In8.Cu" "In9.Cu" "In10.Cu" "In11.Cu" "In12.Cu" "In13.Cu" "In14.Cu"
			"In15.Cu" "In16.Cu"
		)
		(hatch none 0.5)
		(connect_pads
			(clearance 0)
		)
		(min_thickness 0.25)
		(keepout
			(tracks not_allowed)
			(vias allowed)
			(pads allowed)
			(copperpour not_allowed)
			(footprints allowed)
		)
		(placement
			(enabled no)
			(sheetname "")
		)
		(fill
			(thermal_gap 0.5)
			(thermal_bridge_width 0.5)
			(island_removal_mode 0)
		)
		(polygon
			(pts
				(arc
					(start 55.452518 -406.62352)
					(mid 55.071518 -407.00452)
					(end 55.452518 -407.38552)
				)
				(arc
					(start 56.316118 -407.38552)
					(mid 56.697118 -407.00452)
					(end 56.316118 -406.62352)
				)
			)
		)
	)
	(zone
		(layers "F.Cu" "B.Cu" "In1.Cu" "In2.Cu" "In3.Cu" "In4.Cu" "In5.Cu" "In6.Cu"
			"In7.Cu" "In8.Cu" "In9.Cu" "In10.Cu" "In11.Cu" "In12.Cu" "In13.Cu" "In14.Cu"
			"In15.Cu" "In16.Cu"
		)
		(hatch none 0.5)
		(connect_pads
			(clearance 0)
		)
		(min_thickness 0.25)
		(keepout
			(tracks not_allowed)
			(vias allowed)
			(pads allowed)
			(copperpour not_allowed)
			(footprints allowed)
		)
		(placement
			(enabled no)
			(sheetname "")
		)
		(fill
			(thermal_gap 0.5)
			(thermal_bridge_width 0.5)
			(island_removal_mode 0)
		)
		(polygon
			(pts
				(arc
					(start 363.19841 -217.064336)
					(mid 362.54055 -217.064336)
					(end 363.19841 -217.064336)
				)
			)
		)
	)
	(zone
		(layers "F.Cu" "B.Cu" "In1.Cu" "In2.Cu" "In3.Cu" "In4.Cu" "In5.Cu" "In6.Cu"
			"In7.Cu" "In8.Cu" "In9.Cu" "In10.Cu" "In11.Cu" "In12.Cu" "In13.Cu" "In14.Cu"
			"In15.Cu" "In16.Cu"
		)
		(hatch none 0.5)
		(connect_pads
			(clearance 0)
		)
		(min_thickness 0.25)
		(keepout
			(tracks not_allowed)
			(vias allowed)
			(pads allowed)
			(copperpour not_allowed)
			(footprints allowed)
		)
		(placement
			(enabled no)
			(sheetname "")
		)
		(fill
			(thermal_gap 0.5)
			(thermal_bridge_width 0.5)
			(island_removal_mode 0)
		)
		(polygon
			(pts
				(arc
					(start 138.534394 -403.502876)
					(mid 138.153394 -403.883876)
					(end 138.534394 -404.264876)
				)
				(arc
					(start 139.397994 -404.264876)
					(mid 139.778994 -403.883876)
					(end 139.397994 -403.502876)
				)
			)
		)
	)
	(zone
		(layers "F.Cu" "B.Cu" "In1.Cu" "In2.Cu" "In3.Cu" "In4.Cu" "In5.Cu" "In6.Cu"
			"In7.Cu" "In8.Cu" "In9.Cu" "In10.Cu" "In11.Cu" "In12.Cu" "In13.Cu" "In14.Cu"
			"In15.Cu" "In16.Cu"
		)
		(hatch none 0.5)
		(connect_pads
			(clearance 0)
		)
		(min_thickness 0.25)
		(keepout
			(tracks not_allowed)
			(vias allowed)
			(pads allowed)
			(copperpour not_allowed)
			(footprints allowed)
		)
		(placement
			(enabled no)
			(sheetname "")
		)
		(fill
			(thermal_gap 0.5)
			(thermal_bridge_width 0.5)
			(island_removal_mode 0)
		)
		(polygon
			(pts
				(arc
					(start 87.456264 -282.405836)
					(mid 88.114124 -282.405836)
					(end 87.456264 -282.405836)
				)
			)
		)
	)
	(zone
		(layers "F.Cu" "B.Cu" "In1.Cu" "In2.Cu" "In3.Cu" "In4.Cu" "In5.Cu" "In6.Cu"
			"In7.Cu" "In8.Cu" "In9.Cu" "In10.Cu" "In11.Cu" "In12.Cu" "In13.Cu" "In14.Cu"
			"In15.Cu" "In16.Cu"
		)
		(hatch none 0.5)
		(connect_pads
			(clearance 0)
		)
		(min_thickness 0.25)
		(keepout
			(tracks not_allowed)
			(vias allowed)
			(pads allowed)
			(copperpour not_allowed)
			(footprints allowed)
		)
		(placement
			(enabled no)
			(sheetname "")
		)
		(fill
			(thermal_gap 0.5)
			(thermal_bridge_width 0.5)
			(island_removal_mode 0)
		)
		(polygon
			(pts
				(arc
					(start 114.788696 -217.878406)
					(mid 114.130836 -217.878406)
					(end 114.788696 -217.878406)
				)
			)
		)
	)
	(zone
		(layers "F.Cu" "B.Cu" "In1.Cu" "In2.Cu" "In3.Cu" "In4.Cu" "In5.Cu" "In6.Cu"
			"In7.Cu" "In8.Cu" "In9.Cu" "In10.Cu" "In11.Cu" "In12.Cu" "In13.Cu" "In14.Cu"
			"In15.Cu" "In16.Cu"
		)
		(hatch none 0.5)
		(connect_pads
			(clearance 0)
		)
		(min_thickness 0.25)
		(keepout
			(tracks not_allowed)
			(vias allowed)
			(pads allowed)
			(copperpour not_allowed)
			(footprints allowed)
		)
		(placement
			(enabled no)
			(sheetname "")
		)
		(fill
			(thermal_gap 0.5)
			(thermal_bridge_width 0.5)
			(island_removal_mode 0)
		)
		(polygon
			(pts
				(arc
					(start 338.374482 -285.563056)
					(mid 338.354798 -285.610466)
					(end 338.348066 -285.661354)
				)
				(arc
					(start 338.348066 -285.661354)
					(mid 338.405722 -285.800548)
					(end 338.544916 -285.858204)
				)
				(arc
					(start 338.544916 -285.858204)
					(mid 338.643347 -285.831788)
					(end 338.71535 -285.759652)
				)
				(arc
					(start 339.18525 -284.945582)
					(mid 339.204934 -284.898172)
					(end 339.211666 -284.847284)
				)
				(arc
					(start 339.211666 -284.847284)
					(mid 339.15401 -284.70809)
					(end 339.014816 -284.650434)
				)
				(arc
					(start 339.014816 -284.650434)
					(mid 338.916385 -284.67685)
					(end 338.844382 -284.748986)
				)
			)
		)
	)
	(zone
		(layers "F.Cu" "B.Cu" "In1.Cu" "In2.Cu" "In3.Cu" "In4.Cu" "In5.Cu" "In6.Cu"
			"In7.Cu" "In8.Cu" "In9.Cu" "In10.Cu" "In11.Cu" "In12.Cu" "In13.Cu" "In14.Cu"
			"In15.Cu" "In16.Cu"
		)
		(hatch none 0.5)
		(connect_pads
			(clearance 0)
		)
		(min_thickness 0.25)
		(keepout
			(tracks not_allowed)
			(vias allowed)
			(pads allowed)
			(copperpour not_allowed)
			(footprints allowed)
		)
		(placement
			(enabled no)
			(sheetname "")
		)
		(fill
			(thermal_gap 0.5)
			(thermal_bridge_width 0.5)
			(island_removal_mode 0)
		)
		(polygon
			(pts
				(arc
					(start 340.954868 -221.035626)
					(mid 340.882879 -220.963467)
					(end 340.784434 -220.937074)
				)
				(arc
					(start 340.784434 -220.937074)
					(mid 340.64524 -220.99473)
					(end 340.587584 -221.133924)
				)
				(arc
					(start 340.587584 -221.133924)
					(mid 340.594341 -221.184805)
					(end 340.614 -221.232222)
				)
				(arc
					(start 341.083646 -222.046038)
					(mid 341.155635 -222.118197)
					(end 341.25408 -222.14459)
				)
				(arc
					(start 341.25408 -222.14459)
					(mid 341.393274 -222.086934)
					(end 341.45093 -221.94774)
				)
				(arc
					(start 341.45093 -221.94774)
					(mid 341.444173 -221.896859)
					(end 341.424514 -221.849442)
				)
			)
		)
	)
	(zone
		(layers "F.Cu" "B.Cu" "In1.Cu" "In2.Cu" "In3.Cu" "In4.Cu" "In5.Cu" "In6.Cu"
			"In7.Cu" "In8.Cu" "In9.Cu" "In10.Cu" "In11.Cu" "In12.Cu" "In13.Cu" "In14.Cu"
			"In15.Cu" "In16.Cu"
		)
		(hatch none 0.5)
		(connect_pads
			(clearance 0)
		)
		(min_thickness 0.25)
		(keepout
			(tracks not_allowed)
			(vias allowed)
			(pads allowed)
			(copperpour not_allowed)
			(footprints allowed)
		)
		(placement
			(enabled no)
			(sheetname "")
		)
		(fill
			(thermal_gap 0.5)
			(thermal_bridge_width 0.5)
			(island_removal_mode 0)
		)
		(polygon
			(pts
				(arc
					(start 379.754892 -289.807142)
					(mid 379.097032 -289.807142)
					(end 379.754892 -289.807142)
				)
			)
		)
	)
	(zone
		(layers "F.Cu" "B.Cu" "In1.Cu" "In2.Cu" "In3.Cu" "In4.Cu" "In5.Cu" "In6.Cu"
			"In7.Cu" "In8.Cu" "In9.Cu" "In10.Cu" "In11.Cu" "In12.Cu" "In13.Cu" "In14.Cu"
			"In15.Cu" "In16.Cu"
		)
		(hatch none 0.5)
		(connect_pads
			(clearance 0)
		)
		(min_thickness 0.25)
		(keepout
			(tracks not_allowed)
			(vias allowed)
			(pads allowed)
			(copperpour not_allowed)
			(footprints allowed)
		)
		(placement
			(enabled no)
			(sheetname "")
		)
		(fill
			(thermal_gap 0.5)
			(thermal_bridge_width 0.5)
			(island_removal_mode 0)
		)
		(polygon
			(pts
				(arc
					(start 363.668564 -221.133924)
					(mid 363.010704 -221.133924)
					(end 363.668564 -221.133924)
				)
			)
		)
	)
	(zone
		(layers "F.Cu" "B.Cu" "In1.Cu" "In2.Cu" "In3.Cu" "In4.Cu" "In5.Cu" "In6.Cu"
			"In7.Cu" "In8.Cu" "In9.Cu" "In10.Cu" "In11.Cu" "In12.Cu" "In13.Cu" "In14.Cu"
			"In15.Cu" "In16.Cu"
		)
		(hatch none 0.5)
		(connect_pads
			(clearance 0)
		)
		(min_thickness 0.25)
		(keepout
			(tracks not_allowed)
			(vias allowed)
			(pads allowed)
			(copperpour not_allowed)
			(footprints allowed)
		)
		(placement
			(enabled no)
			(sheetname "")
		)
		(fill
			(thermal_gap 0.5)
			(thermal_bridge_width 0.5)
			(island_removal_mode 0)
		)
		(polygon
			(pts
				(arc
					(start 342.52281 -223.575626)
					(mid 341.86495 -223.575626)
					(end 342.52281 -223.575626)
				)
			)
		)
	)
	(zone
		(layers "F.Cu" "B.Cu" "In1.Cu" "In2.Cu" "In3.Cu" "In4.Cu" "In5.Cu" "In6.Cu"
			"In7.Cu" "In8.Cu" "In9.Cu" "In10.Cu" "In11.Cu" "In12.Cu" "In13.Cu" "In14.Cu"
			"In15.Cu" "In16.Cu"
		)
		(hatch none 0.5)
		(connect_pads
			(clearance 0)
		)
		(min_thickness 0.25)
		(keepout
			(tracks not_allowed)
			(vias allowed)
			(pads allowed)
			(copperpour not_allowed)
			(footprints allowed)
		)
		(placement
			(enabled no)
			(sheetname "")
		)
		(fill
			(thermal_gap 0.5)
			(thermal_bridge_width 0.5)
			(island_removal_mode 0)
		)
		(polygon
			(pts
				(arc
					(start 341.193882 -282.307538)
					(mid 341.174198 -282.354948)
					(end 341.167466 -282.405836)
				)
				(arc
					(start 341.167466 -282.405836)
					(mid 341.225122 -282.54503)
					(end 341.364316 -282.602686)
				)
				(arc
					(start 341.364316 -282.602686)
					(mid 341.462747 -282.57627)
					(end 341.53475 -282.504134)
				)
				(arc
					(start 342.00465 -281.690064)
					(mid 342.024334 -281.642654)
					(end 342.031066 -281.591766)
				)
				(arc
					(start 342.031066 -281.591766)
					(mid 341.97341 -281.452572)
					(end 341.834216 -281.394916)
				)
				(arc
					(start 341.834216 -281.394916)
					(mid 341.735785 -281.421332)
					(end 341.663782 -281.493468)
				)
			)
		)
	)
	(zone
		(layers "F.Cu" "B.Cu" "In1.Cu" "In2.Cu" "In3.Cu" "In4.Cu" "In5.Cu" "In6.Cu"
			"In7.Cu" "In8.Cu" "In9.Cu" "In10.Cu" "In11.Cu" "In12.Cu" "In13.Cu" "In14.Cu"
			"In15.Cu" "In16.Cu"
		)
		(hatch none 0.5)
		(connect_pads
			(clearance 0)
		)
		(min_thickness 0.25)
		(keepout
			(tracks not_allowed)
			(vias allowed)
			(pads allowed)
			(copperpour not_allowed)
			(footprints allowed)
		)
		(placement
			(enabled no)
			(sheetname "")
		)
		(fill
			(thermal_gap 0.5)
			(thermal_bridge_width 0.5)
			(island_removal_mode 0)
		)
		(polygon
			(pts
				(arc
					(start 343.102946 -288.103056)
					(mid 342.445086 -288.103056)
					(end 343.102946 -288.103056)
				)
			)
		)
	)
	(zone
		(layers "F.Cu" "B.Cu" "In1.Cu" "In2.Cu" "In3.Cu" "In4.Cu" "In5.Cu" "In6.Cu"
			"In7.Cu" "In8.Cu" "In9.Cu" "In10.Cu" "In11.Cu" "In12.Cu" "In13.Cu" "In14.Cu"
			"In15.Cu" "In16.Cu"
		)
		(hatch none 0.5)
		(connect_pads
			(clearance 0)
		)
		(min_thickness 0.25)
		(keepout
			(tracks not_allowed)
			(vias allowed)
			(pads allowed)
			(copperpour not_allowed)
			(footprints allowed)
		)
		(placement
			(enabled no)
			(sheetname "")
		)
		(fill
			(thermal_gap 0.5)
			(thermal_bridge_width 0.5)
			(island_removal_mode 0)
		)
		(polygon
			(pts
				(arc
					(start 358.810814 -221.231968)
					(mid 358.830498 -221.184558)
					(end 358.83723 -221.13367)
				)
				(arc
					(start 358.83723 -221.13367)
					(mid 358.779574 -220.994476)
					(end 358.64038 -220.93682)
				)
				(arc
					(start 358.64038 -220.93682)
					(mid 358.541949 -220.963236)
					(end 358.469946 -221.035372)
				)
				(arc
					(start 358.0003 -221.849442)
					(mid 357.980616 -221.896852)
					(end 357.973884 -221.94774)
				)
				(arc
					(start 357.973884 -221.94774)
					(mid 358.03154 -222.086934)
					(end 358.170734 -222.14459)
				)
				(arc
					(start 358.170734 -222.14459)
					(mid 358.269165 -222.118174)
					(end 358.341168 -222.046038)
				)
			)
		)
	)
	(zone
		(layers "F.Cu" "B.Cu" "In1.Cu" "In2.Cu" "In3.Cu" "In4.Cu" "In5.Cu" "In6.Cu"
			"In7.Cu" "In8.Cu" "In9.Cu" "In10.Cu" "In11.Cu" "In12.Cu" "In13.Cu" "In14.Cu"
			"In15.Cu" "In16.Cu"
		)
		(hatch none 0.5)
		(connect_pads
			(clearance 0)
		)
		(min_thickness 0.25)
		(keepout
			(tracks not_allowed)
			(vias allowed)
			(pads allowed)
			(copperpour not_allowed)
			(footprints allowed)
		)
		(placement
			(enabled no)
			(sheetname "")
		)
		(fill
			(thermal_gap 0.5)
			(thermal_bridge_width 0.5)
			(island_removal_mode 0)
		)
		(polygon
			(pts
				(arc
					(start 355.680264 -213.732618)
					(mid 355.022404 -213.732618)
					(end 355.680264 -213.732618)
				)
			)
		)
	)
	(zone
		(layers "F.Cu" "B.Cu" "In1.Cu" "In2.Cu" "In3.Cu" "In4.Cu" "In5.Cu" "In6.Cu"
			"In7.Cu" "In8.Cu" "In9.Cu" "In10.Cu" "In11.Cu" "In12.Cu" "In13.Cu" "In14.Cu"
			"In15.Cu" "In16.Cu"
		)
		(hatch none 0.5)
		(connect_pads
			(clearance 0)
		)
		(min_thickness 0.25)
		(keepout
			(tracks not_allowed)
			(vias allowed)
			(pads allowed)
			(copperpour not_allowed)
			(footprints allowed)
		)
		(placement
			(enabled no)
			(sheetname "")
		)
		(fill
			(thermal_gap 0.5)
			(thermal_bridge_width 0.5)
			(island_removal_mode 0)
		)
		(polygon
			(pts
				(arc
					(start 115.258596 -223.575626)
					(mid 114.600736 -223.575626)
					(end 115.258596 -223.575626)
				)
			)
		)
	)
	(zone
		(layers "F.Cu" "B.Cu" "In1.Cu" "In2.Cu" "In3.Cu" "In4.Cu" "In5.Cu" "In6.Cu"
			"In7.Cu" "In8.Cu" "In9.Cu" "In10.Cu" "In11.Cu" "In12.Cu" "In13.Cu" "In14.Cu"
			"In15.Cu" "In16.Cu"
		)
		(hatch none 0.5)
		(connect_pads
			(clearance 0)
		)
		(min_thickness 0.25)
		(keepout
			(tracks not_allowed)
			(vias allowed)
			(pads allowed)
			(copperpour not_allowed)
			(footprints allowed)
		)
		(placement
			(enabled no)
			(sheetname "")
		)
		(fill
			(thermal_gap 0.5)
			(thermal_bridge_width 0.5)
			(island_removal_mode 0)
		)
		(polygon
			(pts
				(arc
					(start 342.053164 -217.878406)
					(mid 341.395304 -217.878406)
					(end 342.053164 -217.878406)
				)
			)
		)
	)
	(zone
		(layers "F.Cu" "B.Cu" "In1.Cu" "In2.Cu" "In3.Cu" "In4.Cu" "In5.Cu" "In6.Cu"
			"In7.Cu" "In8.Cu" "In9.Cu" "In10.Cu" "In11.Cu" "In12.Cu" "In13.Cu" "In14.Cu"
			"In15.Cu" "In16.Cu"
		)
		(hatch none 0.5)
		(connect_pads
			(clearance 0)
		)
		(min_thickness 0.25)
		(keepout
			(tracks not_allowed)
			(vias allowed)
			(pads allowed)
			(copperpour not_allowed)
			(footprints allowed)
		)
		(placement
			(enabled no)
			(sheetname "")
		)
		(fill
			(thermal_gap 0.5)
			(thermal_bridge_width 0.5)
			(island_removal_mode 0)
		)
		(polygon
			(pts
				(arc
					(start 129.825496 -224.389442)
					(mid 129.167636 -224.389442)
					(end 129.825496 -224.389442)
				)
			)
		)
	)
	(zone
		(layers "F.Cu" "B.Cu" "In1.Cu" "In2.Cu" "In3.Cu" "In4.Cu" "In5.Cu" "In6.Cu"
			"In7.Cu" "In8.Cu" "In9.Cu" "In10.Cu" "In11.Cu" "In12.Cu" "In13.Cu" "In14.Cu"
			"In15.Cu" "In16.Cu"
		)
		(hatch none 0.5)
		(connect_pads
			(clearance 0)
		)
		(min_thickness 0.25)
		(keepout
			(tracks not_allowed)
			(vias allowed)
			(pads allowed)
			(copperpour not_allowed)
			(footprints allowed)
		)
		(placement
			(enabled no)
			(sheetname "")
		)
		(fill
			(thermal_gap 0.5)
			(thermal_bridge_width 0.5)
			(island_removal_mode 0)
		)
		(polygon
			(pts
				(arc
					(start 99.832414 -288.818828)
					(mid 99.81273 -288.866238)
					(end 99.805998 -288.917126)
				)
				(arc
					(start 99.805998 -288.917126)
					(mid 99.863654 -289.05632)
					(end 100.002848 -289.113976)
				)
				(arc
					(start 100.002848 -289.113976)
					(mid 100.101279 -289.08756)
					(end 100.173282 -289.015424)
				)
				(arc
					(start 100.643182 -288.201354)
					(mid 100.662866 -288.153944)
					(end 100.669598 -288.103056)
				)
				(arc
					(start 100.669598 -288.103056)
					(mid 100.611942 -287.963862)
					(end 100.472748 -287.906206)
				)
				(arc
					(start 100.472748 -287.906206)
					(mid 100.374317 -287.932622)
					(end 100.302314 -288.004758)
				)
			)
		)
	)
	(zone
		(layers "F.Cu" "B.Cu" "In1.Cu" "In2.Cu" "In3.Cu" "In4.Cu" "In5.Cu" "In6.Cu"
			"In7.Cu" "In8.Cu" "In9.Cu" "In10.Cu" "In11.Cu" "In12.Cu" "In13.Cu" "In14.Cu"
			"In15.Cu" "In16.Cu"
		)
		(hatch none 0.5)
		(connect_pads
			(clearance 0)
		)
		(min_thickness 0.25)
		(keepout
			(tracks not_allowed)
			(vias allowed)
			(pads allowed)
			(copperpour not_allowed)
			(footprints allowed)
		)
		(placement
			(enabled no)
			(sheetname "")
		)
		(fill
			(thermal_gap 0.5)
			(thermal_bridge_width 0.5)
			(island_removal_mode 0)
		)
		(polygon
			(pts
				(arc
					(start 118.077742 -218.692222)
					(mid 117.419882 -218.692222)
					(end 118.077742 -218.692222)
				)
			)
		)
	)
	(zone
		(layers "F.Cu" "B.Cu" "In1.Cu" "In2.Cu" "In3.Cu" "In4.Cu" "In5.Cu" "In6.Cu"
			"In7.Cu" "In8.Cu" "In9.Cu" "In10.Cu" "In11.Cu" "In12.Cu" "In13.Cu" "In14.Cu"
			"In15.Cu" "In16.Cu"
		)
		(hatch none 0.5)
		(connect_pads
			(clearance 0)
		)
		(min_thickness 0.25)
		(keepout
			(tracks not_allowed)
			(vias allowed)
			(pads allowed)
			(copperpour not_allowed)
			(footprints allowed)
		)
		(placement
			(enabled no)
			(sheetname "")
		)
		(fill
			(thermal_gap 0.5)
			(thermal_bridge_width 0.5)
			(island_removal_mode 0)
		)
		(polygon
			(pts
				(arc
					(start 97.402142 -218.692222)
					(mid 96.744282 -218.692222)
					(end 97.402142 -218.692222)
				)
			)
		)
	)
	(zone
		(layers "F.Cu" "B.Cu" "In1.Cu" "In2.Cu" "In3.Cu" "In4.Cu" "In5.Cu" "In6.Cu"
			"In7.Cu" "In8.Cu" "In9.Cu" "In10.Cu" "In11.Cu" "In12.Cu" "In13.Cu" "In14.Cu"
			"In15.Cu" "In16.Cu"
		)
		(hatch none 0.5)
		(connect_pads
			(clearance 0)
		)
		(min_thickness 0.25)
		(keepout
			(tracks not_allowed)
			(vias allowed)
			(pads allowed)
			(copperpour not_allowed)
			(footprints allowed)
		)
		(placement
			(enabled no)
			(sheetname "")
		)
		(fill
			(thermal_gap 0.5)
			(thermal_bridge_width 0.5)
			(island_removal_mode 0)
		)
		(polygon
			(pts
				(arc
					(start 344.512646 -288.917126)
					(mid 343.854786 -288.917126)
					(end 344.512646 -288.917126)
				)
			)
		)
	)
	(zone
		(layers "F.Cu" "B.Cu" "In1.Cu" "In2.Cu" "In3.Cu" "In4.Cu" "In5.Cu" "In6.Cu"
			"In7.Cu" "In8.Cu" "In9.Cu" "In10.Cu" "In11.Cu" "In12.Cu" "In13.Cu" "In14.Cu"
			"In15.Cu" "In16.Cu"
		)
		(hatch none 0.5)
		(connect_pads
			(clearance 0)
		)
		(min_thickness 0.25)
		(keepout
			(tracks not_allowed)
			(vias allowed)
			(pads allowed)
			(copperpour not_allowed)
			(footprints allowed)
		)
		(placement
			(enabled no)
			(sheetname "")
		)
		(fill
			(thermal_gap 0.5)
			(thermal_bridge_width 0.5)
			(island_removal_mode 0)
		)
		(polygon
			(pts
				(xy 468.100156 -195.144136) (xy 468.100156 -200.144126) (xy 467.795356 -199.839326) (xy 467.795356 -195.448936)
			)
		)
	)
	(zone
		(layers "F.Cu" "B.Cu" "In1.Cu" "In2.Cu" "In3.Cu" "In4.Cu" "In5.Cu" "In6.Cu"
			"In7.Cu" "In8.Cu" "In9.Cu" "In10.Cu" "In11.Cu" "In12.Cu" "In13.Cu" "In14.Cu"
			"In15.Cu" "In16.Cu"
		)
		(hatch none 0.5)
		(connect_pads
			(clearance 0)
		)
		(min_thickness 0.25)
		(keepout
			(tracks not_allowed)
			(vias allowed)
			(pads allowed)
			(copperpour not_allowed)
			(footprints allowed)
		)
		(placement
			(enabled no)
			(sheetname "")
		)
		(fill
			(thermal_gap 0.5)
			(thermal_bridge_width 0.5)
			(island_removal_mode 0)
		)
		(polygon
			(pts
				(arc
					(start 107.581446 -223.67367)
					(mid 107.60113 -223.62626)
					(end 107.607862 -223.575372)
				)
				(arc
					(start 107.607862 -223.575372)
					(mid 107.550206 -223.436178)
					(end 107.411012 -223.378522)
				)
				(arc
					(start 107.411012 -223.378522)
					(mid 107.312581 -223.404938)
					(end 107.240578 -223.477074)
				)
				(arc
					(start 106.770932 -224.291144)
					(mid 106.751248 -224.338554)
					(end 106.744516 -224.389442)
				)
				(arc
					(start 106.744516 -224.389442)
					(mid 106.802172 -224.528636)
					(end 106.941366 -224.586292)
				)
				(arc
					(start 106.941366 -224.586292)
					(mid 107.039797 -224.559876)
					(end 107.1118 -224.48774)
				)
			)
		)
	)
	(zone
		(layers "F.Cu" "B.Cu" "In1.Cu" "In2.Cu" "In3.Cu" "In4.Cu" "In5.Cu" "In6.Cu"
			"In7.Cu" "In8.Cu" "In9.Cu" "In10.Cu" "In11.Cu" "In12.Cu" "In13.Cu" "In14.Cu"
			"In15.Cu" "In16.Cu"
		)
		(hatch none 0.5)
		(connect_pads
			(clearance 0)
		)
		(min_thickness 0.25)
		(keepout
			(tracks not_allowed)
			(vias allowed)
			(pads allowed)
			(copperpour not_allowed)
			(footprints allowed)
		)
		(placement
			(enabled no)
			(sheetname "")
		)
		(fill
			(thermal_gap 0.5)
			(thermal_bridge_width 0.5)
			(island_removal_mode 0)
		)
		(polygon
			(pts
				(xy 839.52207 -391.095738) (xy 844.521806 -391.095738) (xy 844.217006 -391.400538) (xy 839.82687 -391.400538)
			)
		)
	)
	(zone
		(layers "F.Cu" "B.Cu" "In1.Cu" "In2.Cu" "In3.Cu" "In4.Cu" "In5.Cu" "In6.Cu"
			"In7.Cu" "In8.Cu" "In9.Cu" "In10.Cu" "In11.Cu" "In12.Cu" "In13.Cu" "In14.Cu"
			"In15.Cu" "In16.Cu"
		)
		(hatch none 0.5)
		(connect_pads
			(clearance 0)
		)
		(min_thickness 0.25)
		(keepout
			(tracks not_allowed)
			(vias allowed)
			(pads allowed)
			(copperpour not_allowed)
			(footprints allowed)
		)
		(placement
			(enabled no)
			(sheetname "")
		)
		(fill
			(thermal_gap 0.5)
			(thermal_bridge_width 0.5)
			(island_removal_mode 0)
		)
		(polygon
			(pts
				(arc
					(start 123.218194 -403.502876)
					(mid 122.837194 -403.883876)
					(end 123.218194 -404.264876)
				)
				(arc
					(start 124.081794 -404.264876)
					(mid 124.462794 -403.883876)
					(end 124.081794 -403.502876)
				)
			)
		)
	)
	(zone
		(layers "F.Cu" "B.Cu" "In1.Cu" "In2.Cu" "In3.Cu" "In4.Cu" "In5.Cu" "In6.Cu"
			"In7.Cu" "In8.Cu" "In9.Cu" "In10.Cu" "In11.Cu" "In12.Cu" "In13.Cu" "In14.Cu"
			"In15.Cu" "In16.Cu"
		)
		(hatch none 0.5)
		(connect_pads
			(clearance 0)
		)
		(min_thickness 0.25)
		(keepout
			(tracks not_allowed)
			(vias allowed)
			(pads allowed)
			(copperpour not_allowed)
			(footprints allowed)
		)
		(placement
			(enabled no)
			(sheetname "")
		)
		(fill
			(thermal_gap 0.5)
			(thermal_bridge_width 0.5)
			(island_removal_mode 0)
		)
		(polygon
			(pts
				(arc
					(start 340.283292 -289.807142)
					(mid 339.625432 -289.807142)
					(end 340.283292 -289.807142)
				)
			)
		)
	)
	(zone
		(layers "F.Cu" "B.Cu" "In1.Cu" "In2.Cu" "In3.Cu" "In4.Cu" "In5.Cu" "In6.Cu"
			"In7.Cu" "In8.Cu" "In9.Cu" "In10.Cu" "In11.Cu" "In12.Cu" "In13.Cu" "In14.Cu"
			"In15.Cu" "In16.Cu"
		)
		(hatch none 0.5)
		(connect_pads
			(clearance 0)
		)
		(min_thickness 0.25)
		(keepout
			(tracks not_allowed)
			(vias allowed)
			(pads allowed)
			(copperpour not_allowed)
			(footprints allowed)
		)
		(placement
			(enabled no)
			(sheetname "")
		)
		(fill
			(thermal_gap 0.5)
			(thermal_bridge_width 0.5)
			(island_removal_mode 0)
		)
		(polygon
			(pts
				(arc
					(start 99.281742 -218.692222)
					(mid 98.623882 -218.692222)
					(end 99.281742 -218.692222)
				)
			)
		)
	)
	(zone
		(layers "F.Cu" "B.Cu" "In1.Cu" "In2.Cu" "In3.Cu" "In4.Cu" "In5.Cu" "In6.Cu"
			"In7.Cu" "In8.Cu" "In9.Cu" "In10.Cu" "In11.Cu" "In12.Cu" "In13.Cu" "In14.Cu"
			"In15.Cu" "In16.Cu"
		)
		(hatch none 0.5)
		(connect_pads
			(clearance 0)
		)
		(min_thickness 0.25)
		(keepout
			(tracks not_allowed)
			(vias allowed)
			(pads allowed)
			(copperpour not_allowed)
			(footprints allowed)
		)
		(placement
			(enabled no)
			(sheetname "")
		)
		(fill
			(thermal_gap 0.5)
			(thermal_bridge_width 0.5)
			(island_removal_mode 0)
		)
		(polygon
			(pts
				(arc
					(start 95.162878 -288.103056)
					(mid 94.505018 -288.103056)
					(end 95.162878 -288.103056)
				)
			)
		)
	)
	(zone
		(layers "F.Cu" "B.Cu" "In1.Cu" "In2.Cu" "In3.Cu" "In4.Cu" "In5.Cu" "In6.Cu"
			"In7.Cu" "In8.Cu" "In9.Cu" "In10.Cu" "In11.Cu" "In12.Cu" "In13.Cu" "In14.Cu"
			"In15.Cu" "In16.Cu"
		)
		(hatch none 0.5)
		(connect_pads
			(clearance 0)
		)
		(min_thickness 0.25)
		(keepout
			(tracks not_allowed)
			(vias allowed)
			(pads allowed)
			(copperpour not_allowed)
			(footprints allowed)
		)
		(placement
			(enabled no)
			(sheetname "")
		)
		(fill
			(thermal_gap 0.5)
			(thermal_bridge_width 0.5)
			(island_removal_mode 0)
		)
		(polygon
			(pts
				(arc
					(start 339.813646 -285.661354)
					(mid 339.155786 -285.661354)
					(end 339.813646 -285.661354)
				)
			)
		)
	)
	(zone
		(layers "F.Cu" "B.Cu" "In1.Cu" "In2.Cu" "In3.Cu" "In4.Cu" "In5.Cu" "In6.Cu"
			"In7.Cu" "In8.Cu" "In9.Cu" "In10.Cu" "In11.Cu" "In12.Cu" "In13.Cu" "In14.Cu"
			"In15.Cu" "In16.Cu"
		)
		(hatch none 0.5)
		(connect_pads
			(clearance 0)
		)
		(min_thickness 0.25)
		(keepout
			(tracks not_allowed)
			(vias allowed)
			(pads allowed)
			(copperpour not_allowed)
			(footprints allowed)
		)
		(placement
			(enabled no)
			(sheetname "")
		)
		(fill
			(thermal_gap 0.5)
			(thermal_bridge_width 0.5)
			(island_removal_mode 0)
		)
		(polygon
			(pts
				(arc
					(start 83.021678 -409.649168)
					(mid 82.640678 -410.030168)
					(end 83.021678 -410.411168)
				)
				(arc
					(start 83.885278 -410.411168)
					(mid 84.266278 -410.030168)
					(end 83.885278 -409.649168)
				)
			)
		)
	)
	(zone
		(layers "F.Cu" "B.Cu" "In1.Cu" "In2.Cu" "In3.Cu" "In4.Cu" "In5.Cu" "In6.Cu"
			"In7.Cu" "In8.Cu" "In9.Cu" "In10.Cu" "In11.Cu" "In12.Cu" "In13.Cu" "In14.Cu"
			"In15.Cu" "In16.Cu"
		)
		(hatch none 0.5)
		(connect_pads
			(clearance 0)
		)
		(min_thickness 0.25)
		(keepout
			(tracks not_allowed)
			(vias allowed)
			(pads allowed)
			(copperpour not_allowed)
			(footprints allowed)
		)
		(placement
			(enabled no)
			(sheetname "")
		)
		(fill
			(thermal_gap 0.5)
			(thermal_bridge_width 0.5)
			(island_removal_mode 0)
		)
		(polygon
			(pts
				(arc
					(start 370.66093 -289.003232)
					(mid 370.676854 -288.961481)
					(end 370.682266 -288.917126)
				)
				(arc
					(start 370.682266 -288.917126)
					(mid 370.62833 -288.786912)
					(end 370.498116 -288.732976)
				)
				(arc
					(start 370.498116 -288.732976)
					(mid 370.403096 -288.759384)
					(end 370.335302 -288.83102)
				)
				(arc
					(start 369.865148 -289.721036)
					(mid 369.849224 -289.762787)
					(end 369.843812 -289.807142)
				)
				(arc
					(start 369.843812 -289.807142)
					(mid 369.897748 -289.937356)
					(end 370.027962 -289.991292)
				)
				(arc
					(start 370.027962 -289.991292)
					(mid 370.122982 -289.964884)
					(end 370.190776 -289.893248)
				)
			)
		)
	)
	(zone
		(layers "F.Cu" "B.Cu" "In1.Cu" "In2.Cu" "In3.Cu" "In4.Cu" "In5.Cu" "In6.Cu"
			"In7.Cu" "In8.Cu" "In9.Cu" "In10.Cu" "In11.Cu" "In12.Cu" "In13.Cu" "In14.Cu"
			"In15.Cu" "In16.Cu"
		)
		(hatch none 0.5)
		(connect_pads
			(clearance 0)
		)
		(min_thickness 0.25)
		(keepout
			(tracks not_allowed)
			(vias allowed)
			(pads allowed)
			(copperpour not_allowed)
			(footprints allowed)
		)
		(placement
			(enabled no)
			(sheetname "")
		)
		(fill
			(thermal_gap 0.5)
			(thermal_bridge_width 0.5)
			(island_removal_mode 0)
		)
		(polygon
			(pts
				(arc
					(start 103.761794 -282.208986)
					(mid 103.564944 -282.405836)
					(end 103.761794 -282.602686)
				)
				(arc
					(start 104.701594 -282.602686)
					(mid 104.898444 -282.405836)
					(end 104.701594 -282.208986)
				)
			)
		)
	)
	(zone
		(layers "F.Cu" "B.Cu" "In1.Cu" "In2.Cu" "In3.Cu" "In4.Cu" "In5.Cu" "In6.Cu"
			"In7.Cu" "In8.Cu" "In9.Cu" "In10.Cu" "In11.Cu" "In12.Cu" "In13.Cu" "In14.Cu"
			"In15.Cu" "In16.Cu"
		)
		(hatch none 0.5)
		(connect_pads
			(clearance 0)
		)
		(min_thickness 0.25)
		(keepout
			(tracks not_allowed)
			(vias allowed)
			(pads allowed)
			(copperpour not_allowed)
			(footprints allowed)
		)
		(placement
			(enabled no)
			(sheetname "")
		)
		(fill
			(thermal_gap 0.5)
			(thermal_bridge_width 0.5)
			(island_removal_mode 0)
		)
		(polygon
			(pts
				(xy 468.100156 -249.7582) (xy 468.100156 -254.75819) (xy 467.795356 -254.45339) (xy 467.795356 -250.063)
			)
		)
	)
	(zone
		(layers "F.Cu" "B.Cu" "In1.Cu" "In2.Cu" "In3.Cu" "In4.Cu" "In5.Cu" "In6.Cu"
			"In7.Cu" "In8.Cu" "In9.Cu" "In10.Cu" "In11.Cu" "In12.Cu" "In13.Cu" "In14.Cu"
			"In15.Cu" "In16.Cu"
		)
		(hatch none 0.5)
		(connect_pads
			(clearance 0)
		)
		(min_thickness 0.25)
		(keepout
			(tracks not_allowed)
			(vias allowed)
			(pads allowed)
			(copperpour not_allowed)
			(footprints allowed)
		)
		(placement
			(enabled no)
			(sheetname "")
		)
		(fill
			(thermal_gap 0.5)
			(thermal_bridge_width 0.5)
			(island_removal_mode 0)
		)
		(polygon
			(pts
				(arc
					(start 364.608364 -224.389442)
					(mid 363.950504 -224.389442)
					(end 364.608364 -224.389442)
				)
			)
		)
	)
	(zone
		(layers "F.Cu" "B.Cu" "In1.Cu" "In2.Cu" "In3.Cu" "In4.Cu" "In5.Cu" "In6.Cu"
			"In7.Cu" "In8.Cu" "In9.Cu" "In10.Cu" "In11.Cu" "In12.Cu" "In13.Cu" "In14.Cu"
			"In15.Cu" "In16.Cu"
		)
		(hatch none 0.5)
		(connect_pads
			(clearance 0)
		)
		(min_thickness 0.25)
		(keepout
			(tracks not_allowed)
			(vias allowed)
			(pads allowed)
			(copperpour not_allowed)
			(footprints allowed)
		)
		(placement
			(enabled no)
			(sheetname "")
		)
		(fill
			(thermal_gap 0.5)
			(thermal_bridge_width 0.5)
			(island_removal_mode 0)
		)
		(polygon
			(pts
				(arc
					(start 51.043078 -400.477228)
					(mid 50.662078 -400.858228)
					(end 51.043078 -401.239228)
				)
				(arc
					(start 51.906678 -401.239228)
					(mid 52.287678 -400.858228)
					(end 51.906678 -400.477228)
				)
			)
		)
	)
	(zone
		(layers "F.Cu" "B.Cu" "In1.Cu" "In2.Cu" "In3.Cu" "In4.Cu" "In5.Cu" "In6.Cu"
			"In7.Cu" "In8.Cu" "In9.Cu" "In10.Cu" "In11.Cu" "In12.Cu" "In13.Cu" "In14.Cu"
			"In15.Cu" "In16.Cu"
		)
		(hatch none 0.5)
		(connect_pads
			(clearance 0)
		)
		(min_thickness 0.25)
		(keepout
			(tracks not_allowed)
			(vias allowed)
			(pads allowed)
			(copperpour not_allowed)
			(footprints allowed)
		)
		(placement
			(enabled no)
			(sheetname "")
		)
		(fill
			(thermal_gap 0.5)
			(thermal_bridge_width 0.5)
			(island_removal_mode 0)
		)
		(polygon
			(pts
				(arc
					(start 372.59641 -223.575626)
					(mid 371.93855 -223.575626)
					(end 372.59641 -223.575626)
				)
			)
		)
	)
	(zone
		(layers "F.Cu" "B.Cu" "In1.Cu" "In2.Cu" "In3.Cu" "In4.Cu" "In5.Cu" "In6.Cu"
			"In7.Cu" "In8.Cu" "In9.Cu" "In10.Cu" "In11.Cu" "In12.Cu" "In13.Cu" "In14.Cu"
			"In15.Cu" "In16.Cu"
		)
		(hatch none 0.5)
		(connect_pads
			(clearance 0)
		)
		(min_thickness 0.25)
		(keepout
			(tracks not_allowed)
			(vias allowed)
			(pads allowed)
			(copperpour not_allowed)
			(footprints allowed)
		)
		(placement
			(enabled no)
			(sheetname "")
		)
		(fill
			(thermal_gap 0.5)
			(thermal_bridge_width 0.5)
			(island_removal_mode 0)
		)
		(polygon
			(pts
				(arc
					(start 347.332046 -288.917126)
					(mid 346.674186 -288.917126)
					(end 347.332046 -288.917126)
				)
			)
		)
	)
	(zone
		(layers "F.Cu" "B.Cu" "In1.Cu" "In2.Cu" "In3.Cu" "In4.Cu" "In5.Cu" "In6.Cu"
			"In7.Cu" "In8.Cu" "In9.Cu" "In10.Cu" "In11.Cu" "In12.Cu" "In13.Cu" "In14.Cu"
			"In15.Cu" "In16.Cu"
		)
		(hatch none 0.5)
		(connect_pads
			(clearance 0)
		)
		(min_thickness 0.25)
		(keepout
			(tracks not_allowed)
			(vias allowed)
			(pads allowed)
			(copperpour not_allowed)
			(footprints allowed)
		)
		(placement
			(enabled no)
			(sheetname "")
		)
		(fill
			(thermal_gap 0.5)
			(thermal_bridge_width 0.5)
			(island_removal_mode 0)
		)
		(polygon
			(pts
				(arc
					(start 99.225862 -288.831274)
					(mid 99.158154 -288.759423)
					(end 99.063048 -288.732976)
				)
				(arc
					(start 99.063048 -288.732976)
					(mid 98.932834 -288.786912)
					(end 98.878898 -288.917126)
				)
				(arc
					(start 98.878898 -288.917126)
					(mid 98.884349 -288.961347)
					(end 98.900234 -289.002978)
				)
				(arc
					(start 99.36988 -289.892994)
					(mid 99.437588 -289.964845)
					(end 99.532694 -289.991292)
				)
				(arc
					(start 99.532694 -289.991292)
					(mid 99.662908 -289.937356)
					(end 99.716844 -289.807142)
				)
				(arc
					(start 99.716844 -289.807142)
					(mid 99.711393 -289.762921)
					(end 99.695508 -289.72129)
				)
			)
		)
	)
	(zone
		(layers "F.Cu" "B.Cu" "In1.Cu" "In2.Cu" "In3.Cu" "In4.Cu" "In5.Cu" "In6.Cu"
			"In7.Cu" "In8.Cu" "In9.Cu" "In10.Cu" "In11.Cu" "In12.Cu" "In13.Cu" "In14.Cu"
			"In15.Cu" "In16.Cu"
		)
		(hatch none 0.5)
		(connect_pads
			(clearance 0)
		)
		(min_thickness 0.25)
		(keepout
			(tracks not_allowed)
			(vias allowed)
			(pads allowed)
			(copperpour not_allowed)
			(footprints allowed)
		)
		(placement
			(enabled no)
			(sheetname "")
		)
		(fill
			(thermal_gap 0.5)
			(thermal_bridge_width 0.5)
			(island_removal_mode 0)
		)
		(polygon
			(pts
				(arc
					(start 128.807718 -288.917126)
					(mid 129.465578 -288.917126)
					(end 128.807718 -288.917126)
				)
			)
		)
	)
	(zone
		(layers "F.Cu" "B.Cu" "In1.Cu" "In2.Cu" "In3.Cu" "In4.Cu" "In5.Cu" "In6.Cu"
			"In7.Cu" "In8.Cu" "In9.Cu" "In10.Cu" "In11.Cu" "In12.Cu" "In13.Cu" "In14.Cu"
			"In15.Cu" "In16.Cu"
		)
		(hatch none 0.5)
		(connect_pads
			(clearance 0)
		)
		(min_thickness 0.25)
		(keepout
			(tracks not_allowed)
			(vias allowed)
			(pads allowed)
			(copperpour not_allowed)
			(footprints allowed)
		)
		(placement
			(enabled no)
			(sheetname "")
		)
		(fill
			(thermal_gap 0.5)
			(thermal_bridge_width 0.5)
			(island_removal_mode 0)
		)
		(polygon
			(pts
				(arc
					(start 337.933792 -285.661354)
					(mid 337.275932 -285.661354)
					(end 337.933792 -285.661354)
				)
			)
		)
	)
	(zone
		(layers "F.Cu" "B.Cu" "In1.Cu" "In2.Cu" "In3.Cu" "In4.Cu" "In5.Cu" "In6.Cu"
			"In7.Cu" "In8.Cu" "In9.Cu" "In10.Cu" "In11.Cu" "In12.Cu" "In13.Cu" "In14.Cu"
			"In15.Cu" "In16.Cu"
		)
		(hatch none 0.5)
		(connect_pads
			(clearance 0)
		)
		(min_thickness 0.25)
		(keepout
			(tracks not_allowed)
			(vias allowed)
			(pads allowed)
			(copperpour not_allowed)
			(footprints allowed)
		)
		(placement
			(enabled no)
			(sheetname "")
		)
		(fill
			(thermal_gap 0.5)
			(thermal_bridge_width 0.5)
			(island_removal_mode 0)
		)
		(polygon
			(pts
				(arc
					(start 354.74021 -218.692222)
					(mid 354.08235 -218.692222)
					(end 354.74021 -218.692222)
				)
			)
		)
	)
	(zone
		(layers "F.Cu" "B.Cu" "In1.Cu" "In2.Cu" "In3.Cu" "In4.Cu" "In5.Cu" "In6.Cu"
			"In7.Cu" "In8.Cu" "In9.Cu" "In10.Cu" "In11.Cu" "In12.Cu" "In13.Cu" "In14.Cu"
			"In15.Cu" "In16.Cu"
		)
		(hatch none 0.5)
		(connect_pads
			(clearance 0)
		)
		(min_thickness 0.25)
		(keepout
			(tracks not_allowed)
			(vias allowed)
			(pads allowed)
			(copperpour not_allowed)
			(footprints allowed)
		)
		(placement
			(enabled no)
			(sheetname "")
		)
		(fill
			(thermal_gap 0.5)
			(thermal_bridge_width 0.5)
			(island_removal_mode 0)
		)
		(polygon
			(pts
				(arc
					(start 102.570788 -214.622634)
					(mid 101.912928 -214.622634)
					(end 102.570788 -214.622634)
				)
			)
		)
	)
	(zone
		(layers "F.Cu" "B.Cu" "In1.Cu" "In2.Cu" "In3.Cu" "In4.Cu" "In5.Cu" "In6.Cu"
			"In7.Cu" "In8.Cu" "In9.Cu" "In10.Cu" "In11.Cu" "In12.Cu" "In13.Cu" "In14.Cu"
			"In15.Cu" "In16.Cu"
		)
		(hatch none 0.5)
		(connect_pads
			(clearance 0)
		)
		(min_thickness 0.25)
		(keepout
			(tracks not_allowed)
			(vias allowed)
			(pads allowed)
			(copperpour not_allowed)
			(footprints allowed)
		)
		(placement
			(enabled no)
			(sheetname "")
		)
		(fill
			(thermal_gap 0.5)
			(thermal_bridge_width 0.5)
			(island_removal_mode 0)
		)
		(polygon
			(pts
				(arc
					(start 370.08816 -221.231968)
					(mid 370.107844 -221.184558)
					(end 370.114576 -221.13367)
				)
				(arc
					(start 370.114576 -221.13367)
					(mid 370.05692 -220.994476)
					(end 369.917726 -220.93682)
				)
				(arc
					(start 369.917726 -220.93682)
					(mid 369.819295 -220.963236)
					(end 369.747292 -221.035372)
				)
				(arc
					(start 369.277646 -221.849442)
					(mid 369.257962 -221.896852)
					(end 369.25123 -221.94774)
				)
				(arc
					(start 369.25123 -221.94774)
					(mid 369.308886 -222.086934)
					(end 369.44808 -222.14459)
				)
				(arc
					(start 369.44808 -222.14459)
					(mid 369.546511 -222.118174)
					(end 369.618514 -222.046038)
				)
			)
		)
	)
	(zone
		(layers "F.Cu" "B.Cu" "In1.Cu" "In2.Cu" "In3.Cu" "In4.Cu" "In5.Cu" "In6.Cu"
			"In7.Cu" "In8.Cu" "In9.Cu" "In10.Cu" "In11.Cu" "In12.Cu" "In13.Cu" "In14.Cu"
			"In15.Cu" "In16.Cu"
		)
		(hatch none 0.5)
		(connect_pads
			(clearance 0)
		)
		(min_thickness 0.25)
		(keepout
			(tracks not_allowed)
			(vias allowed)
			(pads allowed)
			(copperpour not_allowed)
			(footprints allowed)
		)
		(placement
			(enabled no)
			(sheetname "")
		)
		(fill
			(thermal_gap 0.5)
			(thermal_bridge_width 0.5)
			(island_removal_mode 0)
		)
		(polygon
			(pts
				(arc
					(start 132.020056 -9.862312)
					(mid 131.639056 -10.243312)
					(end 132.020056 -10.624312)
				)
				(arc
					(start 132.883656 -10.624312)
					(mid 133.264656 -10.243312)
					(end 132.883656 -9.862312)
				)
			)
		)
	)
	(zone
		(layers "F.Cu" "B.Cu" "In1.Cu" "In2.Cu" "In3.Cu" "In4.Cu" "In5.Cu" "In6.Cu"
			"In7.Cu" "In8.Cu" "In9.Cu" "In10.Cu" "In11.Cu" "In12.Cu" "In13.Cu" "In14.Cu"
			"In15.Cu" "In16.Cu"
		)
		(hatch none 0.5)
		(connect_pads
			(clearance 0)
		)
		(min_thickness 0.25)
		(keepout
			(tracks not_allowed)
			(vias allowed)
			(pads allowed)
			(copperpour not_allowed)
			(footprints allowed)
		)
		(placement
			(enabled no)
			(sheetname "")
		)
		(fill
			(thermal_gap 0.5)
			(thermal_bridge_width 0.5)
			(island_removal_mode 0)
		)
		(polygon
			(pts
				(arc
					(start 374.116092 -289.807142)
					(mid 373.458232 -289.807142)
					(end 374.116092 -289.807142)
				)
			)
		)
	)
	(zone
		(layers "F.Cu" "B.Cu" "In1.Cu" "In2.Cu" "In3.Cu" "In4.Cu" "In5.Cu" "In6.Cu"
			"In7.Cu" "In8.Cu" "In9.Cu" "In10.Cu" "In11.Cu" "In12.Cu" "In13.Cu" "In14.Cu"
			"In15.Cu" "In16.Cu"
		)
		(hatch none 0.5)
		(connect_pads
			(clearance 0)
		)
		(min_thickness 0.25)
		(keepout
			(tracks not_allowed)
			(vias allowed)
			(pads allowed)
			(copperpour not_allowed)
			(footprints allowed)
		)
		(placement
			(enabled no)
			(sheetname "")
		)
		(fill
			(thermal_gap 0.5)
			(thermal_bridge_width 0.5)
			(island_removal_mode 0)
		)
		(polygon
			(pts
				(arc
					(start 350.621346 -284.847538)
					(mid 349.963486 -284.847538)
					(end 350.621346 -284.847538)
				)
			)
		)
	)
	(zone
		(layers "F.Cu" "B.Cu" "In1.Cu" "In2.Cu" "In3.Cu" "In4.Cu" "In5.Cu" "In6.Cu"
			"In7.Cu" "In8.Cu" "In9.Cu" "In10.Cu" "In11.Cu" "In12.Cu" "In13.Cu" "In14.Cu"
			"In15.Cu" "In16.Cu"
		)
		(hatch none 0.5)
		(connect_pads
			(clearance 0)
		)
		(min_thickness 0.25)
		(keepout
			(tracks not_allowed)
			(vias allowed)
			(pads allowed)
			(copperpour not_allowed)
			(footprints allowed)
		)
		(placement
			(enabled no)
			(sheetname "")
		)
		(fill
			(thermal_gap 0.5)
			(thermal_bridge_width 0.5)
			(island_removal_mode 0)
		)
		(polygon
			(pts
				(arc
					(start 91.763342 -221.94774)
					(mid 91.105482 -221.94774)
					(end 91.763342 -221.94774)
				)
			)
		)
	)
	(zone
		(layers "F.Cu" "B.Cu" "In1.Cu" "In2.Cu" "In3.Cu" "In4.Cu" "In5.Cu" "In6.Cu"
			"In7.Cu" "In8.Cu" "In9.Cu" "In10.Cu" "In11.Cu" "In12.Cu" "In13.Cu" "In14.Cu"
			"In15.Cu" "In16.Cu"
		)
		(hatch none 0.5)
		(connect_pads
			(clearance 0)
		)
		(min_thickness 0.25)
		(keepout
			(tracks not_allowed)
			(vias allowed)
			(pads allowed)
			(copperpour not_allowed)
			(footprints allowed)
		)
		(placement
			(enabled no)
			(sheetname "")
		)
		(fill
			(thermal_gap 0.5)
			(thermal_bridge_width 0.5)
			(island_removal_mode 0)
		)
		(polygon
			(pts
				(arc
					(start 349.651828 -282.307538)
					(mid 349.632144 -282.354948)
					(end 349.625412 -282.405836)
				)
				(arc
					(start 349.625412 -282.405836)
					(mid 349.683068 -282.54503)
					(end 349.822262 -282.602686)
				)
				(arc
					(start 349.822262 -282.602686)
					(mid 349.920693 -282.57627)
					(end 349.992696 -282.504134)
				)
				(arc
					(start 350.462596 -281.690064)
					(mid 350.48228 -281.642654)
					(end 350.489012 -281.591766)
				)
				(arc
					(start 350.489012 -281.591766)
					(mid 350.431356 -281.452572)
					(end 350.292162 -281.394916)
				)
				(arc
					(start 350.292162 -281.394916)
					(mid 350.193731 -281.421332)
					(end 350.121728 -281.493468)
				)
			)
		)
	)
	(zone
		(layers "F.Cu" "B.Cu" "In1.Cu" "In2.Cu" "In3.Cu" "In4.Cu" "In5.Cu" "In6.Cu"
			"In7.Cu" "In8.Cu" "In9.Cu" "In10.Cu" "In11.Cu" "In12.Cu" "In13.Cu" "In14.Cu"
			"In15.Cu" "In16.Cu"
		)
		(hatch none 0.5)
		(connect_pads
			(clearance 0)
		)
		(min_thickness 0.25)
		(keepout
			(tracks not_allowed)
			(vias allowed)
			(pads allowed)
			(copperpour not_allowed)
			(footprints allowed)
		)
		(placement
			(enabled no)
			(sheetname "")
		)
		(fill
			(thermal_gap 0.5)
			(thermal_bridge_width 0.5)
			(island_removal_mode 0)
		)
		(polygon
			(pts
				(arc
					(start 398.928844 -4.57073)
					(mid 398.547844 -4.95173)
					(end 398.928844 -5.33273)
				)
				(arc
					(start 399.792444 -5.33273)
					(mid 400.173444 -4.95173)
					(end 399.792444 -4.57073)
				)
			)
		)
	)
	(zone
		(layers "F.Cu" "B.Cu" "In1.Cu" "In2.Cu" "In3.Cu" "In4.Cu" "In5.Cu" "In6.Cu"
			"In7.Cu" "In8.Cu" "In9.Cu" "In10.Cu" "In11.Cu" "In12.Cu" "In13.Cu" "In14.Cu"
			"In15.Cu" "In16.Cu"
		)
		(hatch none 0.5)
		(connect_pads
			(clearance 0)
		)
		(min_thickness 0.25)
		(keepout
			(tracks not_allowed)
			(vias allowed)
			(pads allowed)
			(copperpour not_allowed)
			(footprints allowed)
		)
		(placement
			(enabled no)
			(sheetname "")
		)
		(fill
			(thermal_gap 0.5)
			(thermal_bridge_width 0.5)
			(island_removal_mode 0)
		)
		(polygon
			(pts
				(arc
					(start 106.329988 -214.622634)
					(mid 105.672128 -214.622634)
					(end 106.329988 -214.622634)
				)
			)
		)
	)
	(zone
		(layers "F.Cu" "B.Cu" "In1.Cu" "In2.Cu" "In3.Cu" "In4.Cu" "In5.Cu" "In6.Cu"
			"In7.Cu" "In8.Cu" "In9.Cu" "In10.Cu" "In11.Cu" "In12.Cu" "In13.Cu" "In14.Cu"
			"In15.Cu" "In16.Cu"
		)
		(hatch none 0.5)
		(connect_pads
			(clearance 0)
		)
		(min_thickness 0.25)
		(keepout
			(tracks not_allowed)
			(vias allowed)
			(pads allowed)
			(copperpour not_allowed)
			(footprints allowed)
		)
		(placement
			(enabled no)
			(sheetname "")
		)
		(fill
			(thermal_gap 0.5)
			(thermal_bridge_width 0.5)
			(island_removal_mode 0)
		)
		(polygon
			(pts
				(arc
					(start 166.103554 -403.502876)
					(mid 165.722554 -403.883876)
					(end 166.103554 -404.264876)
				)
				(arc
					(start 166.967154 -404.264876)
					(mid 167.348154 -403.883876)
					(end 166.967154 -403.502876)
				)
			)
		)
	)
	(zone
		(layers "F.Cu" "B.Cu" "In1.Cu" "In2.Cu" "In3.Cu" "In4.Cu" "In5.Cu" "In6.Cu"
			"In7.Cu" "In8.Cu" "In9.Cu" "In10.Cu" "In11.Cu" "In12.Cu" "In13.Cu" "In14.Cu"
			"In15.Cu" "In16.Cu"
		)
		(hatch none 0.5)
		(connect_pads
			(clearance 0)
		)
		(min_thickness 0.25)
		(keepout
			(tracks not_allowed)
			(vias allowed)
			(pads allowed)
			(copperpour not_allowed)
			(footprints allowed)
		)
		(placement
			(enabled no)
			(sheetname "")
		)
		(fill
			(thermal_gap 0.5)
			(thermal_bridge_width 0.5)
			(island_removal_mode 0)
		)
		(polygon
			(pts
				(arc
					(start 343.102946 -284.847538)
					(mid 342.445086 -284.847538)
					(end 343.102946 -284.847538)
				)
			)
		)
	)
	(zone
		(layers "F.Cu" "B.Cu" "In1.Cu" "In2.Cu" "In3.Cu" "In4.Cu" "In5.Cu" "In6.Cu"
			"In7.Cu" "In8.Cu" "In9.Cu" "In10.Cu" "In11.Cu" "In12.Cu" "In13.Cu" "In14.Cu"
			"In15.Cu" "In16.Cu"
		)
		(hatch none 0.5)
		(connect_pads
			(clearance 0)
		)
		(min_thickness 0.25)
		(keepout
			(tracks not_allowed)
			(vias allowed)
			(pads allowed)
			(copperpour not_allowed)
			(footprints allowed)
		)
		(placement
			(enabled no)
			(sheetname "")
		)
		(fill
			(thermal_gap 0.5)
			(thermal_bridge_width 0.5)
			(island_removal_mode 0)
		)
		(polygon
			(pts
				(arc
					(start 121.318782 -288.004758)
					(mid 121.246793 -287.932599)
					(end 121.148348 -287.906206)
				)
				(arc
					(start 121.148348 -287.906206)
					(mid 121.009154 -287.963862)
					(end 120.951498 -288.103056)
				)
				(arc
					(start 120.951498 -288.103056)
					(mid 120.958255 -288.153937)
					(end 120.977914 -288.201354)
				)
				(arc
					(start 121.447814 -289.015424)
					(mid 121.519803 -289.087583)
					(end 121.618248 -289.113976)
				)
				(arc
					(start 121.618248 -289.113976)
					(mid 121.757442 -289.05632)
					(end 121.815098 -288.917126)
				)
				(arc
					(start 121.815098 -288.917126)
					(mid 121.808341 -288.866245)
					(end 121.788682 -288.818828)
				)
			)
		)
	)
	(zone
		(layers "F.Cu" "B.Cu" "In1.Cu" "In2.Cu" "In3.Cu" "In4.Cu" "In5.Cu" "In6.Cu"
			"In7.Cu" "In8.Cu" "In9.Cu" "In10.Cu" "In11.Cu" "In12.Cu" "In13.Cu" "In14.Cu"
			"In15.Cu" "In16.Cu"
		)
		(hatch none 0.5)
		(connect_pads
			(clearance 0)
		)
		(min_thickness 0.25)
		(keepout
			(tracks not_allowed)
			(vias allowed)
			(pads allowed)
			(copperpour not_allowed)
			(footprints allowed)
		)
		(placement
			(enabled no)
			(sheetname "")
		)
		(fill
			(thermal_gap 0.5)
			(thermal_bridge_width 0.5)
			(island_removal_mode 0)
		)
		(polygon
			(pts
				(arc
					(start 97.042478 -284.847538)
					(mid 96.384618 -284.847538)
					(end 97.042478 -284.847538)
				)
			)
		)
	)
	(zone
		(layers "F.Cu" "B.Cu" "In1.Cu" "In2.Cu" "In3.Cu" "In4.Cu" "In5.Cu" "In6.Cu"
			"In7.Cu" "In8.Cu" "In9.Cu" "In10.Cu" "In11.Cu" "In12.Cu" "In13.Cu" "In14.Cu"
			"In15.Cu" "In16.Cu"
		)
		(hatch none 0.5)
		(connect_pads
			(clearance 0)
		)
		(min_thickness 0.25)
		(keepout
			(tracks not_allowed)
			(vias allowed)
			(pads allowed)
			(copperpour not_allowed)
			(footprints allowed)
		)
		(placement
			(enabled no)
			(sheetname "")
		)
		(fill
			(thermal_gap 0.5)
			(thermal_bridge_width 0.5)
			(island_removal_mode 0)
		)
		(polygon
			(pts
				(arc
					(start 93.095318 -282.405836)
					(mid 93.753178 -282.405836)
					(end 93.095318 -282.405836)
				)
			)
		)
	)
	(zone
		(layers "F.Cu" "B.Cu" "In1.Cu" "In2.Cu" "In3.Cu" "In4.Cu" "In5.Cu" "In6.Cu"
			"In7.Cu" "In8.Cu" "In9.Cu" "In10.Cu" "In11.Cu" "In12.Cu" "In13.Cu" "In14.Cu"
			"In15.Cu" "In16.Cu"
		)
		(hatch none 0.5)
		(connect_pads
			(clearance 0)
		)
		(min_thickness 0.25)
		(keepout
			(tracks not_allowed)
			(vias allowed)
			(pads allowed)
			(copperpour not_allowed)
			(footprints allowed)
		)
		(placement
			(enabled no)
			(sheetname "")
		)
		(fill
			(thermal_gap 0.5)
			(thermal_bridge_width 0.5)
			(island_removal_mode 0)
		)
		(polygon
			(pts
				(xy 468.100156 -140.877036) (xy 468.100156 -145.877026) (xy 467.795356 -145.572226) (xy 467.795356 -141.181836)
			)
		)
	)
	(zone
		(layers "F.Cu" "B.Cu" "In1.Cu" "In2.Cu" "In3.Cu" "In4.Cu" "In5.Cu" "In6.Cu"
			"In7.Cu" "In8.Cu" "In9.Cu" "In10.Cu" "In11.Cu" "In12.Cu" "In13.Cu" "In14.Cu"
			"In15.Cu" "In16.Cu"
		)
		(hatch none 0.5)
		(connect_pads
			(clearance 0)
		)
		(min_thickness 0.25)
		(keepout
			(tracks not_allowed)
			(vias allowed)
			(pads allowed)
			(copperpour not_allowed)
			(footprints allowed)
		)
		(placement
			(enabled no)
			(sheetname "")
		)
		(fill
			(thermal_gap 0.5)
			(thermal_bridge_width 0.5)
			(island_removal_mode 0)
		)
		(polygon
			(pts
				(arc
					(start 380.584964 -224.389442)
					(mid 379.927104 -224.389442)
					(end 380.584964 -224.389442)
				)
			)
		)
	)
	(zone
		(layers "F.Cu" "B.Cu" "In1.Cu" "In2.Cu" "In3.Cu" "In4.Cu" "In5.Cu" "In6.Cu"
			"In7.Cu" "In8.Cu" "In9.Cu" "In10.Cu" "In11.Cu" "In12.Cu" "In13.Cu" "In14.Cu"
			"In15.Cu" "In16.Cu"
		)
		(hatch none 0.5)
		(connect_pads
			(clearance 0)
		)
		(min_thickness 0.25)
		(keepout
			(tracks not_allowed)
			(vias allowed)
			(pads allowed)
			(copperpour not_allowed)
			(footprints allowed)
		)
		(placement
			(enabled no)
			(sheetname "")
		)
		(fill
			(thermal_gap 0.5)
			(thermal_bridge_width 0.5)
			(island_removal_mode 0)
		)
		(polygon
			(pts
				(arc
					(start 91.105482 -215.436704)
					(mid 91.763342 -215.436704)
					(end 91.105482 -215.436704)
				)
			)
		)
	)
	(zone
		(layers "F.Cu" "B.Cu" "In1.Cu" "In2.Cu" "In3.Cu" "In4.Cu" "In5.Cu" "In6.Cu"
			"In7.Cu" "In8.Cu" "In9.Cu" "In10.Cu" "In11.Cu" "In12.Cu" "In13.Cu" "In14.Cu"
			"In15.Cu" "In16.Cu"
		)
		(hatch none 0.5)
		(connect_pads
			(clearance 0)
		)
		(min_thickness 0.25)
		(keepout
			(tracks not_allowed)
			(vias allowed)
			(pads allowed)
			(copperpour not_allowed)
			(footprints allowed)
		)
		(placement
			(enabled no)
			(sheetname "")
		)
		(fill
			(thermal_gap 0.5)
			(thermal_bridge_width 0.5)
			(island_removal_mode 0)
		)
		(polygon
			(pts
				(arc
					(start 94.223078 -286.475424)
					(mid 93.565218 -286.475424)
					(end 94.223078 -286.475424)
				)
			)
		)
	)
	(zone
		(layers "F.Cu" "B.Cu" "In1.Cu" "In2.Cu" "In3.Cu" "In4.Cu" "In5.Cu" "In6.Cu"
			"In7.Cu" "In8.Cu" "In9.Cu" "In10.Cu" "In11.Cu" "In12.Cu" "In13.Cu" "In14.Cu"
			"In15.Cu" "In16.Cu"
		)
		(hatch none 0.5)
		(connect_pads
			(clearance 0)
		)
		(min_thickness 0.25)
		(keepout
			(tracks not_allowed)
			(vias allowed)
			(pads allowed)
			(copperpour not_allowed)
			(footprints allowed)
		)
		(placement
			(enabled no)
			(sheetname "")
		)
		(fill
			(thermal_gap 0.5)
			(thermal_bridge_width 0.5)
			(island_removal_mode 0)
		)
		(polygon
			(pts
				(arc
					(start 120.154954 -400.477228)
					(mid 119.773954 -400.858228)
					(end 120.154954 -401.239228)
				)
				(arc
					(start 121.018554 -401.239228)
					(mid 121.399554 -400.858228)
					(end 121.018554 -400.477228)
				)
			)
		)
	)
	(zone
		(layers "F.Cu" "B.Cu" "In1.Cu" "In2.Cu" "In3.Cu" "In4.Cu" "In5.Cu" "In6.Cu"
			"In7.Cu" "In8.Cu" "In9.Cu" "In10.Cu" "In11.Cu" "In12.Cu" "In13.Cu" "In14.Cu"
			"In15.Cu" "In16.Cu"
		)
		(hatch none 0.5)
		(connect_pads
			(clearance 0)
		)
		(min_thickness 0.25)
		(keepout
			(tracks not_allowed)
			(vias allowed)
			(pads allowed)
			(copperpour not_allowed)
			(footprints allowed)
		)
		(placement
			(enabled no)
			(sheetname "")
		)
		(fill
			(thermal_gap 0.5)
			(thermal_bridge_width 0.5)
			(island_removal_mode 0)
		)
		(polygon
			(pts
				(arc
					(start 353.80041 -220.319854)
					(mid 353.14255 -220.319854)
					(end 353.80041 -220.319854)
				)
			)
		)
	)
	(zone
		(layers "F.Cu" "B.Cu" "In1.Cu" "In2.Cu" "In3.Cu" "In4.Cu" "In5.Cu" "In6.Cu"
			"In7.Cu" "In8.Cu" "In9.Cu" "In10.Cu" "In11.Cu" "In12.Cu" "In13.Cu" "In14.Cu"
			"In15.Cu" "In16.Cu"
		)
		(hatch none 0.5)
		(connect_pads
			(clearance 0)
		)
		(min_thickness 0.25)
		(keepout
			(tracks not_allowed)
			(vias allowed)
			(pads allowed)
			(copperpour not_allowed)
			(footprints allowed)
		)
		(placement
			(enabled no)
			(sheetname "")
		)
		(fill
			(thermal_gap 0.5)
			(thermal_bridge_width 0.5)
			(island_removal_mode 0)
		)
		(polygon
			(pts
				(arc
					(start 322.359528 -400.477228)
					(mid 321.978528 -400.858228)
					(end 322.359528 -401.239228)
				)
				(arc
					(start 323.223128 -401.239228)
					(mid 323.604128 -400.858228)
					(end 323.223128 -400.477228)
				)
			)
		)
	)
	(zone
		(layers "F.Cu" "B.Cu" "In1.Cu" "In2.Cu" "In3.Cu" "In4.Cu" "In5.Cu" "In6.Cu"
			"In7.Cu" "In8.Cu" "In9.Cu" "In10.Cu" "In11.Cu" "In12.Cu" "In13.Cu" "In14.Cu"
			"In15.Cu" "In16.Cu"
		)
		(hatch none 0.5)
		(connect_pads
			(clearance 0)
		)
		(min_thickness 0.25)
		(keepout
			(tracks not_allowed)
			(vias allowed)
			(pads allowed)
			(copperpour not_allowed)
			(footprints allowed)
		)
		(placement
			(enabled no)
			(sheetname "")
		)
		(fill
			(thermal_gap 0.5)
			(thermal_bridge_width 0.5)
			(island_removal_mode 0)
		)
		(polygon
			(pts
				(arc
					(start 125.126496 -224.389442)
					(mid 124.468636 -224.389442)
					(end 125.126496 -224.389442)
				)
			)
		)
	)
	(zone
		(layers "F.Cu" "B.Cu" "In1.Cu" "In2.Cu" "In3.Cu" "In4.Cu" "In5.Cu" "In6.Cu"
			"In7.Cu" "In8.Cu" "In9.Cu" "In10.Cu" "In11.Cu" "In12.Cu" "In13.Cu" "In14.Cu"
			"In15.Cu" "In16.Cu"
		)
		(hatch none 0.5)
		(connect_pads
			(clearance 0)
		)
		(min_thickness 0.25)
		(keepout
			(tracks not_allowed)
			(vias allowed)
			(pads allowed)
			(copperpour not_allowed)
			(footprints allowed)
		)
		(placement
			(enabled no)
			(sheetname "")
		)
		(fill
			(thermal_gap 0.5)
			(thermal_bridge_width 0.5)
			(island_removal_mode 0)
		)
		(polygon
			(pts
				(arc
					(start 353.330256 -214.622634)
					(mid 352.672396 -214.622634)
					(end 353.330256 -214.622634)
				)
			)
		)
	)
	(zone
		(layers "F.Cu" "B.Cu" "In1.Cu" "In2.Cu" "In3.Cu" "In4.Cu" "In5.Cu" "In6.Cu"
			"In7.Cu" "In8.Cu" "In9.Cu" "In10.Cu" "In11.Cu" "In12.Cu" "In13.Cu" "In14.Cu"
			"In15.Cu" "In16.Cu"
		)
		(hatch none 0.5)
		(connect_pads
			(clearance 0)
		)
		(min_thickness 0.25)
		(keepout
			(tracks not_allowed)
			(vias allowed)
			(pads allowed)
			(copperpour not_allowed)
			(footprints allowed)
		)
		(placement
			(enabled no)
			(sheetname "")
		)
		(fill
			(thermal_gap 0.5)
			(thermal_bridge_width 0.5)
			(island_removal_mode 0)
		)
		(polygon
			(pts
				(arc
					(start 348.003114 -223.67367)
					(mid 348.022798 -223.62626)
					(end 348.02953 -223.575372)
				)
				(arc
					(start 348.02953 -223.575372)
					(mid 347.971874 -223.436178)
					(end 347.83268 -223.378522)
				)
				(arc
					(start 347.83268 -223.378522)
					(mid 347.734249 -223.404938)
					(end 347.662246 -223.477074)
				)
				(arc
					(start 347.1926 -224.291144)
					(mid 347.172916 -224.338554)
					(end 347.166184 -224.389442)
				)
				(arc
					(start 347.166184 -224.389442)
					(mid 347.22384 -224.528636)
					(end 347.363034 -224.586292)
				)
				(arc
					(start 347.363034 -224.586292)
					(mid 347.461465 -224.559876)
					(end 347.533468 -224.48774)
				)
			)
		)
	)
	(zone
		(layers "F.Cu" "B.Cu" "In1.Cu" "In2.Cu" "In3.Cu" "In4.Cu" "In5.Cu" "In6.Cu"
			"In7.Cu" "In8.Cu" "In9.Cu" "In10.Cu" "In11.Cu" "In12.Cu" "In13.Cu" "In14.Cu"
			"In15.Cu" "In16.Cu"
		)
		(hatch none 0.5)
		(connect_pads
			(clearance 0)
		)
		(min_thickness 0.25)
		(keepout
			(tracks not_allowed)
			(vias allowed)
			(pads allowed)
			(copperpour not_allowed)
			(footprints allowed)
		)
		(placement
			(enabled no)
			(sheetname "")
		)
		(fill
			(thermal_gap 0.5)
			(thermal_bridge_width 0.5)
			(island_removal_mode 0)
		)
		(polygon
			(pts
				(arc
					(start 360.37901 -221.94774)
					(mid 359.72115 -221.94774)
					(end 360.37901 -221.94774)
				)
			)
		)
	)
	(zone
		(layers "F.Cu" "B.Cu" "In1.Cu" "In2.Cu" "In3.Cu" "In4.Cu" "In5.Cu" "In6.Cu"
			"In7.Cu" "In8.Cu" "In9.Cu" "In10.Cu" "In11.Cu" "In12.Cu" "In13.Cu" "In14.Cu"
			"In15.Cu" "In16.Cu"
		)
		(hatch none 0.5)
		(connect_pads
			(clearance 0)
		)
		(min_thickness 0.25)
		(keepout
			(tracks not_allowed)
			(vias allowed)
			(pads allowed)
			(copperpour not_allowed)
			(footprints allowed)
		)
		(placement
			(enabled no)
			(sheetname "")
		)
		(fill
			(thermal_gap 0.5)
			(thermal_bridge_width 0.5)
			(island_removal_mode 0)
		)
		(polygon
			(pts
				(arc
					(start 133.506718 -288.917126)
					(mid 134.164578 -288.917126)
					(end 133.506718 -288.917126)
				)
			)
		)
	)
	(zone
		(layers "F.Cu" "B.Cu" "In1.Cu" "In2.Cu" "In3.Cu" "In4.Cu" "In5.Cu" "In6.Cu"
			"In7.Cu" "In8.Cu" "In9.Cu" "In10.Cu" "In11.Cu" "In12.Cu" "In13.Cu" "In14.Cu"
			"In15.Cu" "In16.Cu"
		)
		(hatch none 0.5)
		(connect_pads
			(clearance 0)
		)
		(min_thickness 0.25)
		(keepout
			(tracks not_allowed)
			(vias allowed)
			(pads allowed)
			(copperpour not_allowed)
			(footprints allowed)
		)
		(placement
			(enabled no)
			(sheetname "")
		)
		(fill
			(thermal_gap 0.5)
			(thermal_bridge_width 0.5)
			(island_removal_mode 0)
		)
		(polygon
			(pts
				(arc
					(start 360.37901 -225.203258)
					(mid 359.72115 -225.203258)
					(end 360.37901 -225.203258)
				)
			)
		)
	)
	(zone
		(layers "F.Cu" "B.Cu" "In1.Cu" "In2.Cu" "In3.Cu" "In4.Cu" "In5.Cu" "In6.Cu"
			"In7.Cu" "In8.Cu" "In9.Cu" "In10.Cu" "In11.Cu" "In12.Cu" "In13.Cu" "In14.Cu"
			"In15.Cu" "In16.Cu"
		)
		(hatch none 0.5)
		(connect_pads
			(clearance 0)
		)
		(min_thickness 0.25)
		(keepout
			(tracks not_allowed)
			(vias allowed)
			(pads allowed)
			(copperpour not_allowed)
			(footprints allowed)
		)
		(placement
			(enabled no)
			(sheetname "")
		)
		(fill
			(thermal_gap 0.5)
			(thermal_bridge_width 0.5)
			(island_removal_mode 0)
		)
		(polygon
			(pts
				(arc
					(start 378.705364 -217.878406)
					(mid 378.047504 -217.878406)
					(end 378.705364 -217.878406)
				)
			)
		)
	)
	(zone
		(layers "F.Cu" "B.Cu" "In1.Cu" "In2.Cu" "In3.Cu" "In4.Cu" "In5.Cu" "In6.Cu"
			"In7.Cu" "In8.Cu" "In9.Cu" "In10.Cu" "In11.Cu" "In12.Cu" "In13.Cu" "In14.Cu"
			"In15.Cu" "In16.Cu"
		)
		(hatch none 0.5)
		(connect_pads
			(clearance 0)
		)
		(min_thickness 0.25)
		(keepout
			(tracks not_allowed)
			(vias allowed)
			(pads allowed)
			(copperpour not_allowed)
			(footprints allowed)
		)
		(placement
			(enabled no)
			(sheetname "")
		)
		(fill
			(thermal_gap 0.5)
			(thermal_bridge_width 0.5)
			(island_removal_mode 0)
		)
		(polygon
			(pts
				(arc
					(start 392.86561 -400.477228)
					(mid 392.48461 -400.858228)
					(end 392.86561 -401.239228)
				)
				(arc
					(start 393.72921 -401.239228)
					(mid 394.11021 -400.858228)
					(end 393.72921 -400.477228)
				)
			)
		)
	)
	(zone
		(layers "F.Cu" "B.Cu" "In1.Cu" "In2.Cu" "In3.Cu" "In4.Cu" "In5.Cu" "In6.Cu"
			"In7.Cu" "In8.Cu" "In9.Cu" "In10.Cu" "In11.Cu" "In12.Cu" "In13.Cu" "In14.Cu"
			"In15.Cu" "In16.Cu"
		)
		(hatch none 0.5)
		(connect_pads
			(clearance 0)
		)
		(min_thickness 0.25)
		(keepout
			(tracks not_allowed)
			(vias allowed)
			(pads allowed)
			(copperpour not_allowed)
			(footprints allowed)
		)
		(placement
			(enabled no)
			(sheetname "")
		)
		(fill
			(thermal_gap 0.5)
			(thermal_bridge_width 0.5)
			(island_removal_mode 0)
		)
		(polygon
			(pts
				(arc
					(start 316.233048 -400.477228)
					(mid 315.852048 -400.858228)
					(end 316.233048 -401.239228)
				)
				(arc
					(start 317.096648 -401.239228)
					(mid 317.477648 -400.858228)
					(end 317.096648 -400.477228)
				)
			)
		)
	)
	(zone
		(layers "F.Cu" "B.Cu" "In1.Cu" "In2.Cu" "In3.Cu" "In4.Cu" "In5.Cu" "In6.Cu"
			"In7.Cu" "In8.Cu" "In9.Cu" "In10.Cu" "In11.Cu" "In12.Cu" "In13.Cu" "In14.Cu"
			"In15.Cu" "In16.Cu"
		)
		(hatch none 0.5)
		(connect_pads
			(clearance 0)
		)
		(min_thickness 0.25)
		(keepout
			(tracks not_allowed)
			(vias allowed)
			(pads allowed)
			(copperpour not_allowed)
			(footprints allowed)
		)
		(placement
			(enabled no)
			(sheetname "")
		)
		(fill
			(thermal_gap 0.5)
			(thermal_bridge_width 0.5)
			(island_removal_mode 0)
		)
		(polygon
			(pts
				(arc
					(start 373.84736 -221.231968)
					(mid 373.867044 -221.184558)
					(end 373.873776 -221.13367)
				)
				(arc
					(start 373.873776 -221.13367)
					(mid 373.81612 -220.994476)
					(end 373.676926 -220.93682)
				)
				(arc
					(start 373.676926 -220.93682)
					(mid 373.578495 -220.963236)
					(end 373.506492 -221.035372)
				)
				(arc
					(start 373.036846 -221.849442)
					(mid 373.017162 -221.896852)
					(end 373.01043 -221.94774)
				)
				(arc
					(start 373.01043 -221.94774)
					(mid 373.068086 -222.086934)
					(end 373.20728 -222.14459)
				)
				(arc
					(start 373.20728 -222.14459)
					(mid 373.305711 -222.118174)
					(end 373.377714 -222.046038)
				)
			)
		)
	)
	(zone
		(layers "F.Cu" "B.Cu" "In1.Cu" "In2.Cu" "In3.Cu" "In4.Cu" "In5.Cu" "In6.Cu"
			"In7.Cu" "In8.Cu" "In9.Cu" "In10.Cu" "In11.Cu" "In12.Cu" "In13.Cu" "In14.Cu"
			"In15.Cu" "In16.Cu"
		)
		(hatch none 0.5)
		(connect_pads
			(clearance 0)
		)
		(min_thickness 0.25)
		(keepout
			(tracks not_allowed)
			(vias allowed)
			(pads allowed)
			(copperpour not_allowed)
			(footprints allowed)
		)
		(placement
			(enabled no)
			(sheetname "")
		)
		(fill
			(thermal_gap 0.5)
			(thermal_bridge_width 0.5)
			(island_removal_mode 0)
		)
		(polygon
			(pts
				(arc
					(start 114.318796 -218.692222)
					(mid 113.660936 -218.692222)
					(end 114.318796 -218.692222)
				)
			)
		)
	)
	(zone
		(layers "F.Cu" "B.Cu" "In1.Cu" "In2.Cu" "In3.Cu" "In4.Cu" "In5.Cu" "In6.Cu"
			"In7.Cu" "In8.Cu" "In9.Cu" "In10.Cu" "In11.Cu" "In12.Cu" "In13.Cu" "In14.Cu"
			"In15.Cu" "In16.Cu"
		)
		(hatch none 0.5)
		(connect_pads
			(clearance 0)
		)
		(min_thickness 0.25)
		(keepout
			(tracks not_allowed)
			(vias allowed)
			(pads allowed)
			(copperpour not_allowed)
			(footprints allowed)
		)
		(placement
			(enabled no)
			(sheetname "")
		)
		(fill
			(thermal_gap 0.5)
			(thermal_bridge_width 0.5)
			(island_removal_mode 0)
		)
		(polygon
			(pts
				(arc
					(start 128.885696 -217.878406)
					(mid 128.227836 -217.878406)
					(end 128.885696 -217.878406)
				)
			)
		)
	)
	(zone
		(layers "F.Cu" "B.Cu" "In1.Cu" "In2.Cu" "In3.Cu" "In4.Cu" "In5.Cu" "In6.Cu"
			"In7.Cu" "In8.Cu" "In9.Cu" "In10.Cu" "In11.Cu" "In12.Cu" "In13.Cu" "In14.Cu"
			"In15.Cu" "In16.Cu"
		)
		(hatch none 0.5)
		(connect_pads
			(clearance 0)
		)
		(min_thickness 0.25)
		(keepout
			(tracks not_allowed)
			(vias allowed)
			(pads allowed)
			(copperpour not_allowed)
			(footprints allowed)
		)
		(placement
			(enabled no)
			(sheetname "")
		)
		(fill
			(thermal_gap 0.5)
			(thermal_bridge_width 0.5)
			(island_removal_mode 0)
		)
		(polygon
			(pts
				(arc
					(start 179.39258 -48.61814)
					(mid 179.01158 -48.23714)
					(end 178.63058 -48.61814)
				)
				(arc
					(start 178.63058 -49.48174)
					(mid 179.01158 -49.86274)
					(end 179.39258 -49.48174)
				)
			)
		)
	)
	(zone
		(layers "F.Cu" "B.Cu" "In1.Cu" "In2.Cu" "In3.Cu" "In4.Cu" "In5.Cu" "In6.Cu"
			"In7.Cu" "In8.Cu" "In9.Cu" "In10.Cu" "In11.Cu" "In12.Cu" "In13.Cu" "In14.Cu"
			"In15.Cu" "In16.Cu"
		)
		(hatch none 0.5)
		(connect_pads
			(clearance 0)
		)
		(min_thickness 0.25)
		(keepout
			(tracks not_allowed)
			(vias allowed)
			(pads allowed)
			(copperpour not_allowed)
			(footprints allowed)
		)
		(placement
			(enabled no)
			(sheetname "")
		)
		(fill
			(thermal_gap 0.5)
			(thermal_bridge_width 0.5)
			(island_removal_mode 0)
		)
		(polygon
			(pts
				(arc
					(start 346.865448 -403.502876)
					(mid 346.484448 -403.883876)
					(end 346.865448 -404.264876)
				)
				(arc
					(start 347.729048 -404.264876)
					(mid 348.110048 -403.883876)
					(end 347.729048 -403.502876)
				)
			)
		)
	)
	(zone
		(layers "F.Cu" "B.Cu" "In1.Cu" "In2.Cu" "In3.Cu" "In4.Cu" "In5.Cu" "In6.Cu"
			"In7.Cu" "In8.Cu" "In9.Cu" "In10.Cu" "In11.Cu" "In12.Cu" "In13.Cu" "In14.Cu"
			"In15.Cu" "In16.Cu"
		)
		(hatch none 0.5)
		(connect_pads
			(clearance 0)
		)
		(min_thickness 0.25)
		(keepout
			(tracks not_allowed)
			(vias allowed)
			(pads allowed)
			(copperpour not_allowed)
			(footprints allowed)
		)
		(placement
			(enabled no)
			(sheetname "")
		)
		(fill
			(thermal_gap 0.5)
			(thermal_bridge_width 0.5)
			(island_removal_mode 0)
		)
		(polygon
			(pts
				(arc
					(start 103.511096 -224.389442)
					(mid 102.853236 -224.389442)
					(end 103.511096 -224.389442)
				)
			)
		)
	)
	(zone
		(layers "F.Cu" "B.Cu" "In1.Cu" "In2.Cu" "In3.Cu" "In4.Cu" "In5.Cu" "In6.Cu"
			"In7.Cu" "In8.Cu" "In9.Cu" "In10.Cu" "In11.Cu" "In12.Cu" "In13.Cu" "In14.Cu"
			"In15.Cu" "In16.Cu"
		)
		(hatch none 0.5)
		(connect_pads
			(clearance 0)
		)
		(min_thickness 0.25)
		(keepout
			(tracks not_allowed)
			(vias allowed)
			(pads allowed)
			(copperpour not_allowed)
			(footprints allowed)
		)
		(placement
			(enabled no)
			(sheetname "")
		)
		(fill
			(thermal_gap 0.5)
			(thermal_bridge_width 0.5)
			(island_removal_mode 0)
		)
		(polygon
			(pts
				(arc
					(start 357.199692 -273.453098)
					(mid 356.541832 -273.453098)
					(end 357.199692 -273.453098)
				)
			)
		)
	)
	(zone
		(layers "F.Cu" "B.Cu" "In1.Cu" "In2.Cu" "In3.Cu" "In4.Cu" "In5.Cu" "In6.Cu"
			"In7.Cu" "In8.Cu" "In9.Cu" "In10.Cu" "In11.Cu" "In12.Cu" "In13.Cu" "In14.Cu"
			"In15.Cu" "In16.Cu"
		)
		(hatch none 0.5)
		(connect_pads
			(clearance 0)
		)
		(min_thickness 0.25)
		(keepout
			(tracks not_allowed)
			(vias allowed)
			(pads allowed)
			(copperpour not_allowed)
			(footprints allowed)
		)
		(placement
			(enabled no)
			(sheetname "")
		)
		(fill
			(thermal_gap 0.5)
			(thermal_bridge_width 0.5)
			(island_removal_mode 0)
		)
		(polygon
			(pts
				(arc
					(start 365.07801 -220.319854)
					(mid 364.42015 -220.319854)
					(end 365.07801 -220.319854)
				)
			)
		)
	)
	(zone
		(layers "F.Cu" "B.Cu" "In1.Cu" "In2.Cu" "In3.Cu" "In4.Cu" "In5.Cu" "In6.Cu"
			"In7.Cu" "In8.Cu" "In9.Cu" "In10.Cu" "In11.Cu" "In12.Cu" "In13.Cu" "In14.Cu"
			"In15.Cu" "In16.Cu"
		)
		(hatch none 0.5)
		(connect_pads
			(clearance 0)
		)
		(min_thickness 0.25)
		(keepout
			(tracks not_allowed)
			(vias allowed)
			(pads allowed)
			(copperpour not_allowed)
			(footprints allowed)
		)
		(placement
			(enabled no)
			(sheetname "")
		)
		(fill
			(thermal_gap 0.5)
			(thermal_bridge_width 0.5)
			(island_removal_mode 0)
		)
		(polygon
			(pts
				(arc
					(start 120.349518 -288.917126)
					(mid 121.007378 -288.917126)
					(end 120.349518 -288.917126)
				)
			)
		)
	)
	(zone
		(layers "F.Cu" "B.Cu" "In1.Cu" "In2.Cu" "In3.Cu" "In4.Cu" "In5.Cu" "In6.Cu"
			"In7.Cu" "In8.Cu" "In9.Cu" "In10.Cu" "In11.Cu" "In12.Cu" "In13.Cu" "In14.Cu"
			"In15.Cu" "In16.Cu"
		)
		(hatch none 0.5)
		(connect_pads
			(clearance 0)
		)
		(min_thickness 0.25)
		(keepout
			(tracks not_allowed)
			(vias allowed)
			(pads allowed)
			(copperpour not_allowed)
			(footprints allowed)
		)
		(placement
			(enabled no)
			(sheetname "")
		)
		(fill
			(thermal_gap 0.5)
			(thermal_bridge_width 0.5)
			(island_removal_mode 0)
		)
		(polygon
			(pts
				(arc
					(start 100.503482 -215.436704)
					(mid 101.161342 -215.436704)
					(end 100.503482 -215.436704)
				)
			)
		)
	)
	(zone
		(layers "F.Cu" "B.Cu" "In1.Cu" "In2.Cu" "In3.Cu" "In4.Cu" "In5.Cu" "In6.Cu"
			"In7.Cu" "In8.Cu" "In9.Cu" "In10.Cu" "In11.Cu" "In12.Cu" "In13.Cu" "In14.Cu"
			"In15.Cu" "In16.Cu"
		)
		(hatch none 0.5)
		(connect_pads
			(clearance 0)
		)
		(min_thickness 0.25)
		(keepout
			(tracks not_allowed)
			(vias allowed)
			(pads allowed)
			(copperpour not_allowed)
			(footprints allowed)
		)
		(placement
			(enabled no)
			(sheetname "")
		)
		(fill
			(thermal_gap 0.5)
			(thermal_bridge_width 0.5)
			(island_removal_mode 0)
		)
		(polygon
			(pts
				(arc
					(start 363.510068 -224.291144)
					(mid 363.438079 -224.218985)
					(end 363.339634 -224.192592)
				)
				(arc
					(start 363.339634 -224.192592)
					(mid 363.20044 -224.250248)
					(end 363.142784 -224.389442)
				)
				(arc
					(start 363.142784 -224.389442)
					(mid 363.149541 -224.440323)
					(end 363.1692 -224.48774)
				)
				(arc
					(start 363.638846 -225.301556)
					(mid 363.710835 -225.373715)
					(end 363.80928 -225.400108)
				)
				(arc
					(start 363.80928 -225.400108)
					(mid 363.948474 -225.342452)
					(end 364.00613 -225.203258)
				)
				(arc
					(start 364.00613 -225.203258)
					(mid 363.999373 -225.152377)
					(end 363.979714 -225.10496)
				)
			)
		)
	)
	(zone
		(layers "F.Cu" "B.Cu" "In1.Cu" "In2.Cu" "In3.Cu" "In4.Cu" "In5.Cu" "In6.Cu"
			"In7.Cu" "In8.Cu" "In9.Cu" "In10.Cu" "In11.Cu" "In12.Cu" "In13.Cu" "In14.Cu"
			"In15.Cu" "In16.Cu"
		)
		(hatch none 0.5)
		(connect_pads
			(clearance 0)
		)
		(min_thickness 0.25)
		(keepout
			(tracks not_allowed)
			(vias allowed)
			(pads allowed)
			(copperpour not_allowed)
			(footprints allowed)
		)
		(placement
			(enabled no)
			(sheetname "")
		)
		(fill
			(thermal_gap 0.5)
			(thermal_bridge_width 0.5)
			(island_removal_mode 0)
		)
		(polygon
			(pts
				(arc
					(start 19.665188 -395.979396)
					(mid 19.284188 -395.598396)
					(end 18.903188 -395.979396)
				)
				(arc
					(start 18.903188 -396.842996)
					(mid 19.284188 -397.223996)
					(end 19.665188 -396.842996)
				)
			)
		)
	)
	(zone
		(layers "F.Cu" "B.Cu" "In1.Cu" "In2.Cu" "In3.Cu" "In4.Cu" "In5.Cu" "In6.Cu"
			"In7.Cu" "In8.Cu" "In9.Cu" "In10.Cu" "In11.Cu" "In12.Cu" "In13.Cu" "In14.Cu"
			"In15.Cu" "In16.Cu"
		)
		(hatch none 0.5)
		(connect_pads
			(clearance 0)
		)
		(min_thickness 0.25)
		(keepout
			(tracks not_allowed)
			(vias allowed)
			(pads allowed)
			(copperpour not_allowed)
			(footprints allowed)
		)
		(placement
			(enabled no)
			(sheetname "")
		)
		(fill
			(thermal_gap 0.5)
			(thermal_bridge_width 0.5)
			(island_removal_mode 0)
		)
		(polygon
			(pts
				(arc
					(start 37.163248 -398.27835)
					(mid 36.782248 -398.65935)
					(end 37.163248 -399.04035)
				)
				(arc
					(start 38.026848 -399.04035)
					(mid 38.407848 -398.65935)
					(end 38.026848 -398.27835)
				)
			)
		)
	)
	(zone
		(layers "F.Cu" "B.Cu" "In1.Cu" "In2.Cu" "In3.Cu" "In4.Cu" "In5.Cu" "In6.Cu"
			"In7.Cu" "In8.Cu" "In9.Cu" "In10.Cu" "In11.Cu" "In12.Cu" "In13.Cu" "In14.Cu"
			"In15.Cu" "In16.Cu"
		)
		(hatch none 0.5)
		(connect_pads
			(clearance 0)
		)
		(min_thickness 0.25)
		(keepout
			(tracks not_allowed)
			(vias allowed)
			(pads allowed)
			(copperpour not_allowed)
			(footprints allowed)
		)
		(placement
			(enabled no)
			(sheetname "")
		)
		(fill
			(thermal_gap 0.5)
			(thermal_bridge_width 0.5)
			(island_removal_mode 0)
		)
		(polygon
			(pts
				(arc
					(start 241.044984 -53.847238)
					(mid 240.663984 -53.466238)
					(end 240.282984 -53.847238)
				)
				(arc
					(start 240.282984 -54.710838)
					(mid 240.663984 -55.091838)
					(end 241.044984 -54.710838)
				)
			)
		)
	)
	(zone
		(layers "F.Cu" "B.Cu" "In1.Cu" "In2.Cu" "In3.Cu" "In4.Cu" "In5.Cu" "In6.Cu"
			"In7.Cu" "In8.Cu" "In9.Cu" "In10.Cu" "In11.Cu" "In12.Cu" "In13.Cu" "In14.Cu"
			"In15.Cu" "In16.Cu"
		)
		(hatch none 0.5)
		(connect_pads
			(clearance 0)
		)
		(min_thickness 0.25)
		(keepout
			(tracks not_allowed)
			(vias allowed)
			(pads allowed)
			(copperpour not_allowed)
			(footprints allowed)
		)
		(placement
			(enabled no)
			(sheetname "")
		)
		(fill
			(thermal_gap 0.5)
			(thermal_bridge_width 0.5)
			(island_removal_mode 0)
		)
		(polygon
			(pts
				(arc
					(start 99.204018 -283.219906)
					(mid 99.861878 -283.219906)
					(end 99.204018 -283.219906)
				)
			)
		)
	)
	(zone
		(layers "F.Cu" "B.Cu" "In1.Cu" "In2.Cu" "In3.Cu" "In4.Cu" "In5.Cu" "In6.Cu"
			"In7.Cu" "In8.Cu" "In9.Cu" "In10.Cu" "In11.Cu" "In12.Cu" "In13.Cu" "In14.Cu"
			"In15.Cu" "In16.Cu"
		)
		(hatch none 0.5)
		(connect_pads
			(clearance 0)
		)
		(min_thickness 0.25)
		(keepout
			(tracks not_allowed)
			(vias allowed)
			(pads allowed)
			(copperpour not_allowed)
			(footprints allowed)
		)
		(placement
			(enabled no)
			(sheetname "")
		)
		(fill
			(thermal_gap 0.5)
			(thermal_bridge_width 0.5)
			(island_removal_mode 0)
		)
		(polygon
			(pts
				(arc
					(start 340.283546 -286.475424)
					(mid 339.625686 -286.475424)
					(end 340.283546 -286.475424)
				)
			)
		)
	)
	(zone
		(layers "F.Cu" "B.Cu" "In1.Cu" "In2.Cu" "In3.Cu" "In4.Cu" "In5.Cu" "In6.Cu"
			"In7.Cu" "In8.Cu" "In9.Cu" "In10.Cu" "In11.Cu" "In12.Cu" "In13.Cu" "In14.Cu"
			"In15.Cu" "In16.Cu"
		)
		(hatch none 0.5)
		(connect_pads
			(clearance 0)
		)
		(min_thickness 0.25)
		(keepout
			(tracks not_allowed)
			(vias allowed)
			(pads allowed)
			(copperpour not_allowed)
			(footprints allowed)
		)
		(placement
			(enabled no)
			(sheetname "")
		)
		(fill
			(thermal_gap 0.5)
			(thermal_bridge_width 0.5)
			(island_removal_mode 0)
		)
		(polygon
			(pts
				(arc
					(start 89.805764 -279.964134)
					(mid 90.463624 -279.964134)
					(end 89.805764 -279.964134)
				)
			)
		)
	)
	(zone
		(layers "F.Cu" "B.Cu" "In1.Cu" "In2.Cu" "In3.Cu" "In4.Cu" "In5.Cu" "In6.Cu"
			"In7.Cu" "In8.Cu" "In9.Cu" "In10.Cu" "In11.Cu" "In12.Cu" "In13.Cu" "In14.Cu"
			"In15.Cu" "In16.Cu"
		)
		(hatch none 0.5)
		(connect_pads
			(clearance 0)
		)
		(min_thickness 0.25)
		(keepout
			(tracks not_allowed)
			(vias allowed)
			(pads allowed)
			(copperpour not_allowed)
			(footprints allowed)
		)
		(placement
			(enabled no)
			(sheetname "")
		)
		(fill
			(thermal_gap 0.5)
			(thermal_bridge_width 0.5)
			(island_removal_mode 0)
		)
		(polygon
			(pts
				(arc
					(start 360.849164 -221.133924)
					(mid 360.191304 -221.133924)
					(end 360.849164 -221.133924)
				)
			)
		)
	)
	(zone
		(layers "F.Cu" "B.Cu" "In1.Cu" "In2.Cu" "In3.Cu" "In4.Cu" "In5.Cu" "In6.Cu"
			"In7.Cu" "In8.Cu" "In9.Cu" "In10.Cu" "In11.Cu" "In12.Cu" "In13.Cu" "In14.Cu"
			"In15.Cu" "In16.Cu"
		)
		(hatch none 0.5)
		(connect_pads
			(clearance 0)
		)
		(min_thickness 0.25)
		(keepout
			(tracks not_allowed)
			(vias allowed)
			(pads allowed)
			(copperpour not_allowed)
			(footprints allowed)
		)
		(placement
			(enabled no)
			(sheetname "")
		)
		(fill
			(thermal_gap 0.5)
			(thermal_bridge_width 0.5)
			(island_removal_mode 0)
		)
		(polygon
			(pts
				(arc
					(start 120.73128 -213.646766)
					(mid 120.663572 -213.574915)
					(end 120.568466 -213.548468)
				)
				(arc
					(start 120.568466 -213.548468)
					(mid 120.438252 -213.602404)
					(end 120.384316 -213.732618)
				)
				(arc
					(start 120.384316 -213.732618)
					(mid 120.389767 -213.776839)
					(end 120.405652 -213.81847)
				)
				(arc
					(start 120.875044 -214.708486)
					(mid 120.942752 -214.780337)
					(end 121.037858 -214.806784)
				)
				(arc
					(start 121.037858 -214.806784)
					(mid 121.168072 -214.752848)
					(end 121.222008 -214.622634)
				)
				(arc
					(start 121.222008 -214.622634)
					(mid 121.216557 -214.578413)
					(end 121.200672 -214.536782)
				)
			)
		)
	)
	(zone
		(layers "F.Cu" "B.Cu" "In1.Cu" "In2.Cu" "In3.Cu" "In4.Cu" "In5.Cu" "In6.Cu"
			"In7.Cu" "In8.Cu" "In9.Cu" "In10.Cu" "In11.Cu" "In12.Cu" "In13.Cu" "In14.Cu"
			"In15.Cu" "In16.Cu"
		)
		(hatch none 0.5)
		(connect_pads
			(clearance 0)
		)
		(min_thickness 0.25)
		(keepout
			(tracks not_allowed)
			(vias allowed)
			(pads allowed)
			(copperpour not_allowed)
			(footprints allowed)
		)
		(placement
			(enabled no)
			(sheetname "")
		)
		(fill
			(thermal_gap 0.5)
			(thermal_bridge_width 0.5)
			(island_removal_mode 0)
		)
		(polygon
			(pts
				(arc
					(start 94.424246 -217.162634)
					(mid 94.44393 -217.115224)
					(end 94.450662 -217.064336)
				)
				(arc
					(start 94.450662 -217.064336)
					(mid 94.393006 -216.925142)
					(end 94.253812 -216.867486)
				)
				(arc
					(start 94.253812 -216.867486)
					(mid 94.155381 -216.893902)
					(end 94.083378 -216.966038)
				)
				(arc
					(start 93.613732 -217.780108)
					(mid 93.594048 -217.827518)
					(end 93.587316 -217.878406)
				)
				(arc
					(start 93.587316 -217.878406)
					(mid 93.644972 -218.0176)
					(end 93.784166 -218.075256)
				)
				(arc
					(start 93.784166 -218.075256)
					(mid 93.882597 -218.04884)
					(end 93.9546 -217.976704)
				)
			)
		)
	)
	(zone
		(layers "F.Cu" "B.Cu" "In1.Cu" "In2.Cu" "In3.Cu" "In4.Cu" "In5.Cu" "In6.Cu"
			"In7.Cu" "In8.Cu" "In9.Cu" "In10.Cu" "In11.Cu" "In12.Cu" "In13.Cu" "In14.Cu"
			"In15.Cu" "In16.Cu"
		)
		(hatch none 0.5)
		(connect_pads
			(clearance 0)
		)
		(min_thickness 0.25)
		(keepout
			(tracks not_allowed)
			(vias allowed)
			(pads allowed)
			(copperpour not_allowed)
			(footprints allowed)
		)
		(placement
			(enabled no)
			(sheetname "")
		)
		(fill
			(thermal_gap 0.5)
			(thermal_bridge_width 0.5)
			(island_removal_mode 0)
		)
		(polygon
			(pts
				(arc
					(start 132.456682 -215.436704)
					(mid 133.114542 -215.436704)
					(end 132.456682 -215.436704)
				)
			)
		)
	)
	(zone
		(layers "F.Cu" "B.Cu" "In1.Cu" "In2.Cu" "In3.Cu" "In4.Cu" "In5.Cu" "In6.Cu"
			"In7.Cu" "In8.Cu" "In9.Cu" "In10.Cu" "In11.Cu" "In12.Cu" "In13.Cu" "In14.Cu"
			"In15.Cu" "In16.Cu"
		)
		(hatch none 0.5)
		(connect_pads
			(clearance 0)
		)
		(min_thickness 0.25)
		(keepout
			(tracks not_allowed)
			(vias allowed)
			(pads allowed)
			(copperpour not_allowed)
			(footprints allowed)
		)
		(placement
			(enabled no)
			(sheetname "")
		)
		(fill
			(thermal_gap 0.5)
			(thermal_bridge_width 0.5)
			(island_removal_mode 0)
		)
		(polygon
			(pts
				(arc
					(start 103.932482 -274.168362)
					(mid 103.860493 -274.096203)
					(end 103.762048 -274.06981)
				)
				(arc
					(start 103.762048 -274.06981)
					(mid 103.622854 -274.127466)
					(end 103.565198 -274.26666)
				)
				(arc
					(start 103.565198 -274.26666)
					(mid 103.571955 -274.317541)
					(end 103.591614 -274.364958)
				)
				(arc
					(start 104.061514 -275.179028)
					(mid 104.133503 -275.251187)
					(end 104.231948 -275.27758)
				)
				(arc
					(start 104.231948 -275.27758)
					(mid 104.371142 -275.219924)
					(end 104.428798 -275.08073)
				)
				(arc
					(start 104.428798 -275.08073)
					(mid 104.422041 -275.029849)
					(end 104.402382 -274.982432)
				)
			)
		)
	)
	(zone
		(layers "F.Cu" "B.Cu" "In1.Cu" "In2.Cu" "In3.Cu" "In4.Cu" "In5.Cu" "In6.Cu"
			"In7.Cu" "In8.Cu" "In9.Cu" "In10.Cu" "In11.Cu" "In12.Cu" "In13.Cu" "In14.Cu"
			"In15.Cu" "In16.Cu"
		)
		(hatch none 0.5)
		(connect_pads
			(clearance 0)
		)
		(min_thickness 0.25)
		(keepout
			(tracks not_allowed)
			(vias allowed)
			(pads allowed)
			(copperpour not_allowed)
			(footprints allowed)
		)
		(placement
			(enabled no)
			(sheetname "")
		)
		(fill
			(thermal_gap 0.5)
			(thermal_bridge_width 0.5)
			(island_removal_mode 0)
		)
		(polygon
			(pts
				(arc
					(start 344.512646 -280.778204)
					(mid 343.854786 -280.778204)
					(end 344.512646 -280.778204)
				)
			)
		)
	)
	(zone
		(layers "F.Cu" "B.Cu" "In1.Cu" "In2.Cu" "In3.Cu" "In4.Cu" "In5.Cu" "In6.Cu"
			"In7.Cu" "In8.Cu" "In9.Cu" "In10.Cu" "In11.Cu" "In12.Cu" "In13.Cu" "In14.Cu"
			"In15.Cu" "In16.Cu"
		)
		(hatch none 0.5)
		(connect_pads
			(clearance 0)
		)
		(min_thickness 0.25)
		(keepout
			(tracks not_allowed)
			(vias allowed)
			(pads allowed)
			(copperpour not_allowed)
			(footprints allowed)
		)
		(placement
			(enabled no)
			(sheetname "")
		)
		(fill
			(thermal_gap 0.5)
			(thermal_bridge_width 0.5)
			(island_removal_mode 0)
		)
		(polygon
			(pts
				(arc
					(start 126.281434 -400.477228)
					(mid 125.900434 -400.858228)
					(end 126.281434 -401.239228)
				)
				(arc
					(start 127.145034 -401.239228)
					(mid 127.526034 -400.858228)
					(end 127.145034 -400.477228)
				)
			)
		)
	)
	(zone
		(layers "F.Cu" "B.Cu" "In1.Cu" "In2.Cu" "In3.Cu" "In4.Cu" "In5.Cu" "In6.Cu"
			"In7.Cu" "In8.Cu" "In9.Cu" "In10.Cu" "In11.Cu" "In12.Cu" "In13.Cu" "In14.Cu"
			"In15.Cu" "In16.Cu"
		)
		(hatch none 0.5)
		(connect_pads
			(clearance 0)
		)
		(min_thickness 0.25)
		(keepout
			(tracks not_allowed)
			(vias allowed)
			(pads allowed)
			(copperpour not_allowed)
			(footprints allowed)
		)
		(placement
			(enabled no)
			(sheetname "")
		)
		(fill
			(thermal_gap 0.5)
			(thermal_bridge_width 0.5)
			(island_removal_mode 0)
		)
		(polygon
			(pts
				(arc
					(start 101.472492 -214.720932)
					(mid 101.492176 -214.673522)
					(end 101.498908 -214.622634)
				)
				(arc
					(start 101.498908 -214.622634)
					(mid 101.441252 -214.48344)
					(end 101.302058 -214.425784)
				)
				(arc
					(start 101.302058 -214.425784)
					(mid 101.203627 -214.4522)
					(end 101.131624 -214.524336)
				)
				(arc
					(start 100.661978 -215.338406)
					(mid 100.642294 -215.385816)
					(end 100.635562 -215.436704)
				)
				(arc
					(start 100.635562 -215.436704)
					(mid 100.693218 -215.575898)
					(end 100.832412 -215.633554)
				)
				(arc
					(start 100.832412 -215.633554)
					(mid 100.930843 -215.607138)
					(end 101.002846 -215.535002)
				)
			)
		)
	)
	(zone
		(layers "F.Cu" "B.Cu" "In1.Cu" "In2.Cu" "In3.Cu" "In4.Cu" "In5.Cu" "In6.Cu"
			"In7.Cu" "In8.Cu" "In9.Cu" "In10.Cu" "In11.Cu" "In12.Cu" "In13.Cu" "In14.Cu"
			"In15.Cu" "In16.Cu"
		)
		(hatch none 0.5)
		(connect_pads
			(clearance 0)
		)
		(min_thickness 0.25)
		(keepout
			(tracks not_allowed)
			(vias allowed)
			(pads allowed)
			(copperpour not_allowed)
			(footprints allowed)
		)
		(placement
			(enabled no)
			(sheetname "")
		)
		(fill
			(thermal_gap 0.5)
			(thermal_bridge_width 0.5)
			(island_removal_mode 0)
		)
		(polygon
			(pts
				(arc
					(start 92.954094 -283.023056)
					(mid 92.757244 -283.219906)
					(end 92.954094 -283.416756)
				)
				(arc
					(start 93.893894 -283.416756)
					(mid 94.090744 -283.219906)
					(end 93.893894 -283.023056)
				)
			)
		)
	)
	(zone
		(layers "F.Cu" "B.Cu" "In1.Cu" "In2.Cu" "In3.Cu" "In4.Cu" "In5.Cu" "In6.Cu"
			"In7.Cu" "In8.Cu" "In9.Cu" "In10.Cu" "In11.Cu" "In12.Cu" "In13.Cu" "In14.Cu"
			"In15.Cu" "In16.Cu"
		)
		(hatch none 0.5)
		(connect_pads
			(clearance 0)
		)
		(min_thickness 0.25)
		(keepout
			(tracks not_allowed)
			(vias allowed)
			(pads allowed)
			(copperpour not_allowed)
			(footprints allowed)
		)
		(placement
			(enabled no)
			(sheetname "")
		)
		(fill
			(thermal_gap 0.5)
			(thermal_bridge_width 0.5)
			(island_removal_mode 0)
		)
		(polygon
			(pts
				(arc
					(start 137.157968 -206.024988)
					(mid 132.711952 -206.024988)
					(end 137.157968 -206.024988)
				)
			)
		)
	)
	(zone
		(layers "F.Cu" "B.Cu" "In1.Cu" "In2.Cu" "In3.Cu" "In4.Cu" "In5.Cu" "In6.Cu"
			"In7.Cu" "In8.Cu" "In9.Cu" "In10.Cu" "In11.Cu" "In12.Cu" "In13.Cu" "In14.Cu"
			"In15.Cu" "In16.Cu"
		)
		(hatch none 0.5)
		(connect_pads
			(clearance 0)
		)
		(min_thickness 0.25)
		(keepout
			(tracks not_allowed)
			(vias allowed)
			(pads allowed)
			(copperpour not_allowed)
			(footprints allowed)
		)
		(placement
			(enabled no)
			(sheetname "")
		)
		(fill
			(thermal_gap 0.5)
			(thermal_bridge_width 0.5)
			(island_removal_mode 0)
		)
		(polygon
			(pts
				(arc
					(start 354.850192 -280.778204)
					(mid 354.192332 -280.778204)
					(end 354.850192 -280.778204)
				)
			)
		)
	)
	(zone
		(layers "F.Cu" "B.Cu" "In1.Cu" "In2.Cu" "In3.Cu" "In4.Cu" "In5.Cu" "In6.Cu"
			"In7.Cu" "In8.Cu" "In9.Cu" "In10.Cu" "In11.Cu" "In12.Cu" "In13.Cu" "In14.Cu"
			"In15.Cu" "In16.Cu"
		)
		(hatch none 0.5)
		(connect_pads
			(clearance 0)
		)
		(min_thickness 0.25)
		(keepout
			(tracks not_allowed)
			(vias allowed)
			(pads allowed)
			(copperpour not_allowed)
			(footprints allowed)
		)
		(placement
			(enabled no)
			(sheetname "")
		)
		(fill
			(thermal_gap 0.5)
			(thermal_bridge_width 0.5)
			(island_removal_mode 0)
		)
		(polygon
			(pts
				(arc
					(start 114.788696 -224.389442)
					(mid 114.130836 -224.389442)
					(end 114.788696 -224.389442)
				)
			)
		)
	)
	(zone
		(layers "F.Cu" "B.Cu" "In1.Cu" "In2.Cu" "In3.Cu" "In4.Cu" "In5.Cu" "In6.Cu"
			"In7.Cu" "In8.Cu" "In9.Cu" "In10.Cu" "In11.Cu" "In12.Cu" "In13.Cu" "In14.Cu"
			"In15.Cu" "In16.Cu"
		)
		(hatch none 0.5)
		(connect_pads
			(clearance 0)
		)
		(min_thickness 0.25)
		(keepout
			(tracks not_allowed)
			(vias allowed)
			(pads allowed)
			(copperpour not_allowed)
			(footprints allowed)
		)
		(placement
			(enabled no)
			(sheetname "")
		)
		(fill
			(thermal_gap 0.5)
			(thermal_bridge_width 0.5)
			(island_removal_mode 0)
		)
		(polygon
			(pts
				(arc
					(start 240.849658 -128.156208)
					(mid 240.468658 -127.775208)
					(end 240.087658 -128.156208)
				)
				(arc
					(start 240.087658 -129.019808)
					(mid 240.468658 -129.400808)
					(end 240.849658 -129.019808)
				)
			)
		)
	)
	(zone
		(layers "F.Cu" "B.Cu" "In1.Cu" "In2.Cu" "In3.Cu" "In4.Cu" "In5.Cu" "In6.Cu"
			"In7.Cu" "In8.Cu" "In9.Cu" "In10.Cu" "In11.Cu" "In12.Cu" "In13.Cu" "In14.Cu"
			"In15.Cu" "In16.Cu"
		)
		(hatch none 0.5)
		(connect_pads
			(clearance 0)
		)
		(min_thickness 0.25)
		(keepout
			(tracks not_allowed)
			(vias allowed)
			(pads allowed)
			(copperpour not_allowed)
			(footprints allowed)
		)
		(placement
			(enabled no)
			(sheetname "")
		)
		(fill
			(thermal_gap 0.5)
			(thermal_bridge_width 0.5)
			(island_removal_mode 0)
		)
		(polygon
			(pts
				(arc
					(start 343.40673 -288.831274)
					(mid 343.339022 -288.759423)
					(end 343.243916 -288.732976)
				)
				(arc
					(start 343.243916 -288.732976)
					(mid 343.113702 -288.786912)
					(end 343.059766 -288.917126)
				)
				(arc
					(start 343.059766 -288.917126)
					(mid 343.065217 -288.961347)
					(end 343.081102 -289.002978)
				)
				(arc
					(start 343.550748 -289.892994)
					(mid 343.618456 -289.964845)
					(end 343.713562 -289.991292)
				)
				(arc
					(start 343.713562 -289.991292)
					(mid 343.843776 -289.937356)
					(end 343.897712 -289.807142)
				)
				(arc
					(start 343.897712 -289.807142)
					(mid 343.892261 -289.762921)
					(end 343.876376 -289.72129)
				)
			)
		)
	)
	(zone
		(layers "F.Cu" "B.Cu" "In1.Cu" "In2.Cu" "In3.Cu" "In4.Cu" "In5.Cu" "In6.Cu"
			"In7.Cu" "In8.Cu" "In9.Cu" "In10.Cu" "In11.Cu" "In12.Cu" "In13.Cu" "In14.Cu"
			"In15.Cu" "In16.Cu"
		)
		(hatch none 0.5)
		(connect_pads
			(clearance 0)
		)
		(min_thickness 0.25)
		(keepout
			(tracks not_allowed)
			(vias allowed)
			(pads allowed)
			(copperpour not_allowed)
			(footprints allowed)
		)
		(placement
			(enabled no)
			(sheetname "")
		)
		(fill
			(thermal_gap 0.5)
			(thermal_bridge_width 0.5)
			(island_removal_mode 0)
		)
		(polygon
			(pts
				(arc
					(start 96.303846 -217.162634)
					(mid 96.32353 -217.115224)
					(end 96.330262 -217.064336)
				)
				(arc
					(start 96.330262 -217.064336)
					(mid 96.272606 -216.925142)
					(end 96.133412 -216.867486)
				)
				(arc
					(start 96.133412 -216.867486)
					(mid 96.034981 -216.893902)
					(end 95.962978 -216.966038)
				)
				(arc
					(start 95.493332 -217.780108)
					(mid 95.473648 -217.827518)
					(end 95.466916 -217.878406)
				)
				(arc
					(start 95.466916 -217.878406)
					(mid 95.524572 -218.0176)
					(end 95.663766 -218.075256)
				)
				(arc
					(start 95.663766 -218.075256)
					(mid 95.762197 -218.04884)
					(end 95.8342 -217.976704)
				)
			)
		)
	)
	(zone
		(layers "F.Cu" "B.Cu" "In1.Cu" "In2.Cu" "In3.Cu" "In4.Cu" "In5.Cu" "In6.Cu"
			"In7.Cu" "In8.Cu" "In9.Cu" "In10.Cu" "In11.Cu" "In12.Cu" "In13.Cu" "In14.Cu"
			"In15.Cu" "In16.Cu"
		)
		(hatch none 0.5)
		(connect_pads
			(clearance 0)
		)
		(min_thickness 0.25)
		(keepout
			(tracks not_allowed)
			(vias allowed)
			(pads allowed)
			(copperpour not_allowed)
			(footprints allowed)
		)
		(placement
			(enabled no)
			(sheetname "")
		)
		(fill
			(thermal_gap 0.5)
			(thermal_bridge_width 0.5)
			(island_removal_mode 0)
		)
		(polygon
			(pts
				(arc
					(start 370.357146 -286.475424)
					(mid 369.699286 -286.475424)
					(end 370.357146 -286.475424)
				)
			)
		)
	)
	(zone
		(layers "F.Cu" "B.Cu" "In1.Cu" "In2.Cu" "In3.Cu" "In4.Cu" "In5.Cu" "In6.Cu"
			"In7.Cu" "In8.Cu" "In9.Cu" "In10.Cu" "In11.Cu" "In12.Cu" "In13.Cu" "In14.Cu"
			"In15.Cu" "In16.Cu"
		)
		(hatch none 0.5)
		(connect_pads
			(clearance 0)
		)
		(min_thickness 0.25)
		(keepout
			(tracks not_allowed)
			(vias allowed)
			(pads allowed)
			(copperpour not_allowed)
			(footprints allowed)
		)
		(placement
			(enabled no)
			(sheetname "")
		)
		(fill
			(thermal_gap 0.5)
			(thermal_bridge_width 0.5)
			(island_removal_mode 0)
		)
		(polygon
			(pts
				(arc
					(start 141.597634 -400.477228)
					(mid 141.216634 -400.858228)
					(end 141.597634 -401.239228)
				)
				(arc
					(start 142.461234 -401.239228)
					(mid 142.842234 -400.858228)
					(end 142.461234 -400.477228)
				)
			)
		)
	)
	(zone
		(layers "F.Cu" "B.Cu" "In1.Cu" "In2.Cu" "In3.Cu" "In4.Cu" "In5.Cu" "In6.Cu"
			"In7.Cu" "In8.Cu" "In9.Cu" "In10.Cu" "In11.Cu" "In12.Cu" "In13.Cu" "In14.Cu"
			"In15.Cu" "In16.Cu"
		)
		(hatch none 0.5)
		(connect_pads
			(clearance 0)
		)
		(min_thickness 0.25)
		(keepout
			(tracks not_allowed)
			(vias allowed)
			(pads allowed)
			(copperpour not_allowed)
			(footprints allowed)
		)
		(placement
			(enabled no)
			(sheetname "")
		)
		(fill
			(thermal_gap 0.5)
			(thermal_bridge_width 0.5)
			(island_removal_mode 0)
		)
		(polygon
			(pts
				(arc
					(start 366.95761 -217.064336)
					(mid 366.29975 -217.064336)
					(end 366.95761 -217.064336)
				)
			)
		)
	)
	(zone
		(layers "F.Cu" "B.Cu" "In1.Cu" "In2.Cu" "In3.Cu" "In4.Cu" "In5.Cu" "In6.Cu"
			"In7.Cu" "In8.Cu" "In9.Cu" "In10.Cu" "In11.Cu" "In12.Cu" "In13.Cu" "In14.Cu"
			"In15.Cu" "In16.Cu"
		)
		(hatch none 0.5)
		(connect_pads
			(clearance 0)
		)
		(min_thickness 0.25)
		(keepout
			(tracks not_allowed)
			(vias allowed)
			(pads allowed)
			(copperpour not_allowed)
			(footprints allowed)
		)
		(placement
			(enabled no)
			(sheetname "")
		)
		(fill
			(thermal_gap 0.5)
			(thermal_bridge_width 0.5)
			(island_removal_mode 0)
		)
		(polygon
			(pts
				(arc
					(start 88.396318 -288.917126)
					(mid 89.054178 -288.917126)
					(end 88.396318 -288.917126)
				)
			)
		)
	)
	(zone
		(layers "F.Cu" "B.Cu" "In1.Cu" "In2.Cu" "In3.Cu" "In4.Cu" "In5.Cu" "In6.Cu"
			"In7.Cu" "In8.Cu" "In9.Cu" "In10.Cu" "In11.Cu" "In12.Cu" "In13.Cu" "In14.Cu"
			"In15.Cu" "In16.Cu"
		)
		(hatch none 0.5)
		(connect_pads
			(clearance 0)
		)
		(min_thickness 0.25)
		(keepout
			(tracks not_allowed)
			(vias allowed)
			(pads allowed)
			(copperpour not_allowed)
			(footprints allowed)
		)
		(placement
			(enabled no)
			(sheetname "")
		)
		(fill
			(thermal_gap 0.5)
			(thermal_bridge_width 0.5)
			(island_removal_mode 0)
		)
		(polygon
			(pts
				(arc
					(start 352.232468 -217.780108)
					(mid 352.160479 -217.707949)
					(end 352.062034 -217.681556)
				)
				(arc
					(start 352.062034 -217.681556)
					(mid 351.92284 -217.739212)
					(end 351.865184 -217.878406)
				)
				(arc
					(start 351.865184 -217.878406)
					(mid 351.871941 -217.929287)
					(end 351.8916 -217.976704)
				)
				(arc
					(start 352.361246 -218.79052)
					(mid 352.433235 -218.862679)
					(end 352.53168 -218.889072)
				)
				(arc
					(start 352.53168 -218.889072)
					(mid 352.670874 -218.831416)
					(end 352.72853 -218.692222)
				)
				(arc
					(start 352.72853 -218.692222)
					(mid 352.721773 -218.641341)
					(end 352.702114 -218.593924)
				)
			)
		)
	)
	(zone
		(layers "F.Cu" "B.Cu" "In1.Cu" "In2.Cu" "In3.Cu" "In4.Cu" "In5.Cu" "In6.Cu"
			"In7.Cu" "In8.Cu" "In9.Cu" "In10.Cu" "In11.Cu" "In12.Cu" "In13.Cu" "In14.Cu"
			"In15.Cu" "In16.Cu"
		)
		(hatch none 0.5)
		(connect_pads
			(clearance 0)
		)
		(min_thickness 0.25)
		(keepout
			(tracks not_allowed)
			(vias allowed)
			(pads allowed)
			(copperpour not_allowed)
			(footprints allowed)
		)
		(placement
			(enabled no)
			(sheetname "")
		)
		(fill
			(thermal_gap 0.5)
			(thermal_bridge_width 0.5)
			(island_removal_mode 0)
		)
		(polygon
			(pts
				(arc
					(start 182.422292 -44.116498)
					(mid 182.041292 -43.735498)
					(end 181.660292 -44.116498)
				)
				(arc
					(start 181.660292 -44.980098)
					(mid 182.041292 -45.361098)
					(end 182.422292 -44.980098)
				)
			)
		)
	)
	(zone
		(layers "F.Cu" "B.Cu" "In1.Cu" "In2.Cu" "In3.Cu" "In4.Cu" "In5.Cu" "In6.Cu"
			"In7.Cu" "In8.Cu" "In9.Cu" "In10.Cu" "In11.Cu" "In12.Cu" "In13.Cu" "In14.Cu"
			"In15.Cu" "In16.Cu"
		)
		(hatch none 0.5)
		(connect_pads
			(clearance 0)
		)
		(min_thickness 0.25)
		(keepout
			(tracks not_allowed)
			(vias allowed)
			(pads allowed)
			(copperpour not_allowed)
			(footprints allowed)
		)
		(placement
			(enabled no)
			(sheetname "")
		)
		(fill
			(thermal_gap 0.5)
			(thermal_bridge_width 0.5)
			(island_removal_mode 0)
		)
		(polygon
			(pts
				(arc
					(start 129.747264 -285.661354)
					(mid 130.405124 -285.661354)
					(end 129.747264 -285.661354)
				)
			)
		)
	)
	(zone
		(layers "F.Cu" "B.Cu" "In1.Cu" "In2.Cu" "In3.Cu" "In4.Cu" "In5.Cu" "In6.Cu"
			"In7.Cu" "In8.Cu" "In9.Cu" "In10.Cu" "In11.Cu" "In12.Cu" "In13.Cu" "In14.Cu"
			"In15.Cu" "In16.Cu"
		)
		(hatch none 0.5)
		(connect_pads
			(clearance 0)
		)
		(min_thickness 0.25)
		(keepout
			(tracks not_allowed)
			(vias allowed)
			(pads allowed)
			(copperpour not_allowed)
			(footprints allowed)
		)
		(placement
			(enabled no)
			(sheetname "")
		)
		(fill
			(thermal_gap 0.5)
			(thermal_bridge_width 0.5)
			(island_removal_mode 0)
		)
		(polygon
			(pts
				(arc
					(start 342.085168 -406.62352)
					(mid 341.704168 -407.00452)
					(end 342.085168 -407.38552)
				)
				(arc
					(start 342.948768 -407.38552)
					(mid 343.329768 -407.00452)
					(end 342.948768 -406.62352)
				)
			)
		)
	)
	(zone
		(layers "F.Cu" "B.Cu" "In1.Cu" "In2.Cu" "In3.Cu" "In4.Cu" "In5.Cu" "In6.Cu"
			"In7.Cu" "In8.Cu" "In9.Cu" "In10.Cu" "In11.Cu" "In12.Cu" "In13.Cu" "In14.Cu"
			"In15.Cu" "In16.Cu"
		)
		(hatch none 0.5)
		(connect_pads
			(clearance 0)
		)
		(min_thickness 0.25)
		(keepout
			(tracks not_allowed)
			(vias allowed)
			(pads allowed)
			(copperpour not_allowed)
			(footprints allowed)
		)
		(placement
			(enabled no)
			(sheetname "")
		)
		(fill
			(thermal_gap 0.5)
			(thermal_bridge_width 0.5)
			(island_removal_mode 0)
		)
		(polygon
			(pts
				(arc
					(start 350.041464 -213.732618)
					(mid 349.383604 -213.732618)
					(end 350.041464 -213.732618)
				)
			)
		)
	)
	(zone
		(layers "F.Cu" "B.Cu" "In1.Cu" "In2.Cu" "In3.Cu" "In4.Cu" "In5.Cu" "In6.Cu"
			"In7.Cu" "In8.Cu" "In9.Cu" "In10.Cu" "In11.Cu" "In12.Cu" "In13.Cu" "In14.Cu"
			"In15.Cu" "In16.Cu"
		)
		(hatch none 0.5)
		(connect_pads
			(clearance 0)
		)
		(min_thickness 0.25)
		(keepout
			(tracks not_allowed)
			(vias allowed)
			(pads allowed)
			(copperpour not_allowed)
			(footprints allowed)
		)
		(placement
			(enabled no)
			(sheetname "")
		)
		(fill
			(thermal_gap 0.5)
			(thermal_bridge_width 0.5)
			(island_removal_mode 0)
		)
		(polygon
			(pts
				(arc
					(start 348.631764 -221.133924)
					(mid 347.973904 -221.133924)
					(end 348.631764 -221.133924)
				)
			)
		)
	)
	(zone
		(layers "F.Cu" "B.Cu" "In1.Cu" "In2.Cu" "In3.Cu" "In4.Cu" "In5.Cu" "In6.Cu"
			"In7.Cu" "In8.Cu" "In9.Cu" "In10.Cu" "In11.Cu" "In12.Cu" "In13.Cu" "In14.Cu"
			"In15.Cu" "In16.Cu"
		)
		(hatch none 0.5)
		(connect_pads
			(clearance 0)
		)
		(min_thickness 0.25)
		(keepout
			(tracks not_allowed)
			(vias allowed)
			(pads allowed)
			(copperpour not_allowed)
			(footprints allowed)
		)
		(placement
			(enabled no)
			(sheetname "")
		)
		(fill
			(thermal_gap 0.5)
			(thermal_bridge_width 0.5)
			(island_removal_mode 0)
		)
		(polygon
			(pts
				(arc
					(start 353.800664 -213.732618)
					(mid 353.142804 -213.732618)
					(end 353.800664 -213.732618)
				)
			)
		)
	)
	(zone
		(layers "F.Cu" "B.Cu" "In1.Cu" "In2.Cu" "In3.Cu" "In4.Cu" "In5.Cu" "In6.Cu"
			"In7.Cu" "In8.Cu" "In9.Cu" "In10.Cu" "In11.Cu" "In12.Cu" "In13.Cu" "In14.Cu"
			"In15.Cu" "In16.Cu"
		)
		(hatch none 0.5)
		(connect_pads
			(clearance 0)
		)
		(min_thickness 0.25)
		(keepout
			(tracks not_allowed)
			(vias allowed)
			(pads allowed)
			(copperpour not_allowed)
			(footprints allowed)
		)
		(placement
			(enabled no)
			(sheetname "")
		)
		(fill
			(thermal_gap 0.5)
			(thermal_bridge_width 0.5)
			(island_removal_mode 0)
		)
		(polygon
			(pts
				(arc
					(start 316.233048 -403.502876)
					(mid 315.852048 -403.883876)
					(end 316.233048 -404.264876)
				)
				(arc
					(start 317.096648 -404.264876)
					(mid 317.477648 -403.883876)
					(end 317.096648 -403.502876)
				)
			)
		)
	)
	(zone
		(layers "F.Cu" "B.Cu" "In1.Cu" "In2.Cu" "In3.Cu" "In4.Cu" "In5.Cu" "In6.Cu"
			"In7.Cu" "In8.Cu" "In9.Cu" "In10.Cu" "In11.Cu" "In12.Cu" "In13.Cu" "In14.Cu"
			"In15.Cu" "In16.Cu"
		)
		(hatch none 0.5)
		(connect_pads
			(clearance 0)
		)
		(min_thickness 0.25)
		(keepout
			(tracks not_allowed)
			(vias allowed)
			(pads allowed)
			(copperpour not_allowed)
			(footprints allowed)
		)
		(placement
			(enabled no)
			(sheetname "")
		)
		(fill
			(thermal_gap 0.5)
			(thermal_bridge_width 0.5)
			(island_removal_mode 0)
		)
		(polygon
			(pts
				(arc
					(start 98.6536 -221.035626)
					(mid 98.581611 -220.963467)
					(end 98.483166 -220.937074)
				)
				(arc
					(start 98.483166 -220.937074)
					(mid 98.343972 -220.99473)
					(end 98.286316 -221.133924)
				)
				(arc
					(start 98.286316 -221.133924)
					(mid 98.293073 -221.184805)
					(end 98.312732 -221.232222)
				)
				(arc
					(start 98.782378 -222.046038)
					(mid 98.854367 -222.118197)
					(end 98.952812 -222.14459)
				)
				(arc
					(start 98.952812 -222.14459)
					(mid 99.092006 -222.086934)
					(end 99.149662 -221.94774)
				)
				(arc
					(start 99.149662 -221.94774)
					(mid 99.142905 -221.896859)
					(end 99.123246 -221.849442)
				)
			)
		)
	)
	(zone
		(layers "F.Cu" "B.Cu" "In1.Cu" "In2.Cu" "In3.Cu" "In4.Cu" "In5.Cu" "In6.Cu"
			"In7.Cu" "In8.Cu" "In9.Cu" "In10.Cu" "In11.Cu" "In12.Cu" "In13.Cu" "In14.Cu"
			"In15.Cu" "In16.Cu"
		)
		(hatch none 0.5)
		(connect_pads
			(clearance 0)
		)
		(min_thickness 0.25)
		(keepout
			(tracks not_allowed)
			(vias allowed)
			(pads allowed)
			(copperpour not_allowed)
			(footprints allowed)
		)
		(placement
			(enabled no)
			(sheetname "")
		)
		(fill
			(thermal_gap 0.5)
			(thermal_bridge_width 0.5)
			(island_removal_mode 0)
		)
		(polygon
			(pts
				(arc
					(start 92.155518 -288.917126)
					(mid 92.813378 -288.917126)
					(end 92.155518 -288.917126)
				)
			)
		)
	)
	(zone
		(layers "F.Cu" "B.Cu" "In1.Cu" "In2.Cu" "In3.Cu" "In4.Cu" "In5.Cu" "In6.Cu"
			"In7.Cu" "In8.Cu" "In9.Cu" "In10.Cu" "In11.Cu" "In12.Cu" "In13.Cu" "In14.Cu"
			"In15.Cu" "In16.Cu"
		)
		(hatch none 0.5)
		(connect_pads
			(clearance 0)
		)
		(min_thickness 0.25)
		(keepout
			(tracks not_allowed)
			(vias allowed)
			(pads allowed)
			(copperpour not_allowed)
			(footprints allowed)
		)
		(placement
			(enabled no)
			(sheetname "")
		)
		(fill
			(thermal_gap 0.5)
			(thermal_bridge_width 0.5)
			(island_removal_mode 0)
		)
		(polygon
			(pts
				(arc
					(start 368.679222 -220.22181)
					(mid 368.607233 -220.149651)
					(end 368.508788 -220.123258)
				)
				(arc
					(start 368.508788 -220.123258)
					(mid 368.369594 -220.180914)
					(end 368.311938 -220.320108)
				)
				(arc
					(start 368.311938 -220.320108)
					(mid 368.318695 -220.370989)
					(end 368.338354 -220.418406)
				)
				(arc
					(start 368.808 -221.232222)
					(mid 368.879989 -221.304381)
					(end 368.978434 -221.330774)
				)
				(arc
					(start 368.978434 -221.330774)
					(mid 369.117628 -221.273118)
					(end 369.175284 -221.133924)
				)
				(arc
					(start 369.175284 -221.133924)
					(mid 369.168527 -221.083043)
					(end 369.148868 -221.035626)
				)
			)
		)
	)
	(zone
		(layers "F.Cu" "B.Cu" "In1.Cu" "In2.Cu" "In3.Cu" "In4.Cu" "In5.Cu" "In6.Cu"
			"In7.Cu" "In8.Cu" "In9.Cu" "In10.Cu" "In11.Cu" "In12.Cu" "In13.Cu" "In14.Cu"
			"In15.Cu" "In16.Cu"
		)
		(hatch none 0.5)
		(connect_pads
			(clearance 0)
		)
		(min_thickness 0.25)
		(keepout
			(tracks not_allowed)
			(vias allowed)
			(pads allowed)
			(copperpour not_allowed)
			(footprints allowed)
		)
		(placement
			(enabled no)
			(sheetname "")
		)
		(fill
			(thermal_gap 0.5)
			(thermal_bridge_width 0.5)
			(island_removal_mode 0)
		)
		(polygon
			(pts
				(arc
					(start 362.728764 -217.878406)
					(mid 362.070904 -217.878406)
					(end 362.728764 -217.878406)
				)
			)
		)
	)
	(zone
		(layers "F.Cu" "B.Cu" "In1.Cu" "In2.Cu" "In3.Cu" "In4.Cu" "In5.Cu" "In6.Cu"
			"In7.Cu" "In8.Cu" "In9.Cu" "In10.Cu" "In11.Cu" "In12.Cu" "In13.Cu" "In14.Cu"
			"In15.Cu" "In16.Cu"
		)
		(hatch none 0.5)
		(connect_pads
			(clearance 0)
		)
		(min_thickness 0.25)
		(keepout
			(tracks not_allowed)
			(vias allowed)
			(pads allowed)
			(copperpour not_allowed)
			(footprints allowed)
		)
		(placement
			(enabled no)
			(sheetname "")
		)
		(fill
			(thermal_gap 0.5)
			(thermal_bridge_width 0.5)
			(island_removal_mode 0)
		)
		(polygon
			(pts
				(arc
					(start 42.526712 -6.343396)
					(mid 42.145712 -6.724396)
					(end 42.526712 -7.105396)
				)
				(arc
					(start 43.390312 -7.105396)
					(mid 43.771312 -6.724396)
					(end 43.390312 -6.343396)
				)
			)
		)
	)
	(zone
		(layers "F.Cu" "B.Cu" "In1.Cu" "In2.Cu" "In3.Cu" "In4.Cu" "In5.Cu" "In6.Cu"
			"In7.Cu" "In8.Cu" "In9.Cu" "In10.Cu" "In11.Cu" "In12.Cu" "In13.Cu" "In14.Cu"
			"In15.Cu" "In16.Cu"
		)
		(hatch none 0.5)
		(connect_pads
			(clearance 0)
		)
		(min_thickness 0.25)
		(keepout
			(tracks not_allowed)
			(vias allowed)
			(pads allowed)
			(copperpour not_allowed)
			(footprints allowed)
		)
		(placement
			(enabled no)
			(sheetname "")
		)
		(fill
			(thermal_gap 0.5)
			(thermal_bridge_width 0.5)
			(island_removal_mode 0)
		)
		(polygon
			(pts
				(arc
					(start 132.4864 -224.291144)
					(mid 132.414411 -224.218985)
					(end 132.315966 -224.192592)
				)
				(arc
					(start 132.315966 -224.192592)
					(mid 132.176772 -224.250248)
					(end 132.119116 -224.389442)
				)
				(arc
					(start 132.119116 -224.389442)
					(mid 132.125873 -224.440323)
					(end 132.145532 -224.48774)
				)
				(arc
					(start 132.615178 -225.301556)
					(mid 132.687167 -225.373715)
					(end 132.785612 -225.400108)
				)
				(arc
					(start 132.785612 -225.400108)
					(mid 132.924806 -225.342452)
					(end 132.982462 -225.203258)
				)
				(arc
					(start 132.982462 -225.203258)
					(mid 132.975705 -225.152377)
					(end 132.956046 -225.10496)
				)
			)
		)
	)
	(zone
		(layers "F.Cu" "B.Cu" "In1.Cu" "In2.Cu" "In3.Cu" "In4.Cu" "In5.Cu" "In6.Cu"
			"In7.Cu" "In8.Cu" "In9.Cu" "In10.Cu" "In11.Cu" "In12.Cu" "In13.Cu" "In14.Cu"
			"In15.Cu" "In16.Cu"
		)
		(hatch none 0.5)
		(connect_pads
			(clearance 0)
		)
		(min_thickness 0.25)
		(keepout
			(tracks not_allowed)
			(vias allowed)
			(pads allowed)
			(copperpour not_allowed)
			(footprints allowed)
		)
		(placement
			(enabled no)
			(sheetname "")
		)
		(fill
			(thermal_gap 0.5)
			(thermal_bridge_width 0.5)
			(island_removal_mode 0)
		)
		(polygon
			(pts
				(arc
					(start 344.982546 -288.103056)
					(mid 344.324686 -288.103056)
					(end 344.982546 -288.103056)
				)
			)
		)
	)
	(zone
		(layers "F.Cu" "B.Cu" "In1.Cu" "In2.Cu" "In3.Cu" "In4.Cu" "In5.Cu" "In6.Cu"
			"In7.Cu" "In8.Cu" "In9.Cu" "In10.Cu" "In11.Cu" "In12.Cu" "In13.Cu" "In14.Cu"
			"In15.Cu" "In16.Cu"
		)
		(hatch none 0.5)
		(connect_pads
			(clearance 0)
		)
		(min_thickness 0.25)
		(keepout
			(tracks not_allowed)
			(vias allowed)
			(pads allowed)
			(copperpour not_allowed)
			(footprints allowed)
		)
		(placement
			(enabled no)
			(sheetname "")
		)
		(fill
			(thermal_gap 0.5)
			(thermal_bridge_width 0.5)
			(island_removal_mode 0)
		)
		(polygon
			(pts
				(arc
					(start 131.815078 -286.475424)
					(mid 131.157218 -286.475424)
					(end 131.815078 -286.475424)
				)
			)
		)
	)
	(zone
		(layers "F.Cu" "B.Cu" "In1.Cu" "In2.Cu" "In3.Cu" "In4.Cu" "In5.Cu" "In6.Cu"
			"In7.Cu" "In8.Cu" "In9.Cu" "In10.Cu" "In11.Cu" "In12.Cu" "In13.Cu" "In14.Cu"
			"In15.Cu" "In16.Cu"
		)
		(hatch none 0.5)
		(connect_pads
			(clearance 0)
		)
		(min_thickness 0.25)
		(keepout
			(tracks not_allowed)
			(vias allowed)
			(pads allowed)
			(copperpour not_allowed)
			(footprints allowed)
		)
		(placement
			(enabled no)
			(sheetname "")
		)
		(fill
			(thermal_gap 0.5)
			(thermal_bridge_width 0.5)
			(island_removal_mode 0)
		)
		(polygon
			(pts
				(arc
					(start 340.173564 -221.133924)
					(mid 339.515704 -221.133924)
					(end 340.173564 -221.133924)
				)
			)
		)
	)
	(zone
		(layers "F.Cu" "B.Cu" "In1.Cu" "In2.Cu" "In3.Cu" "In4.Cu" "In5.Cu" "In6.Cu"
			"In7.Cu" "In8.Cu" "In9.Cu" "In10.Cu" "In11.Cu" "In12.Cu" "In13.Cu" "In14.Cu"
			"In15.Cu" "In16.Cu"
		)
		(hatch none 0.5)
		(connect_pads
			(clearance 0)
		)
		(min_thickness 0.25)
		(keepout
			(tracks not_allowed)
			(vias allowed)
			(pads allowed)
			(copperpour not_allowed)
			(footprints allowed)
		)
		(placement
			(enabled no)
			(sheetname "")
		)
		(fill
			(thermal_gap 0.5)
			(thermal_bridge_width 0.5)
			(island_removal_mode 0)
		)
		(polygon
			(pts
				(arc
					(start 131.704588 -214.622634)
					(mid 131.046728 -214.622634)
					(end 131.704588 -214.622634)
				)
			)
		)
	)
	(zone
		(layers "F.Cu" "B.Cu" "In1.Cu" "In2.Cu" "In3.Cu" "In4.Cu" "In5.Cu" "In6.Cu"
			"In7.Cu" "In8.Cu" "In9.Cu" "In10.Cu" "In11.Cu" "In12.Cu" "In13.Cu" "In14.Cu"
			"In15.Cu" "In16.Cu"
		)
		(hatch none 0.5)
		(connect_pads
			(clearance 0)
		)
		(min_thickness 0.25)
		(keepout
			(tracks not_allowed)
			(vias allowed)
			(pads allowed)
			(copperpour not_allowed)
			(footprints allowed)
		)
		(placement
			(enabled no)
			(sheetname "")
		)
		(fill
			(thermal_gap 0.5)
			(thermal_bridge_width 0.5)
			(island_removal_mode 0)
		)
		(polygon
			(pts
				(arc
					(start 339.65515 -285.563056)
					(mid 339.583161 -285.490897)
					(end 339.484716 -285.464504)
				)
				(arc
					(start 339.484716 -285.464504)
					(mid 339.345522 -285.52216)
					(end 339.287866 -285.661354)
				)
				(arc
					(start 339.287866 -285.661354)
					(mid 339.294623 -285.712235)
					(end 339.314282 -285.759652)
				)
				(arc
					(start 339.784182 -286.573722)
					(mid 339.856171 -286.645881)
					(end 339.954616 -286.672274)
				)
				(arc
					(start 339.954616 -286.672274)
					(mid 340.09381 -286.614618)
					(end 340.151466 -286.475424)
				)
				(arc
					(start 340.151466 -286.475424)
					(mid 340.144709 -286.424543)
					(end 340.12505 -286.377126)
				)
			)
		)
	)
	(zone
		(layers "F.Cu" "B.Cu" "In1.Cu" "In2.Cu" "In3.Cu" "In4.Cu" "In5.Cu" "In6.Cu"
			"In7.Cu" "In8.Cu" "In9.Cu" "In10.Cu" "In11.Cu" "In12.Cu" "In13.Cu" "In14.Cu"
			"In15.Cu" "In16.Cu"
		)
		(hatch none 0.5)
		(connect_pads
			(clearance 0)
		)
		(min_thickness 0.25)
		(keepout
			(tracks not_allowed)
			(vias allowed)
			(pads allowed)
			(copperpour not_allowed)
			(footprints allowed)
		)
		(placement
			(enabled no)
			(sheetname "")
		)
		(fill
			(thermal_gap 0.5)
			(thermal_bridge_width 0.5)
			(island_removal_mode 0)
		)
		(polygon
			(pts
				(arc
					(start 359.43921 -223.575626)
					(mid 358.78135 -223.575626)
					(end 359.43921 -223.575626)
				)
			)
		)
	)
	(zone
		(layers "F.Cu" "B.Cu" "In1.Cu" "In2.Cu" "In3.Cu" "In4.Cu" "In5.Cu" "In6.Cu"
			"In7.Cu" "In8.Cu" "In9.Cu" "In10.Cu" "In11.Cu" "In12.Cu" "In13.Cu" "In14.Cu"
			"In15.Cu" "In16.Cu"
		)
		(hatch none 0.5)
		(connect_pads
			(clearance 0)
		)
		(min_thickness 0.25)
		(keepout
			(tracks not_allowed)
			(vias allowed)
			(pads allowed)
			(copperpour not_allowed)
			(footprints allowed)
		)
		(placement
			(enabled no)
			(sheetname "")
		)
		(fill
			(thermal_gap 0.5)
			(thermal_bridge_width 0.5)
			(island_removal_mode 0)
		)
		(polygon
			(pts
				(arc
					(start 361.160314 -223.67367)
					(mid 361.179998 -223.62626)
					(end 361.18673 -223.575372)
				)
				(arc
					(start 361.18673 -223.575372)
					(mid 361.129074 -223.436178)
					(end 360.98988 -223.378522)
				)
				(arc
					(start 360.98988 -223.378522)
					(mid 360.891449 -223.404938)
					(end 360.819446 -223.477074)
				)
				(arc
					(start 360.3498 -224.291144)
					(mid 360.330116 -224.338554)
					(end 360.323384 -224.389442)
				)
				(arc
					(start 360.323384 -224.389442)
					(mid 360.38104 -224.528636)
					(end 360.520234 -224.586292)
				)
				(arc
					(start 360.520234 -224.586292)
					(mid 360.618665 -224.559876)
					(end 360.690668 -224.48774)
				)
			)
		)
	)
	(zone
		(layers "F.Cu" "B.Cu" "In1.Cu" "In2.Cu" "In3.Cu" "In4.Cu" "In5.Cu" "In6.Cu"
			"In7.Cu" "In8.Cu" "In9.Cu" "In10.Cu" "In11.Cu" "In12.Cu" "In13.Cu" "In14.Cu"
			"In15.Cu" "In16.Cu"
		)
		(hatch none 0.5)
		(connect_pads
			(clearance 0)
		)
		(min_thickness 0.25)
		(keepout
			(tracks not_allowed)
			(vias allowed)
			(pads allowed)
			(copperpour not_allowed)
			(footprints allowed)
		)
		(placement
			(enabled no)
			(sheetname "")
		)
		(fill
			(thermal_gap 0.5)
			(thermal_bridge_width 0.5)
			(island_removal_mode 0)
		)
		(polygon
			(pts
				(arc
					(start 91.293696 -221.133924)
					(mid 90.635836 -221.133924)
					(end 91.293696 -221.133924)
				)
			)
		)
	)
	(zone
		(layers "F.Cu" "B.Cu" "In1.Cu" "In2.Cu" "In3.Cu" "In4.Cu" "In5.Cu" "In6.Cu"
			"In7.Cu" "In8.Cu" "In9.Cu" "In10.Cu" "In11.Cu" "In12.Cu" "In13.Cu" "In14.Cu"
			"In15.Cu" "In16.Cu"
		)
		(hatch none 0.5)
		(connect_pads
			(clearance 0)
		)
		(min_thickness 0.25)
		(keepout
			(tracks not_allowed)
			(vias allowed)
			(pads allowed)
			(copperpour not_allowed)
			(footprints allowed)
		)
		(placement
			(enabled no)
			(sheetname "")
		)
		(fill
			(thermal_gap 0.5)
			(thermal_bridge_width 0.5)
			(island_removal_mode 0)
		)
		(polygon
			(pts
				(arc
					(start 369.77701 -225.203258)
					(mid 369.11915 -225.203258)
					(end 369.77701 -225.203258)
				)
			)
		)
	)
	(zone
		(layers "F.Cu" "B.Cu" "In1.Cu" "In2.Cu" "In3.Cu" "In4.Cu" "In5.Cu" "In6.Cu"
			"In7.Cu" "In8.Cu" "In9.Cu" "In10.Cu" "In11.Cu" "In12.Cu" "In13.Cu" "In14.Cu"
			"In15.Cu" "In16.Cu"
		)
		(hatch none 0.5)
		(connect_pads
			(clearance 0)
		)
		(min_thickness 0.25)
		(keepout
			(tracks not_allowed)
			(vias allowed)
			(pads allowed)
			(copperpour not_allowed)
			(footprints allowed)
		)
		(placement
			(enabled no)
			(sheetname "")
		)
		(fill
			(thermal_gap 0.5)
			(thermal_bridge_width 0.5)
			(island_removal_mode 0)
		)
		(polygon
			(pts
				(arc
					(start 314.516008 -409.649168)
					(mid 314.135008 -410.030168)
					(end 314.516008 -410.411168)
				)
				(arc
					(start 315.379608 -410.411168)
					(mid 315.760608 -410.030168)
					(end 315.379608 -409.649168)
				)
			)
		)
	)
	(zone
		(layers "F.Cu" "B.Cu" "In1.Cu" "In2.Cu" "In3.Cu" "In4.Cu" "In5.Cu" "In6.Cu"
			"In7.Cu" "In8.Cu" "In9.Cu" "In10.Cu" "In11.Cu" "In12.Cu" "In13.Cu" "In14.Cu"
			"In15.Cu" "In16.Cu"
		)
		(hatch none 0.5)
		(connect_pads
			(clearance 0)
		)
		(min_thickness 0.25)
		(keepout
			(tracks not_allowed)
			(vias allowed)
			(pads allowed)
			(copperpour not_allowed)
			(footprints allowed)
		)
		(placement
			(enabled no)
			(sheetname "")
		)
		(fill
			(thermal_gap 0.5)
			(thermal_bridge_width 0.5)
			(island_removal_mode 0)
		)
		(polygon
			(pts
				(arc
					(start 128.257554 -220.22181)
					(mid 128.185565 -220.149651)
					(end 128.08712 -220.123258)
				)
				(arc
					(start 128.08712 -220.123258)
					(mid 127.947926 -220.180914)
					(end 127.89027 -220.320108)
				)
				(arc
					(start 127.89027 -220.320108)
					(mid 127.897027 -220.370989)
					(end 127.916686 -220.418406)
				)
				(arc
					(start 128.386332 -221.232222)
					(mid 128.458321 -221.304381)
					(end 128.556766 -221.330774)
				)
				(arc
					(start 128.556766 -221.330774)
					(mid 128.69596 -221.273118)
					(end 128.753616 -221.133924)
				)
				(arc
					(start 128.753616 -221.133924)
					(mid 128.746859 -221.083043)
					(end 128.7272 -221.035626)
				)
			)
		)
	)
	(zone
		(layers "F.Cu" "B.Cu" "In1.Cu" "In2.Cu" "In3.Cu" "In4.Cu" "In5.Cu" "In6.Cu"
			"In7.Cu" "In8.Cu" "In9.Cu" "In10.Cu" "In11.Cu" "In12.Cu" "In13.Cu" "In14.Cu"
			"In15.Cu" "In16.Cu"
		)
		(hatch none 0.5)
		(connect_pads
			(clearance 0)
		)
		(min_thickness 0.25)
		(keepout
			(tracks not_allowed)
			(vias allowed)
			(pads allowed)
			(copperpour not_allowed)
			(footprints allowed)
		)
		(placement
			(enabled no)
			(sheetname "")
		)
		(fill
			(thermal_gap 0.5)
			(thermal_bridge_width 0.5)
			(island_removal_mode 0)
		)
		(polygon
			(pts
				(arc
					(start 354.350828 -277.424134)
					(mid 354.331144 -277.471544)
					(end 354.324412 -277.522432)
				)
				(arc
					(start 354.324412 -277.522432)
					(mid 354.382068 -277.661626)
					(end 354.521262 -277.719282)
				)
				(arc
					(start 354.521262 -277.719282)
					(mid 354.619693 -277.692866)
					(end 354.691696 -277.62073)
				)
				(arc
					(start 355.161596 -276.80666)
					(mid 355.18128 -276.75925)
					(end 355.188012 -276.708362)
				)
				(arc
					(start 355.188012 -276.708362)
					(mid 355.130356 -276.569168)
					(end 354.991162 -276.511512)
				)
				(arc
					(start 354.991162 -276.511512)
					(mid 354.892731 -276.537928)
					(end 354.820728 -276.610064)
				)
			)
		)
	)
	(zone
		(layers "F.Cu" "B.Cu" "In1.Cu" "In2.Cu" "In3.Cu" "In4.Cu" "In5.Cu" "In6.Cu"
			"In7.Cu" "In8.Cu" "In9.Cu" "In10.Cu" "In11.Cu" "In12.Cu" "In13.Cu" "In14.Cu"
			"In15.Cu" "In16.Cu"
		)
		(hatch none 0.5)
		(connect_pads
			(clearance 0)
		)
		(min_thickness 0.25)
		(keepout
			(tracks not_allowed)
			(vias allowed)
			(pads allowed)
			(copperpour not_allowed)
			(footprints allowed)
		)
		(placement
			(enabled no)
			(sheetname "")
		)
		(fill
			(thermal_gap 0.5)
			(thermal_bridge_width 0.5)
			(island_removal_mode 0)
		)
		(polygon
			(pts
				(arc
					(start 123.058682 -215.436704)
					(mid 123.716542 -215.436704)
					(end 123.058682 -215.436704)
				)
			)
		)
	)
	(zone
		(layers "F.Cu" "B.Cu" "In1.Cu" "In2.Cu" "In3.Cu" "In4.Cu" "In5.Cu" "In6.Cu"
			"In7.Cu" "In8.Cu" "In9.Cu" "In10.Cu" "In11.Cu" "In12.Cu" "In13.Cu" "In14.Cu"
			"In15.Cu" "In16.Cu"
		)
		(hatch none 0.5)
		(connect_pads
			(clearance 0)
		)
		(min_thickness 0.25)
		(keepout
			(tracks not_allowed)
			(vias allowed)
			(pads allowed)
			(copperpour not_allowed)
			(footprints allowed)
		)
		(placement
			(enabled no)
			(sheetname "")
		)
		(fill
			(thermal_gap 0.5)
			(thermal_bridge_width 0.5)
			(island_removal_mode 0)
		)
		(polygon
			(pts
				(arc
					(start 370.71681 -217.064336)
					(mid 370.05895 -217.064336)
					(end 370.71681 -217.064336)
				)
			)
		)
	)
	(zone
		(layers "F.Cu" "B.Cu" "In1.Cu" "In2.Cu" "In3.Cu" "In4.Cu" "In5.Cu" "In6.Cu"
			"In7.Cu" "In8.Cu" "In9.Cu" "In10.Cu" "In11.Cu" "In12.Cu" "In13.Cu" "In14.Cu"
			"In15.Cu" "In16.Cu"
		)
		(hatch none 0.5)
		(connect_pads
			(clearance 0)
		)
		(min_thickness 0.25)
		(keepout
			(tracks not_allowed)
			(vias allowed)
			(pads allowed)
			(copperpour not_allowed)
			(footprints allowed)
		)
		(placement
			(enabled no)
			(sheetname "")
		)
		(fill
			(thermal_gap 0.5)
			(thermal_bridge_width 0.5)
			(island_removal_mode 0)
		)
		(polygon
			(pts
				(arc
					(start 305.326288 -409.649168)
					(mid 304.945288 -410.030168)
					(end 305.326288 -410.411168)
				)
				(arc
					(start 306.189888 -410.411168)
					(mid 306.570888 -410.030168)
					(end 306.189888 -409.649168)
				)
			)
		)
	)
	(zone
		(layers "F.Cu" "B.Cu" "In1.Cu" "In2.Cu" "In3.Cu" "In4.Cu" "In5.Cu" "In6.Cu"
			"In7.Cu" "In8.Cu" "In9.Cu" "In10.Cu" "In11.Cu" "In12.Cu" "In13.Cu" "In14.Cu"
			"In15.Cu" "In16.Cu"
		)
		(hatch none 0.5)
		(connect_pads
			(clearance 0)
		)
		(min_thickness 0.25)
		(keepout
			(tracks not_allowed)
			(vias allowed)
			(pads allowed)
			(copperpour not_allowed)
			(footprints allowed)
		)
		(placement
			(enabled no)
			(sheetname "")
		)
		(fill
			(thermal_gap 0.5)
			(thermal_bridge_width 0.5)
			(island_removal_mode 0)
		)
		(polygon
			(pts
				(arc
					(start 381.99441 -217.064336)
					(mid 381.33655 -217.064336)
					(end 381.99441 -217.064336)
				)
			)
		)
	)
	(zone
		(layers "F.Cu" "B.Cu" "In1.Cu" "In2.Cu" "In3.Cu" "In4.Cu" "In5.Cu" "In6.Cu"
			"In7.Cu" "In8.Cu" "In9.Cu" "In10.Cu" "In11.Cu" "In12.Cu" "In13.Cu" "In14.Cu"
			"In15.Cu" "In16.Cu"
		)
		(hatch none 0.5)
		(connect_pads
			(clearance 0)
		)
		(min_thickness 0.25)
		(keepout
			(tracks not_allowed)
			(vias allowed)
			(pads allowed)
			(copperpour not_allowed)
			(footprints allowed)
		)
		(placement
			(enabled no)
			(sheetname "")
		)
		(fill
			(thermal_gap 0.5)
			(thermal_bridge_width 0.5)
			(island_removal_mode 0)
		)
		(polygon
			(pts
				(arc
					(start 339.087968 -206.024988)
					(mid 334.641952 -206.024988)
					(end 339.087968 -206.024988)
				)
			)
		)
	)
	(zone
		(layers "F.Cu" "B.Cu" "In1.Cu" "In2.Cu" "In3.Cu" "In4.Cu" "In5.Cu" "In6.Cu"
			"In7.Cu" "In8.Cu" "In9.Cu" "In10.Cu" "In11.Cu" "In12.Cu" "In13.Cu" "In14.Cu"
			"In15.Cu" "In16.Cu"
		)
		(hatch none 0.5)
		(connect_pads
			(clearance 0)
		)
		(min_thickness 0.25)
		(keepout
			(tracks not_allowed)
			(vias allowed)
			(pads allowed)
			(copperpour not_allowed)
			(footprints allowed)
		)
		(placement
			(enabled no)
			(sheetname "")
		)
		(fill
			(thermal_gap 0.5)
			(thermal_bridge_width 0.5)
			(island_removal_mode 0)
		)
		(polygon
			(pts
				(arc
					(start 102.052882 -279.051766)
					(mid 101.980893 -278.979607)
					(end 101.882448 -278.953214)
				)
				(arc
					(start 101.882448 -278.953214)
					(mid 101.743254 -279.01087)
					(end 101.685598 -279.150064)
				)
				(arc
					(start 101.685598 -279.150064)
					(mid 101.692355 -279.200945)
					(end 101.712014 -279.248362)
				)
				(arc
					(start 102.181914 -280.062432)
					(mid 102.253903 -280.134591)
					(end 102.352348 -280.160984)
				)
				(arc
					(start 102.352348 -280.160984)
					(mid 102.491542 -280.103328)
					(end 102.549198 -279.964134)
				)
				(arc
					(start 102.549198 -279.964134)
					(mid 102.542441 -279.913253)
					(end 102.522782 -279.865836)
				)
			)
		)
	)
	(zone
		(layers "F.Cu" "B.Cu" "In1.Cu" "In2.Cu" "In3.Cu" "In4.Cu" "In5.Cu" "In6.Cu"
			"In7.Cu" "In8.Cu" "In9.Cu" "In10.Cu" "In11.Cu" "In12.Cu" "In13.Cu" "In14.Cu"
			"In15.Cu" "In16.Cu"
		)
		(hatch none 0.5)
		(connect_pads
			(clearance 0)
		)
		(min_thickness 0.25)
		(keepout
			(tracks not_allowed)
			(vias allowed)
			(pads allowed)
			(copperpour not_allowed)
			(footprints allowed)
		)
		(placement
			(enabled no)
			(sheetname "")
		)
		(fill
			(thermal_gap 0.5)
			(thermal_bridge_width 0.5)
			(island_removal_mode 0)
		)
		(polygon
			(pts
				(arc
					(start 366.95761 -223.575626)
					(mid 366.29975 -223.575626)
					(end 366.95761 -223.575626)
				)
			)
		)
	)
	(zone
		(layers "F.Cu" "B.Cu" "In1.Cu" "In2.Cu" "In3.Cu" "In4.Cu" "In5.Cu" "In6.Cu"
			"In7.Cu" "In8.Cu" "In9.Cu" "In10.Cu" "In11.Cu" "In12.Cu" "In13.Cu" "In14.Cu"
			"In15.Cu" "In16.Cu"
		)
		(hatch none 0.5)
		(connect_pads
			(clearance 0)
		)
		(min_thickness 0.25)
		(keepout
			(tracks not_allowed)
			(vias allowed)
			(pads allowed)
			(copperpour not_allowed)
			(footprints allowed)
		)
		(placement
			(enabled no)
			(sheetname "")
		)
		(fill
			(thermal_gap 0.5)
			(thermal_bridge_width 0.5)
			(island_removal_mode 0)
		)
		(polygon
			(pts
				(arc
					(start 107.270296 -224.389442)
					(mid 106.612436 -224.389442)
					(end 107.270296 -224.389442)
				)
			)
		)
	)
	(zone
		(layers "F.Cu" "B.Cu" "In1.Cu" "In2.Cu" "In3.Cu" "In4.Cu" "In5.Cu" "In6.Cu"
			"In7.Cu" "In8.Cu" "In9.Cu" "In10.Cu" "In11.Cu" "In12.Cu" "In13.Cu" "In14.Cu"
			"In15.Cu" "In16.Cu"
		)
		(hatch none 0.5)
		(connect_pads
			(clearance 0)
		)
		(min_thickness 0.25)
		(keepout
			(tracks not_allowed)
			(vias allowed)
			(pads allowed)
			(copperpour not_allowed)
			(footprints allowed)
		)
		(placement
			(enabled no)
			(sheetname "")
		)
		(fill
			(thermal_gap 0.5)
			(thermal_bridge_width 0.5)
			(island_removal_mode 0)
		)
		(polygon
			(pts
				(arc
					(start 373.53621 -225.203258)
					(mid 372.87835 -225.203258)
					(end 373.53621 -225.203258)
				)
			)
		)
	)
	(zone
		(layers "F.Cu" "B.Cu" "In1.Cu" "In2.Cu" "In3.Cu" "In4.Cu" "In5.Cu" "In6.Cu"
			"In7.Cu" "In8.Cu" "In9.Cu" "In10.Cu" "In11.Cu" "In12.Cu" "In13.Cu" "In14.Cu"
			"In15.Cu" "In16.Cu"
		)
		(hatch none 0.5)
		(connect_pads
			(clearance 0)
		)
		(min_thickness 0.25)
		(keepout
			(tracks not_allowed)
			(vias allowed)
			(pads allowed)
			(copperpour not_allowed)
			(footprints allowed)
		)
		(placement
			(enabled no)
			(sheetname "")
		)
		(fill
			(thermal_gap 0.5)
			(thermal_bridge_width 0.5)
			(island_removal_mode 0)
		)
		(polygon
			(pts
				(arc
					(start 356.729792 -277.522432)
					(mid 356.071932 -277.522432)
					(end 356.729792 -277.522432)
				)
			)
		)
	)
	(zone
		(layers "F.Cu" "B.Cu" "In1.Cu" "In2.Cu" "In3.Cu" "In4.Cu" "In5.Cu" "In6.Cu"
			"In7.Cu" "In8.Cu" "In9.Cu" "In10.Cu" "In11.Cu" "In12.Cu" "In13.Cu" "In14.Cu"
			"In15.Cu" "In16.Cu"
		)
		(hatch none 0.5)
		(connect_pads
			(clearance 0)
		)
		(min_thickness 0.25)
		(keepout
			(tracks not_allowed)
			(vias allowed)
			(pads allowed)
			(copperpour not_allowed)
			(footprints allowed)
		)
		(placement
			(enabled no)
			(sheetname "")
		)
		(fill
			(thermal_gap 0.5)
			(thermal_bridge_width 0.5)
			(island_removal_mode 0)
		)
		(polygon
			(pts
				(arc
					(start 348.657672 -179.757832)
					(mid 348.806462 -180.117042)
					(end 349.165672 -180.265832)
				)
				(arc
					(start 349.16618 -180.265832)
					(mid 349.297389 -180.248595)
					(end 349.419672 -180.198014)
				)
				(arc
					(start 350.343724 -179.66436)
					(mid 350.529657 -179.478424)
					(end 350.597724 -179.224432)
				)
				(arc
					(start 350.597724 -179.224432)
					(mid 350.448934 -178.865222)
					(end 350.089724 -178.716432)
				)
				(arc
					(start 350.089216 -178.716432)
					(mid 349.958007 -178.733669)
					(end 349.835724 -178.78425)
				)
				(arc
					(start 348.911672 -179.317904)
					(mid 348.725739 -179.50384)
					(end 348.657672 -179.757832)
				)
			)
		)
	)
	(zone
		(layers "F.Cu" "B.Cu" "In1.Cu" "In2.Cu" "In3.Cu" "In4.Cu" "In5.Cu" "In6.Cu"
			"In7.Cu" "In8.Cu" "In9.Cu" "In10.Cu" "In11.Cu" "In12.Cu" "In13.Cu" "In14.Cu"
			"In15.Cu" "In16.Cu"
		)
		(hatch none 0.5)
		(connect_pads
			(clearance 0)
		)
		(min_thickness 0.25)
		(keepout
			(tracks not_allowed)
			(vias allowed)
			(pads allowed)
			(copperpour not_allowed)
			(footprints allowed)
		)
		(placement
			(enabled no)
			(sheetname "")
		)
		(fill
			(thermal_gap 0.5)
			(thermal_bridge_width 0.5)
			(island_removal_mode 0)
		)
		(polygon
			(pts
				(arc
					(start 328.486008 -400.477228)
					(mid 328.105008 -400.858228)
					(end 328.486008 -401.239228)
				)
				(arc
					(start 329.349608 -401.239228)
					(mid 329.730608 -400.858228)
					(end 329.349608 -400.477228)
				)
			)
		)
	)
	(zone
		(layers "F.Cu" "B.Cu" "In1.Cu" "In2.Cu" "In3.Cu" "In4.Cu" "In5.Cu" "In6.Cu"
			"In7.Cu" "In8.Cu" "In9.Cu" "In10.Cu" "In11.Cu" "In12.Cu" "In13.Cu" "In14.Cu"
			"In15.Cu" "In16.Cu"
		)
		(hatch none 0.5)
		(connect_pads
			(clearance 0)
		)
		(min_thickness 0.25)
		(keepout
			(tracks not_allowed)
			(vias allowed)
			(pads allowed)
			(copperpour not_allowed)
			(footprints allowed)
		)
		(placement
			(enabled no)
			(sheetname "")
		)
		(fill
			(thermal_gap 0.5)
			(thermal_bridge_width 0.5)
			(island_removal_mode 0)
		)
		(polygon
			(pts
				(arc
					(start 139.880594 -409.649168)
					(mid 139.499594 -410.030168)
					(end 139.880594 -410.411168)
				)
				(arc
					(start 140.744194 -410.411168)
					(mid 141.125194 -410.030168)
					(end 140.744194 -409.649168)
				)
			)
		)
	)
	(zone
		(layers "F.Cu" "B.Cu" "In1.Cu" "In2.Cu" "In3.Cu" "In4.Cu" "In5.Cu" "In6.Cu"
			"In7.Cu" "In8.Cu" "In9.Cu" "In10.Cu" "In11.Cu" "In12.Cu" "In13.Cu" "In14.Cu"
			"In15.Cu" "In16.Cu"
		)
		(hatch none 0.5)
		(connect_pads
			(clearance 0)
		)
		(min_thickness 0.25)
		(keepout
			(tracks not_allowed)
			(vias allowed)
			(pads allowed)
			(copperpour not_allowed)
			(footprints allowed)
		)
		(placement
			(enabled no)
			(sheetname "")
		)
		(fill
			(thermal_gap 0.5)
			(thermal_bridge_width 0.5)
			(island_removal_mode 0)
		)
		(polygon
			(pts
				(arc
					(start 102.681278 -284.847538)
					(mid 102.023418 -284.847538)
					(end 102.681278 -284.847538)
				)
			)
		)
	)
	(zone
		(layers "F.Cu" "B.Cu" "In1.Cu" "In2.Cu" "In3.Cu" "In4.Cu" "In5.Cu" "In6.Cu"
			"In7.Cu" "In8.Cu" "In9.Cu" "In10.Cu" "In11.Cu" "In12.Cu" "In13.Cu" "In14.Cu"
			"In15.Cu" "In16.Cu"
		)
		(hatch none 0.5)
		(connect_pads
			(clearance 0)
		)
		(min_thickness 0.25)
		(keepout
			(tracks not_allowed)
			(vias allowed)
			(pads allowed)
			(copperpour not_allowed)
			(footprints allowed)
		)
		(placement
			(enabled no)
			(sheetname "")
		)
		(fill
			(thermal_gap 0.5)
			(thermal_bridge_width 0.5)
			(island_removal_mode 0)
		)
		(polygon
			(pts
				(arc
					(start 381.164846 -288.917126)
					(mid 380.506986 -288.917126)
					(end 381.164846 -288.917126)
				)
			)
		)
	)
	(zone
		(layers "F.Cu" "B.Cu" "In1.Cu" "In2.Cu" "In3.Cu" "In4.Cu" "In5.Cu" "In6.Cu"
			"In7.Cu" "In8.Cu" "In9.Cu" "In10.Cu" "In11.Cu" "In12.Cu" "In13.Cu" "In14.Cu"
			"In15.Cu" "In16.Cu"
		)
		(hatch none 0.5)
		(connect_pads
			(clearance 0)
		)
		(min_thickness 0.25)
		(keepout
			(tracks not_allowed)
			(vias allowed)
			(pads allowed)
			(copperpour not_allowed)
			(footprints allowed)
		)
		(placement
			(enabled no)
			(sheetname "")
		)
		(fill
			(thermal_gap 0.5)
			(thermal_bridge_width 0.5)
			(island_removal_mode 0)
		)
		(polygon
			(pts
				(arc
					(start 326.768968 -409.649168)
					(mid 326.387968 -410.030168)
					(end 326.768968 -410.411168)
				)
				(arc
					(start 327.632568 -410.411168)
					(mid 328.013568 -410.030168)
					(end 327.632568 -409.649168)
				)
			)
		)
	)
	(zone
		(layers "F.Cu" "B.Cu" "In1.Cu" "In2.Cu" "In3.Cu" "In4.Cu" "In5.Cu" "In6.Cu"
			"In7.Cu" "In8.Cu" "In9.Cu" "In10.Cu" "In11.Cu" "In12.Cu" "In13.Cu" "In14.Cu"
			"In15.Cu" "In16.Cu"
		)
		(hatch none 0.5)
		(connect_pads
			(clearance 0)
		)
		(min_thickness 0.25)
		(keepout
			(tracks not_allowed)
			(vias allowed)
			(pads allowed)
			(copperpour not_allowed)
			(footprints allowed)
		)
		(placement
			(enabled no)
			(sheetname "")
		)
		(fill
			(thermal_gap 0.5)
			(thermal_bridge_width 0.5)
			(island_removal_mode 0)
		)
		(polygon
			(pts
				(arc
					(start 426.703236 -18.744438)
					(mid 426.322236 -19.125438)
					(end 426.703236 -19.506438)
				)
				(arc
					(start 427.566836 -19.506438)
					(mid 427.947836 -19.125438)
					(end 427.566836 -18.744438)
				)
			)
		)
	)
	(zone
		(layers "F.Cu" "B.Cu" "In1.Cu" "In2.Cu" "In3.Cu" "In4.Cu" "In5.Cu" "In6.Cu"
			"In7.Cu" "In8.Cu" "In9.Cu" "In10.Cu" "In11.Cu" "In12.Cu" "In13.Cu" "In14.Cu"
			"In15.Cu" "In16.Cu"
		)
		(hatch none 0.5)
		(connect_pads
			(clearance 0)
		)
		(min_thickness 0.25)
		(keepout
			(tracks not_allowed)
			(vias allowed)
			(pads allowed)
			(copperpour not_allowed)
			(footprints allowed)
		)
		(placement
			(enabled no)
			(sheetname "")
		)
		(fill
			(thermal_gap 0.5)
			(thermal_bridge_width 0.5)
			(island_removal_mode 0)
		)
		(polygon
			(pts
				(arc
					(start 104.450896 -224.389442)
					(mid 103.793036 -224.389442)
					(end 104.450896 -224.389442)
				)
			)
		)
	)
	(zone
		(layers "F.Cu" "B.Cu" "In1.Cu" "In2.Cu" "In3.Cu" "In4.Cu" "In5.Cu" "In6.Cu"
			"In7.Cu" "In8.Cu" "In9.Cu" "In10.Cu" "In11.Cu" "In12.Cu" "In13.Cu" "In14.Cu"
			"In15.Cu" "In16.Cu"
		)
		(hatch none 0.5)
		(connect_pads
			(clearance 0)
		)
		(min_thickness 0.25)
		(keepout
			(tracks not_allowed)
			(vias allowed)
			(pads allowed)
			(copperpour not_allowed)
			(footprints allowed)
		)
		(placement
			(enabled no)
			(sheetname "")
		)
		(fill
			(thermal_gap 0.5)
			(thermal_bridge_width 0.5)
			(island_removal_mode 0)
		)
		(polygon
			(pts
				(arc
					(start 101.631496 -224.389442)
					(mid 100.973636 -224.389442)
					(end 101.631496 -224.389442)
				)
			)
		)
	)
	(zone
		(layers "F.Cu" "B.Cu" "In1.Cu" "In2.Cu" "In3.Cu" "In4.Cu" "In5.Cu" "In6.Cu"
			"In7.Cu" "In8.Cu" "In9.Cu" "In10.Cu" "In11.Cu" "In12.Cu" "In13.Cu" "In14.Cu"
			"In15.Cu" "In16.Cu"
		)
		(hatch none 0.5)
		(connect_pads
			(clearance 0)
		)
		(min_thickness 0.25)
		(keepout
			(tracks not_allowed)
			(vias allowed)
			(pads allowed)
			(copperpour not_allowed)
			(footprints allowed)
		)
		(placement
			(enabled no)
			(sheetname "")
		)
		(fill
			(thermal_gap 0.5)
			(thermal_bridge_width 0.5)
			(island_removal_mode 0)
		)
		(polygon
			(pts
				(arc
					(start 168.539922 -10.624312)
					(mid 168.158922 -11.005312)
					(end 168.539922 -11.386312)
				)
				(arc
					(start 169.403522 -11.386312)
					(mid 169.784522 -11.005312)
					(end 169.403522 -10.624312)
				)
			)
		)
	)
	(zone
		(layers "F.Cu" "B.Cu" "In1.Cu" "In2.Cu" "In3.Cu" "In4.Cu" "In5.Cu" "In6.Cu"
			"In7.Cu" "In8.Cu" "In9.Cu" "In10.Cu" "In11.Cu" "In12.Cu" "In13.Cu" "In14.Cu"
			"In15.Cu" "In16.Cu"
		)
		(hatch none 0.5)
		(connect_pads
			(clearance 0)
		)
		(min_thickness 0.25)
		(keepout
			(tracks not_allowed)
			(vias allowed)
			(pads allowed)
			(copperpour not_allowed)
			(footprints allowed)
		)
		(placement
			(enabled no)
			(sheetname "")
		)
		(fill
			(thermal_gap 0.5)
			(thermal_bridge_width 0.5)
			(island_removal_mode 0)
		)
		(polygon
			(pts
				(arc
					(start 104.262682 -215.436704)
					(mid 104.920542 -215.436704)
					(end 104.262682 -215.436704)
				)
			)
		)
	)
	(zone
		(layers "F.Cu" "B.Cu" "In1.Cu" "In2.Cu" "In3.Cu" "In4.Cu" "In5.Cu" "In6.Cu"
			"In7.Cu" "In8.Cu" "In9.Cu" "In10.Cu" "In11.Cu" "In12.Cu" "In13.Cu" "In14.Cu"
			"In15.Cu" "In16.Cu"
		)
		(hatch none 0.5)
		(connect_pads
			(clearance 0)
		)
		(min_thickness 0.25)
		(keepout
			(tracks not_allowed)
			(vias allowed)
			(pads allowed)
			(copperpour not_allowed)
			(footprints allowed)
		)
		(placement
			(enabled no)
			(sheetname "")
		)
		(fill
			(thermal_gap 0.5)
			(thermal_bridge_width 0.5)
			(island_removal_mode 0)
		)
		(polygon
			(pts
				(arc
					(start 361.788964 -224.389442)
					(mid 361.131104 -224.389442)
					(end 361.788964 -224.389442)
				)
			)
		)
	)
	(zone
		(layers "F.Cu" "B.Cu" "In1.Cu" "In2.Cu" "In3.Cu" "In4.Cu" "In5.Cu" "In6.Cu"
			"In7.Cu" "In8.Cu" "In9.Cu" "In10.Cu" "In11.Cu" "In12.Cu" "In13.Cu" "In14.Cu"
			"In15.Cu" "In16.Cu"
		)
		(hatch none 0.5)
		(connect_pads
			(clearance 0)
		)
		(min_thickness 0.25)
		(keepout
			(tracks not_allowed)
			(vias allowed)
			(pads allowed)
			(copperpour not_allowed)
			(footprints allowed)
		)
		(placement
			(enabled no)
			(sheetname "")
		)
		(fill
			(thermal_gap 0.5)
			(thermal_bridge_width 0.5)
			(island_removal_mode 0)
		)
		(polygon
			(pts
				(arc
					(start 113.660682 -215.436704)
					(mid 114.318542 -215.436704)
					(end 113.660682 -215.436704)
				)
			)
		)
	)
	(zone
		(layers "F.Cu" "B.Cu" "In1.Cu" "In2.Cu" "In3.Cu" "In4.Cu" "In5.Cu" "In6.Cu"
			"In7.Cu" "In8.Cu" "In9.Cu" "In10.Cu" "In11.Cu" "In12.Cu" "In13.Cu" "In14.Cu"
			"In15.Cu" "In16.Cu"
		)
		(hatch none 0.5)
		(connect_pads
			(clearance 0)
		)
		(min_thickness 0.25)
		(keepout
			(tracks not_allowed)
			(vias allowed)
			(pads allowed)
			(copperpour not_allowed)
			(footprints allowed)
		)
		(placement
			(enabled no)
			(sheetname "")
		)
		(fill
			(thermal_gap 0.5)
			(thermal_bridge_width 0.5)
			(island_removal_mode 0)
		)
		(polygon
			(pts
				(arc
					(start 355.521514 -223.67367)
					(mid 355.541198 -223.62626)
					(end 355.54793 -223.575372)
				)
				(arc
					(start 355.54793 -223.575372)
					(mid 355.490274 -223.436178)
					(end 355.35108 -223.378522)
				)
				(arc
					(start 355.35108 -223.378522)
					(mid 355.252649 -223.404938)
					(end 355.180646 -223.477074)
				)
				(arc
					(start 354.711 -224.291144)
					(mid 354.691316 -224.338554)
					(end 354.684584 -224.389442)
				)
				(arc
					(start 354.684584 -224.389442)
					(mid 354.74224 -224.528636)
					(end 354.881434 -224.586292)
				)
				(arc
					(start 354.881434 -224.586292)
					(mid 354.979865 -224.559876)
					(end 355.051868 -224.48774)
				)
			)
		)
	)
	(zone
		(layers "F.Cu" "B.Cu" "In1.Cu" "In2.Cu" "In3.Cu" "In4.Cu" "In5.Cu" "In6.Cu"
			"In7.Cu" "In8.Cu" "In9.Cu" "In10.Cu" "In11.Cu" "In12.Cu" "In13.Cu" "In14.Cu"
			"In15.Cu" "In16.Cu"
		)
		(hatch none 0.5)
		(connect_pads
			(clearance 0)
		)
		(min_thickness 0.25)
		(keepout
			(tracks not_allowed)
			(vias allowed)
			(pads allowed)
			(copperpour not_allowed)
			(footprints allowed)
		)
		(placement
			(enabled no)
			(sheetname "")
		)
		(fill
			(thermal_gap 0.5)
			(thermal_bridge_width 0.5)
			(island_removal_mode 0)
		)
		(polygon
			(pts
				(arc
					(start 347.691964 -217.878406)
					(mid 347.034104 -217.878406)
					(end 347.691964 -217.878406)
				)
			)
		)
	)
	(zone
		(layers "F.Cu" "B.Cu" "In1.Cu" "In2.Cu" "In3.Cu" "In4.Cu" "In5.Cu" "In6.Cu"
			"In7.Cu" "In8.Cu" "In9.Cu" "In10.Cu" "In11.Cu" "In12.Cu" "In13.Cu" "In14.Cu"
			"In15.Cu" "In16.Cu"
		)
		(hatch none 0.5)
		(connect_pads
			(clearance 0)
		)
		(min_thickness 0.25)
		(keepout
			(tracks not_allowed)
			(vias allowed)
			(pads allowed)
			(copperpour not_allowed)
			(footprints allowed)
		)
		(placement
			(enabled no)
			(sheetname "")
		)
		(fill
			(thermal_gap 0.5)
			(thermal_bridge_width 0.5)
			(island_removal_mode 0)
		)
		(polygon
			(pts
				(arc
					(start 344.982546 -284.847538)
					(mid 344.324686 -284.847538)
					(end 344.982546 -284.847538)
				)
			)
		)
	)
	(zone
		(layers "F.Cu" "B.Cu" "In1.Cu" "In2.Cu" "In3.Cu" "In4.Cu" "In5.Cu" "In6.Cu"
			"In7.Cu" "In8.Cu" "In9.Cu" "In10.Cu" "In11.Cu" "In12.Cu" "In13.Cu" "In14.Cu"
			"In15.Cu" "In16.Cu"
		)
		(hatch none 0.5)
		(connect_pads
			(clearance 0)
		)
		(min_thickness 0.25)
		(keepout
			(tracks not_allowed)
			(vias allowed)
			(pads allowed)
			(copperpour not_allowed)
			(footprints allowed)
		)
		(placement
			(enabled no)
			(sheetname "")
		)
		(fill
			(thermal_gap 0.5)
			(thermal_bridge_width 0.5)
			(island_removal_mode 0)
		)
		(polygon
			(pts
				(arc
					(start 343.46261 -218.692222)
					(mid 342.80475 -218.692222)
					(end 343.46261 -218.692222)
				)
			)
		)
	)
	(zone
		(layers "F.Cu" "B.Cu" "In1.Cu" "In2.Cu" "In3.Cu" "In4.Cu" "In5.Cu" "In6.Cu"
			"In7.Cu" "In8.Cu" "In9.Cu" "In10.Cu" "In11.Cu" "In12.Cu" "In13.Cu" "In14.Cu"
			"In15.Cu" "In16.Cu"
		)
		(hatch none 0.5)
		(connect_pads
			(clearance 0)
		)
		(min_thickness 0.25)
		(keepout
			(tracks not_allowed)
			(vias allowed)
			(pads allowed)
			(copperpour not_allowed)
			(footprints allowed)
		)
		(placement
			(enabled no)
			(sheetname "")
		)
		(fill
			(thermal_gap 0.5)
			(thermal_bridge_width 0.5)
			(island_removal_mode 0)
		)
		(polygon
			(pts
				(arc
					(start 338.605114 -217.162634)
					(mid 338.624798 -217.115224)
					(end 338.63153 -217.064336)
				)
				(arc
					(start 338.63153 -217.064336)
					(mid 338.573874 -216.925142)
					(end 338.43468 -216.867486)
				)
				(arc
					(start 338.43468 -216.867486)
					(mid 338.336249 -216.893902)
					(end 338.264246 -216.966038)
				)
				(arc
					(start 337.7946 -217.780108)
					(mid 337.774916 -217.827518)
					(end 337.768184 -217.878406)
				)
				(arc
					(start 337.768184 -217.878406)
					(mid 337.82584 -218.0176)
					(end 337.965034 -218.075256)
				)
				(arc
					(start 337.965034 -218.075256)
					(mid 338.063465 -218.04884)
					(end 338.135468 -217.976704)
				)
			)
		)
	)
	(zone
		(layers "F.Cu" "B.Cu" "In1.Cu" "In2.Cu" "In3.Cu" "In4.Cu" "In5.Cu" "In6.Cu"
			"In7.Cu" "In8.Cu" "In9.Cu" "In10.Cu" "In11.Cu" "In12.Cu" "In13.Cu" "In14.Cu"
			"In15.Cu" "In16.Cu"
		)
		(hatch none 0.5)
		(connect_pads
			(clearance 0)
		)
		(min_thickness 0.25)
		(keepout
			(tracks not_allowed)
			(vias allowed)
			(pads allowed)
			(copperpour not_allowed)
			(footprints allowed)
		)
		(placement
			(enabled no)
			(sheetname "")
		)
		(fill
			(thermal_gap 0.5)
			(thermal_bridge_width 0.5)
			(island_removal_mode 0)
		)
		(polygon
			(pts
				(arc
					(start 107.581446 -217.162634)
					(mid 107.60113 -217.115224)
					(end 107.607862 -217.064336)
				)
				(arc
					(start 107.607862 -217.064336)
					(mid 107.550206 -216.925142)
					(end 107.411012 -216.867486)
				)
				(arc
					(start 107.411012 -216.867486)
					(mid 107.312581 -216.893902)
					(end 107.240578 -216.966038)
				)
				(arc
					(start 106.770932 -217.780108)
					(mid 106.751248 -217.827518)
					(end 106.744516 -217.878406)
				)
				(arc
					(start 106.744516 -217.878406)
					(mid 106.802172 -218.0176)
					(end 106.941366 -218.075256)
				)
				(arc
					(start 106.941366 -218.075256)
					(mid 107.039797 -218.04884)
					(end 107.1118 -217.976704)
				)
			)
		)
	)
	(zone
		(layers "F.Cu" "B.Cu" "In1.Cu" "In2.Cu" "In3.Cu" "In4.Cu" "In5.Cu" "In6.Cu"
			"In7.Cu" "In8.Cu" "In9.Cu" "In10.Cu" "In11.Cu" "In12.Cu" "In13.Cu" "In14.Cu"
			"In15.Cu" "In16.Cu"
		)
		(hatch none 0.5)
		(connect_pads
			(clearance 0)
		)
		(min_thickness 0.25)
		(keepout
			(tracks not_allowed)
			(vias allowed)
			(pads allowed)
			(copperpour not_allowed)
			(footprints allowed)
		)
		(placement
			(enabled no)
			(sheetname "")
		)
		(fill
			(thermal_gap 0.5)
			(thermal_bridge_width 0.5)
			(island_removal_mode 0)
		)
		(polygon
			(pts
				(arc
					(start 352.232468 -224.291144)
					(mid 352.160479 -224.218985)
					(end 352.062034 -224.192592)
				)
				(arc
					(start 352.062034 -224.192592)
					(mid 351.92284 -224.250248)
					(end 351.865184 -224.389442)
				)
				(arc
					(start 351.865184 -224.389442)
					(mid 351.871941 -224.440323)
					(end 351.8916 -224.48774)
				)
				(arc
					(start 352.361246 -225.301556)
					(mid 352.433235 -225.373715)
					(end 352.53168 -225.400108)
				)
				(arc
					(start 352.53168 -225.400108)
					(mid 352.670874 -225.342452)
					(end 352.72853 -225.203258)
				)
				(arc
					(start 352.72853 -225.203258)
					(mid 352.721773 -225.152377)
					(end 352.702114 -225.10496)
				)
			)
		)
	)
	(zone
		(layers "F.Cu" "B.Cu" "In1.Cu" "In2.Cu" "In3.Cu" "In4.Cu" "In5.Cu" "In6.Cu"
			"In7.Cu" "In8.Cu" "In9.Cu" "In10.Cu" "In11.Cu" "In12.Cu" "In13.Cu" "In14.Cu"
			"In15.Cu" "In16.Cu"
		)
		(hatch none 0.5)
		(connect_pads
			(clearance 0)
		)
		(min_thickness 0.25)
		(keepout
			(tracks not_allowed)
			(vias allowed)
			(pads allowed)
			(copperpour not_allowed)
			(footprints allowed)
		)
		(placement
			(enabled no)
			(sheetname "")
		)
		(fill
			(thermal_gap 0.5)
			(thermal_bridge_width 0.5)
			(island_removal_mode 0)
		)
		(polygon
			(pts
				(arc
					(start 394.21181 -406.62352)
					(mid 393.83081 -407.00452)
					(end 394.21181 -407.38552)
				)
				(arc
					(start 395.07541 -407.38552)
					(mid 395.45641 -407.00452)
					(end 395.07541 -406.62352)
				)
			)
		)
	)
	(zone
		(layers "F.Cu" "B.Cu" "In1.Cu" "In2.Cu" "In3.Cu" "In4.Cu" "In5.Cu" "In6.Cu"
			"In7.Cu" "In8.Cu" "In9.Cu" "In10.Cu" "In11.Cu" "In12.Cu" "In13.Cu" "In14.Cu"
			"In15.Cu" "In16.Cu"
		)
		(hatch none 0.5)
		(connect_pads
			(clearance 0)
		)
		(min_thickness 0.25)
		(keepout
			(tracks not_allowed)
			(vias allowed)
			(pads allowed)
			(copperpour not_allowed)
			(footprints allowed)
		)
		(placement
			(enabled no)
			(sheetname "")
		)
		(fill
			(thermal_gap 0.5)
			(thermal_bridge_width 0.5)
			(island_removal_mode 0)
		)
		(polygon
			(pts
				(arc
					(start 380.61265 -400.477228)
					(mid 380.23165 -400.858228)
					(end 380.61265 -401.239228)
				)
				(arc
					(start 381.47625 -401.239228)
					(mid 381.85725 -400.858228)
					(end 381.47625 -400.477228)
				)
			)
		)
	)
	(zone
		(layers "F.Cu" "B.Cu" "In1.Cu" "In2.Cu" "In3.Cu" "In4.Cu" "In5.Cu" "In6.Cu"
			"In7.Cu" "In8.Cu" "In9.Cu" "In10.Cu" "In11.Cu" "In12.Cu" "In13.Cu" "In14.Cu"
			"In15.Cu" "In16.Cu"
		)
		(hatch none 0.5)
		(connect_pads
			(clearance 0)
		)
		(min_thickness 0.25)
		(keepout
			(tracks not_allowed)
			(vias allowed)
			(pads allowed)
			(copperpour not_allowed)
			(footprints allowed)
		)
		(placement
			(enabled no)
			(sheetname "")
		)
		(fill
			(thermal_gap 0.5)
			(thermal_bridge_width 0.5)
			(island_removal_mode 0)
		)
		(polygon
			(pts
				(arc
					(start 350.98101 -215.436704)
					(mid 350.32315 -215.436704)
					(end 350.98101 -215.436704)
				)
			)
		)
	)
	(zone
		(layers "F.Cu" "B.Cu" "In1.Cu" "In2.Cu" "In3.Cu" "In4.Cu" "In5.Cu" "In6.Cu"
			"In7.Cu" "In8.Cu" "In9.Cu" "In10.Cu" "In11.Cu" "In12.Cu" "In13.Cu" "In14.Cu"
			"In15.Cu" "In16.Cu"
		)
		(hatch none 0.5)
		(connect_pads
			(clearance 0)
		)
		(min_thickness 0.25)
		(keepout
			(tracks not_allowed)
			(vias allowed)
			(pads allowed)
			(copperpour not_allowed)
			(footprints allowed)
		)
		(placement
			(enabled no)
			(sheetname "")
		)
		(fill
			(thermal_gap 0.5)
			(thermal_bridge_width 0.5)
			(island_removal_mode 0)
		)
		(polygon
			(pts
				(arc
					(start 129.824988 -214.622634)
					(mid 129.167128 -214.622634)
					(end 129.824988 -214.622634)
				)
			)
		)
	)
	(zone
		(layers "F.Cu" "B.Cu" "In1.Cu" "In2.Cu" "In3.Cu" "In4.Cu" "In5.Cu" "In6.Cu"
			"In7.Cu" "In8.Cu" "In9.Cu" "In10.Cu" "In11.Cu" "In12.Cu" "In13.Cu" "In14.Cu"
			"In15.Cu" "In16.Cu"
		)
		(hatch none 0.5)
		(connect_pads
			(clearance 0)
		)
		(min_thickness 0.25)
		(keepout
			(tracks not_allowed)
			(vias allowed)
			(pads allowed)
			(copperpour not_allowed)
			(footprints allowed)
		)
		(placement
			(enabled no)
			(sheetname "")
		)
		(fill
			(thermal_gap 0.5)
			(thermal_bridge_width 0.5)
			(island_removal_mode 0)
		)
		(polygon
			(pts
				(arc
					(start 103.903018 -275.08073)
					(mid 104.560878 -275.08073)
					(end 103.903018 -275.08073)
				)
			)
		)
	)
	(zone
		(layers "F.Cu" "B.Cu" "In1.Cu" "In2.Cu" "In3.Cu" "In4.Cu" "In5.Cu" "In6.Cu"
			"In7.Cu" "In8.Cu" "In9.Cu" "In10.Cu" "In11.Cu" "In12.Cu" "In13.Cu" "In14.Cu"
			"In15.Cu" "In16.Cu"
		)
		(hatch none 0.5)
		(connect_pads
			(clearance 0)
		)
		(min_thickness 0.25)
		(keepout
			(tracks not_allowed)
			(vias allowed)
			(pads allowed)
			(copperpour not_allowed)
			(footprints allowed)
		)
		(placement
			(enabled no)
			(sheetname "")
		)
		(fill
			(thermal_gap 0.5)
			(thermal_bridge_width 0.5)
			(island_removal_mode 0)
		)
		(polygon
			(pts
				(arc
					(start 338.605114 -220.418152)
					(mid 338.624798 -220.370742)
					(end 338.63153 -220.319854)
				)
				(arc
					(start 338.63153 -220.319854)
					(mid 338.573874 -220.18066)
					(end 338.43468 -220.123004)
				)
				(arc
					(start 338.43468 -220.123004)
					(mid 338.336249 -220.14942)
					(end 338.264246 -220.221556)
				)
				(arc
					(start 337.7946 -221.035626)
					(mid 337.774916 -221.083036)
					(end 337.768184 -221.133924)
				)
				(arc
					(start 337.768184 -221.133924)
					(mid 337.82584 -221.273118)
					(end 337.965034 -221.330774)
				)
				(arc
					(start 337.965034 -221.330774)
					(mid 338.063465 -221.304358)
					(end 338.135468 -221.232222)
				)
			)
		)
	)
	(zone
		(layers "F.Cu" "B.Cu" "In1.Cu" "In2.Cu" "In3.Cu" "In4.Cu" "In5.Cu" "In6.Cu"
			"In7.Cu" "In8.Cu" "In9.Cu" "In10.Cu" "In11.Cu" "In12.Cu" "In13.Cu" "In14.Cu"
			"In15.Cu" "In16.Cu"
		)
		(hatch none 0.5)
		(connect_pads
			(clearance 0)
		)
		(min_thickness 0.25)
		(keepout
			(tracks not_allowed)
			(vias allowed)
			(pads allowed)
			(copperpour not_allowed)
			(footprints allowed)
		)
		(placement
			(enabled no)
			(sheetname "")
		)
		(fill
			(thermal_gap 0.5)
			(thermal_bridge_width 0.5)
			(island_removal_mode 0)
		)
		(polygon
			(pts
				(arc
					(start 345.922346 -286.475424)
					(mid 345.264486 -286.475424)
					(end 345.922346 -286.475424)
				)
			)
		)
	)
	(zone
		(layers "F.Cu" "B.Cu" "In1.Cu" "In2.Cu" "In3.Cu" "In4.Cu" "In5.Cu" "In6.Cu"
			"In7.Cu" "In8.Cu" "In9.Cu" "In10.Cu" "In11.Cu" "In12.Cu" "In13.Cu" "In14.Cu"
			"In15.Cu" "In16.Cu"
		)
		(hatch none 0.5)
		(connect_pads
			(clearance 0)
		)
		(min_thickness 0.25)
		(keepout
			(tracks not_allowed)
			(vias allowed)
			(pads allowed)
			(copperpour not_allowed)
			(footprints allowed)
		)
		(placement
			(enabled no)
			(sheetname "")
		)
		(fill
			(thermal_gap 0.5)
			(thermal_bridge_width 0.5)
			(island_removal_mode 0)
		)
		(polygon
			(pts
				(arc
					(start 97.952814 -288.818828)
					(mid 97.93313 -288.866238)
					(end 97.926398 -288.917126)
				)
				(arc
					(start 97.926398 -288.917126)
					(mid 97.984054 -289.05632)
					(end 98.123248 -289.113976)
				)
				(arc
					(start 98.123248 -289.113976)
					(mid 98.221679 -289.08756)
					(end 98.293682 -289.015424)
				)
				(arc
					(start 98.763582 -288.201354)
					(mid 98.783266 -288.153944)
					(end 98.789998 -288.103056)
				)
				(arc
					(start 98.789998 -288.103056)
					(mid 98.732342 -287.963862)
					(end 98.593148 -287.906206)
				)
				(arc
					(start 98.593148 -287.906206)
					(mid 98.494717 -287.932622)
					(end 98.422714 -288.004758)
				)
			)
		)
	)
	(zone
		(layers "F.Cu" "B.Cu" "In1.Cu" "In2.Cu" "In3.Cu" "In4.Cu" "In5.Cu" "In6.Cu"
			"In7.Cu" "In8.Cu" "In9.Cu" "In10.Cu" "In11.Cu" "In12.Cu" "In13.Cu" "In14.Cu"
			"In15.Cu" "In16.Cu"
		)
		(hatch none 0.5)
		(connect_pads
			(clearance 0)
		)
		(min_thickness 0.25)
		(keepout
			(tracks not_allowed)
			(vias allowed)
			(pads allowed)
			(copperpour not_allowed)
			(footprints allowed)
		)
		(placement
			(enabled no)
			(sheetname "")
		)
		(fill
			(thermal_gap 0.5)
			(thermal_bridge_width 0.5)
			(island_removal_mode 0)
		)
		(polygon
			(pts
				(arc
					(start 349.05315 -285.563056)
					(mid 348.981161 -285.490897)
					(end 348.882716 -285.464504)
				)
				(arc
					(start 348.882716 -285.464504)
					(mid 348.743522 -285.52216)
					(end 348.685866 -285.661354)
				)
				(arc
					(start 348.685866 -285.661354)
					(mid 348.692623 -285.712235)
					(end 348.712282 -285.759652)
				)
				(arc
					(start 349.182182 -286.573722)
					(mid 349.254171 -286.645881)
					(end 349.352616 -286.672274)
				)
				(arc
					(start 349.352616 -286.672274)
					(mid 349.49181 -286.614618)
					(end 349.549466 -286.475424)
				)
				(arc
					(start 349.549466 -286.475424)
					(mid 349.542709 -286.424543)
					(end 349.52305 -286.377126)
				)
			)
		)
	)
	(zone
		(layers "F.Cu" "B.Cu" "In1.Cu" "In2.Cu" "In3.Cu" "In4.Cu" "In5.Cu" "In6.Cu"
			"In7.Cu" "In8.Cu" "In9.Cu" "In10.Cu" "In11.Cu" "In12.Cu" "In13.Cu" "In14.Cu"
			"In15.Cu" "In16.Cu"
		)
		(hatch none 0.5)
		(connect_pads
			(clearance 0)
		)
		(min_thickness 0.25)
		(keepout
			(tracks not_allowed)
			(vias allowed)
			(pads allowed)
			(copperpour not_allowed)
			(footprints allowed)
		)
		(placement
			(enabled no)
			(sheetname "")
		)
		(fill
			(thermal_gap 0.5)
			(thermal_bridge_width 0.5)
			(island_removal_mode 0)
		)
		(polygon
			(pts
				(arc
					(start 123.218194 -400.477228)
					(mid 122.837194 -400.858228)
					(end 123.218194 -401.239228)
				)
				(arc
					(start 124.081794 -401.239228)
					(mid 124.462794 -400.858228)
					(end 124.081794 -400.477228)
				)
			)
		)
	)
	(zone
		(layers "F.Cu" "B.Cu" "In1.Cu" "In2.Cu" "In3.Cu" "In4.Cu" "In5.Cu" "In6.Cu"
			"In7.Cu" "In8.Cu" "In9.Cu" "In10.Cu" "In11.Cu" "In12.Cu" "In13.Cu" "In14.Cu"
			"In15.Cu" "In16.Cu"
		)
		(hatch none 0.5)
		(connect_pads
			(clearance 0)
		)
		(min_thickness 0.25)
		(keepout
			(tracks not_allowed)
			(vias allowed)
			(pads allowed)
			(copperpour not_allowed)
			(footprints allowed)
		)
		(placement
			(enabled no)
			(sheetname "")
		)
		(fill
			(thermal_gap 0.5)
			(thermal_bridge_width 0.5)
			(island_removal_mode 0)
		)
		(polygon
			(pts
				(arc
					(start 109.72927 -275.8948)
					(mid 109.07141 -275.8948)
					(end 109.72927 -275.8948)
				)
			)
		)
	)
	(zone
		(layers "F.Cu" "B.Cu" "In1.Cu" "In2.Cu" "In3.Cu" "In4.Cu" "In5.Cu" "In6.Cu"
			"In7.Cu" "In8.Cu" "In9.Cu" "In10.Cu" "In11.Cu" "In12.Cu" "In13.Cu" "In14.Cu"
			"In15.Cu" "In16.Cu"
		)
		(hatch none 0.5)
		(connect_pads
			(clearance 0)
		)
		(min_thickness 0.25)
		(keepout
			(tracks not_allowed)
			(vias allowed)
			(pads allowed)
			(copperpour not_allowed)
			(footprints allowed)
		)
		(placement
			(enabled no)
			(sheetname "")
		)
		(fill
			(thermal_gap 0.5)
			(thermal_bridge_width 0.5)
			(island_removal_mode 0)
		)
		(polygon
			(pts
				(arc
					(start 344.512392 -282.405836)
					(mid 343.854532 -282.405836)
					(end 344.512392 -282.405836)
				)
			)
		)
	)
	(zone
		(layers "F.Cu" "B.Cu" "In1.Cu" "In2.Cu" "In3.Cu" "In4.Cu" "In5.Cu" "In6.Cu"
			"In7.Cu" "In8.Cu" "In9.Cu" "In10.Cu" "In11.Cu" "In12.Cu" "In13.Cu" "In14.Cu"
			"In15.Cu" "In16.Cu"
		)
		(hatch none 0.5)
		(connect_pads
			(clearance 0)
		)
		(min_thickness 0.25)
		(keepout
			(tracks not_allowed)
			(vias allowed)
			(pads allowed)
			(copperpour not_allowed)
			(footprints allowed)
		)
		(placement
			(enabled no)
			(sheetname "")
		)
		(fill
			(thermal_gap 0.5)
			(thermal_bridge_width 0.5)
			(island_removal_mode 0)
		)
		(polygon
			(pts
				(arc
					(start 115.57 -224.291144)
					(mid 115.498011 -224.218985)
					(end 115.399566 -224.192592)
				)
				(arc
					(start 115.399566 -224.192592)
					(mid 115.260372 -224.250248)
					(end 115.202716 -224.389442)
				)
				(arc
					(start 115.202716 -224.389442)
					(mid 115.209473 -224.440323)
					(end 115.229132 -224.48774)
				)
				(arc
					(start 115.698778 -225.301556)
					(mid 115.770767 -225.373715)
					(end 115.869212 -225.400108)
				)
				(arc
					(start 115.869212 -225.400108)
					(mid 116.008406 -225.342452)
					(end 116.066062 -225.203258)
				)
				(arc
					(start 116.066062 -225.203258)
					(mid 116.059305 -225.152377)
					(end 116.039646 -225.10496)
				)
			)
		)
	)
	(zone
		(layers "F.Cu" "B.Cu" "In1.Cu" "In2.Cu" "In3.Cu" "In4.Cu" "In5.Cu" "In6.Cu"
			"In7.Cu" "In8.Cu" "In9.Cu" "In10.Cu" "In11.Cu" "In12.Cu" "In13.Cu" "In14.Cu"
			"In15.Cu" "In16.Cu"
		)
		(hatch none 0.5)
		(connect_pads
			(clearance 0)
		)
		(min_thickness 0.25)
		(keepout
			(tracks not_allowed)
			(vias allowed)
			(pads allowed)
			(copperpour not_allowed)
			(footprints allowed)
		)
		(placement
			(enabled no)
			(sheetname "")
		)
		(fill
			(thermal_gap 0.5)
			(thermal_bridge_width 0.5)
			(island_removal_mode 0)
		)
		(polygon
			(pts
				(arc
					(start 92.074492 -214.720932)
					(mid 92.094176 -214.673522)
					(end 92.100908 -214.622634)
				)
				(arc
					(start 92.100908 -214.622634)
					(mid 92.043252 -214.48344)
					(end 91.904058 -214.425784)
				)
				(arc
					(start 91.904058 -214.425784)
					(mid 91.805627 -214.4522)
					(end 91.733624 -214.524336)
				)
				(arc
					(start 91.263978 -215.338406)
					(mid 91.244294 -215.385816)
					(end 91.237562 -215.436704)
				)
				(arc
					(start 91.237562 -215.436704)
					(mid 91.295218 -215.575898)
					(end 91.434412 -215.633554)
				)
				(arc
					(start 91.434412 -215.633554)
					(mid 91.532843 -215.607138)
					(end 91.604846 -215.535002)
				)
			)
		)
	)
	(zone
		(layers "F.Cu" "B.Cu" "In1.Cu" "In2.Cu" "In3.Cu" "In4.Cu" "In5.Cu" "In6.Cu"
			"In7.Cu" "In8.Cu" "In9.Cu" "In10.Cu" "In11.Cu" "In12.Cu" "In13.Cu" "In14.Cu"
			"In15.Cu" "In16.Cu"
		)
		(hatch none 0.5)
		(connect_pads
			(clearance 0)
		)
		(min_thickness 0.25)
		(keepout
			(tracks not_allowed)
			(vias allowed)
			(pads allowed)
			(copperpour not_allowed)
			(footprints allowed)
		)
		(placement
			(enabled no)
			(sheetname "")
		)
		(fill
			(thermal_gap 0.5)
			(thermal_bridge_width 0.5)
			(island_removal_mode 0)
		)
		(polygon
			(pts
				(arc
					(start 116.979954 -216.966292)
					(mid 116.907965 -216.894133)
					(end 116.80952 -216.86774)
				)
				(arc
					(start 116.80952 -216.86774)
					(mid 116.670326 -216.925396)
					(end 116.61267 -217.06459)
				)
				(arc
					(start 116.61267 -217.06459)
					(mid 116.619427 -217.115471)
					(end 116.639086 -217.162888)
				)
				(arc
					(start 117.108732 -217.976704)
					(mid 117.180721 -218.048863)
					(end 117.279166 -218.075256)
				)
				(arc
					(start 117.279166 -218.075256)
					(mid 117.41836 -218.0176)
					(end 117.476016 -217.878406)
				)
				(arc
					(start 117.476016 -217.878406)
					(mid 117.469259 -217.827525)
					(end 117.4496 -217.780108)
				)
			)
		)
	)
	(zone
		(layers "F.Cu" "B.Cu" "In1.Cu" "In2.Cu" "In3.Cu" "In4.Cu" "In5.Cu" "In6.Cu"
			"In7.Cu" "In8.Cu" "In9.Cu" "In10.Cu" "In11.Cu" "In12.Cu" "In13.Cu" "In14.Cu"
			"In15.Cu" "In16.Cu"
		)
		(hatch none 0.5)
		(connect_pads
			(clearance 0)
		)
		(min_thickness 0.25)
		(keepout
			(tracks not_allowed)
			(vias allowed)
			(pads allowed)
			(copperpour not_allowed)
			(footprints allowed)
		)
		(placement
			(enabled no)
			(sheetname "")
		)
		(fill
			(thermal_gap 0.5)
			(thermal_bridge_width 0.5)
			(island_removal_mode 0)
		)
		(polygon
			(pts
				(arc
					(start 334.95615 -283.935424)
					(mid 334.884161 -283.863265)
					(end 334.785716 -283.836872)
				)
				(arc
					(start 334.785716 -283.836872)
					(mid 334.646522 -283.894528)
					(end 334.588866 -284.033722)
				)
				(arc
					(start 334.588866 -284.033722)
					(mid 334.595623 -284.084603)
					(end 334.615282 -284.13202)
				)
				(arc
					(start 335.084928 -284.945836)
					(mid 335.156917 -285.017995)
					(end 335.255362 -285.044388)
				)
				(arc
					(start 335.255362 -285.044388)
					(mid 335.394556 -284.986732)
					(end 335.452212 -284.847538)
				)
				(arc
					(start 335.452212 -284.847538)
					(mid 335.445455 -284.796657)
					(end 335.425796 -284.74924)
				)
			)
		)
	)
	(zone
		(layers "F.Cu" "B.Cu" "In1.Cu" "In2.Cu" "In3.Cu" "In4.Cu" "In5.Cu" "In6.Cu"
			"In7.Cu" "In8.Cu" "In9.Cu" "In10.Cu" "In11.Cu" "In12.Cu" "In13.Cu" "In14.Cu"
			"In15.Cu" "In16.Cu"
		)
		(hatch none 0.5)
		(connect_pads
			(clearance 0)
		)
		(min_thickness 0.25)
		(keepout
			(tracks not_allowed)
			(vias allowed)
			(pads allowed)
			(copperpour not_allowed)
			(footprints allowed)
		)
		(placement
			(enabled no)
			(sheetname "")
		)
		(fill
			(thermal_gap 0.5)
			(thermal_bridge_width 0.5)
			(island_removal_mode 0)
		)
		(polygon
			(pts
				(arc
					(start 179.6542 -42.618152)
					(mid 179.2732 -42.237152)
					(end 178.8922 -42.618152)
				)
				(arc
					(start 178.8922 -43.481752)
					(mid 179.2732 -43.862752)
					(end 179.6542 -43.481752)
				)
			)
		)
	)
	(zone
		(layers "F.Cu" "B.Cu" "In1.Cu" "In2.Cu" "In3.Cu" "In4.Cu" "In5.Cu" "In6.Cu"
			"In7.Cu" "In8.Cu" "In9.Cu" "In10.Cu" "In11.Cu" "In12.Cu" "In13.Cu" "In14.Cu"
			"In15.Cu" "In16.Cu"
		)
		(hatch none 0.5)
		(connect_pads
			(clearance 0)
		)
		(min_thickness 0.25)
		(keepout
			(tracks not_allowed)
			(vias allowed)
			(pads allowed)
			(copperpour not_allowed)
			(footprints allowed)
		)
		(placement
			(enabled no)
			(sheetname "")
		)
		(fill
			(thermal_gap 0.5)
			(thermal_bridge_width 0.5)
			(island_removal_mode 0)
		)
		(polygon
			(pts
				(arc
					(start 368.679222 -216.966292)
					(mid 368.607233 -216.894133)
					(end 368.508788 -216.86774)
				)
				(arc
					(start 368.508788 -216.86774)
					(mid 368.369594 -216.925396)
					(end 368.311938 -217.06459)
				)
				(arc
					(start 368.311938 -217.06459)
					(mid 368.318695 -217.115471)
					(end 368.338354 -217.162888)
				)
				(arc
					(start 368.808 -217.976704)
					(mid 368.879989 -218.048863)
					(end 368.978434 -218.075256)
				)
				(arc
					(start 368.978434 -218.075256)
					(mid 369.117628 -218.0176)
					(end 369.175284 -217.878406)
				)
				(arc
					(start 369.175284 -217.878406)
					(mid 369.168527 -217.827525)
					(end 369.148868 -217.780108)
				)
			)
		)
	)
	(zone
		(layers "F.Cu" "B.Cu" "In1.Cu" "In2.Cu" "In3.Cu" "In4.Cu" "In5.Cu" "In6.Cu"
			"In7.Cu" "In8.Cu" "In9.Cu" "In10.Cu" "In11.Cu" "In12.Cu" "In13.Cu" "In14.Cu"
			"In15.Cu" "In16.Cu"
		)
		(hatch none 0.5)
		(connect_pads
			(clearance 0)
		)
		(min_thickness 0.25)
		(keepout
			(tracks not_allowed)
			(vias allowed)
			(pads allowed)
			(copperpour not_allowed)
			(footprints allowed)
		)
		(placement
			(enabled no)
			(sheetname "")
		)
		(fill
			(thermal_gap 0.5)
			(thermal_bridge_width 0.5)
			(island_removal_mode 0)
		)
		(polygon
			(pts
				(arc
					(start 348.003114 -217.162634)
					(mid 348.022798 -217.115224)
					(end 348.02953 -217.064336)
				)
				(arc
					(start 348.02953 -217.064336)
					(mid 347.971874 -216.925142)
					(end 347.83268 -216.867486)
				)
				(arc
					(start 347.83268 -216.867486)
					(mid 347.734249 -216.893902)
					(end 347.662246 -216.966038)
				)
				(arc
					(start 347.1926 -217.780108)
					(mid 347.172916 -217.827518)
					(end 347.166184 -217.878406)
				)
				(arc
					(start 347.166184 -217.878406)
					(mid 347.22384 -218.0176)
					(end 347.363034 -218.075256)
				)
				(arc
					(start 347.363034 -218.075256)
					(mid 347.461465 -218.04884)
					(end 347.533468 -217.976704)
				)
			)
		)
	)
	(zone
		(layers "F.Cu" "B.Cu" "In1.Cu" "In2.Cu" "In3.Cu" "In4.Cu" "In5.Cu" "In6.Cu"
			"In7.Cu" "In8.Cu" "In9.Cu" "In10.Cu" "In11.Cu" "In12.Cu" "In13.Cu" "In14.Cu"
			"In15.Cu" "In16.Cu"
		)
		(hatch none 0.5)
		(connect_pads
			(clearance 0)
		)
		(min_thickness 0.25)
		(keepout
			(tracks not_allowed)
			(vias allowed)
			(pads allowed)
			(copperpour not_allowed)
			(footprints allowed)
		)
		(placement
			(enabled no)
			(sheetname "")
		)
		(fill
			(thermal_gap 0.5)
			(thermal_bridge_width 0.5)
			(island_removal_mode 0)
		)
		(polygon
			(pts
				(arc
					(start 342.992964 -224.389442)
					(mid 342.335104 -224.389442)
					(end 342.992964 -224.389442)
				)
			)
		)
	)
	(zone
		(layers "F.Cu" "B.Cu" "In1.Cu" "In2.Cu" "In3.Cu" "In4.Cu" "In5.Cu" "In6.Cu"
			"In7.Cu" "In8.Cu" "In9.Cu" "In10.Cu" "In11.Cu" "In12.Cu" "In13.Cu" "In14.Cu"
			"In15.Cu" "In16.Cu"
		)
		(hatch none 0.5)
		(connect_pads
			(clearance 0)
		)
		(min_thickness 0.25)
		(keepout
			(tracks not_allowed)
			(vias allowed)
			(pads allowed)
			(copperpour not_allowed)
			(footprints allowed)
		)
		(placement
			(enabled no)
			(sheetname "")
		)
		(fill
			(thermal_gap 0.5)
			(thermal_bridge_width 0.5)
			(island_removal_mode 0)
		)
		(polygon
			(pts
				(arc
					(start 122.148092 -221.231968)
					(mid 122.167776 -221.184558)
					(end 122.174508 -221.13367)
				)
				(arc
					(start 122.174508 -221.13367)
					(mid 122.116852 -220.994476)
					(end 121.977658 -220.93682)
				)
				(arc
					(start 121.977658 -220.93682)
					(mid 121.879227 -220.963236)
					(end 121.807224 -221.035372)
				)
				(arc
					(start 121.337578 -221.849442)
					(mid 121.317894 -221.896852)
					(end 121.311162 -221.94774)
				)
				(arc
					(start 121.311162 -221.94774)
					(mid 121.368818 -222.086934)
					(end 121.508012 -222.14459)
				)
				(arc
					(start 121.508012 -222.14459)
					(mid 121.606443 -222.118174)
					(end 121.678446 -222.046038)
				)
			)
		)
	)
	(zone
		(layers "F.Cu" "B.Cu" "In1.Cu" "In2.Cu" "In3.Cu" "In4.Cu" "In5.Cu" "In6.Cu"
			"In7.Cu" "In8.Cu" "In9.Cu" "In10.Cu" "In11.Cu" "In12.Cu" "In13.Cu" "In14.Cu"
			"In15.Cu" "In16.Cu"
		)
		(hatch none 0.5)
		(connect_pads
			(clearance 0)
		)
		(min_thickness 0.25)
		(keepout
			(tracks not_allowed)
			(vias allowed)
			(pads allowed)
			(copperpour not_allowed)
			(footprints allowed)
		)
		(placement
			(enabled no)
			(sheetname "")
		)
		(fill
			(thermal_gap 0.5)
			(thermal_bridge_width 0.5)
			(island_removal_mode 0)
		)
		(polygon
			(pts
				(arc
					(start 383.67589 -403.502876)
					(mid 383.29489 -403.883876)
					(end 383.67589 -404.264876)
				)
				(arc
					(start 384.53949 -404.264876)
					(mid 384.92049 -403.883876)
					(end 384.53949 -403.502876)
				)
			)
		)
	)
	(zone
		(layers "F.Cu" "B.Cu" "In1.Cu" "In2.Cu" "In3.Cu" "In4.Cu" "In5.Cu" "In6.Cu"
			"In7.Cu" "In8.Cu" "In9.Cu" "In10.Cu" "In11.Cu" "In12.Cu" "In13.Cu" "In14.Cu"
			"In15.Cu" "In16.Cu"
		)
		(hatch none 0.5)
		(connect_pads
			(clearance 0)
		)
		(min_thickness 0.25)
		(keepout
			(tracks not_allowed)
			(vias allowed)
			(pads allowed)
			(copperpour not_allowed)
			(footprints allowed)
		)
		(placement
			(enabled no)
			(sheetname "")
		)
		(fill
			(thermal_gap 0.5)
			(thermal_bridge_width 0.5)
			(island_removal_mode 0)
		)
		(polygon
			(pts
				(arc
					(start 119.957342 -218.692222)
					(mid 119.299482 -218.692222)
					(end 119.957342 -218.692222)
				)
			)
		)
	)
	(zone
		(layers "F.Cu" "B.Cu" "In1.Cu" "In2.Cu" "In3.Cu" "In4.Cu" "In5.Cu" "In6.Cu"
			"In7.Cu" "In8.Cu" "In9.Cu" "In10.Cu" "In11.Cu" "In12.Cu" "In13.Cu" "In14.Cu"
			"In15.Cu" "In16.Cu"
		)
		(hatch none 0.5)
		(connect_pads
			(clearance 0)
		)
		(min_thickness 0.25)
		(keepout
			(tracks not_allowed)
			(vias allowed)
			(pads allowed)
			(copperpour not_allowed)
			(footprints allowed)
		)
		(placement
			(enabled no)
			(sheetname "")
		)
		(fill
			(thermal_gap 0.5)
			(thermal_bridge_width 0.5)
			(island_removal_mode 0)
		)
		(polygon
			(pts
				(arc
					(start 347.801946 -281.59202)
					(mid 347.144086 -281.59202)
					(end 347.801946 -281.59202)
				)
			)
		)
	)
	(zone
		(layers "F.Cu" "B.Cu" "In1.Cu" "In2.Cu" "In3.Cu" "In4.Cu" "In5.Cu" "In6.Cu"
			"In7.Cu" "In8.Cu" "In9.Cu" "In10.Cu" "In11.Cu" "In12.Cu" "In13.Cu" "In14.Cu"
			"In15.Cu" "In16.Cu"
		)
		(hatch none 0.5)
		(connect_pads
			(clearance 0)
		)
		(min_thickness 0.25)
		(keepout
			(tracks not_allowed)
			(vias allowed)
			(pads allowed)
			(copperpour not_allowed)
			(footprints allowed)
		)
		(placement
			(enabled no)
			(sheetname "")
		)
		(fill
			(thermal_gap 0.5)
			(thermal_bridge_width 0.5)
			(island_removal_mode 0)
		)
		(polygon
			(pts
				(arc
					(start 199.462898 -153.774902)
					(mid 188.446918 -153.774902)
					(end 199.462898 -153.774902)
				)
			)
		)
	)
	(zone
		(layers "F.Cu" "B.Cu" "In1.Cu" "In2.Cu" "In3.Cu" "In4.Cu" "In5.Cu" "In6.Cu"
			"In7.Cu" "In8.Cu" "In9.Cu" "In10.Cu" "In11.Cu" "In12.Cu" "In13.Cu" "In14.Cu"
			"In15.Cu" "In16.Cu"
		)
		(hatch none 0.5)
		(connect_pads
			(clearance 0)
		)
		(min_thickness 0.25)
		(keepout
			(tracks not_allowed)
			(vias allowed)
			(pads allowed)
			(copperpour not_allowed)
			(footprints allowed)
		)
		(placement
			(enabled no)
			(sheetname "")
		)
		(fill
			(thermal_gap 0.5)
			(thermal_bridge_width 0.5)
			(island_removal_mode 0)
		)
		(polygon
			(pts
				(arc
					(start 121.2088 -224.291144)
					(mid 121.136811 -224.218985)
					(end 121.038366 -224.192592)
				)
				(arc
					(start 121.038366 -224.192592)
					(mid 120.899172 -224.250248)
					(end 120.841516 -224.389442)
				)
				(arc
					(start 120.841516 -224.389442)
					(mid 120.848273 -224.440323)
					(end 120.867932 -224.48774)
				)
				(arc
					(start 121.337578 -225.301556)
					(mid 121.409567 -225.373715)
					(end 121.508012 -225.400108)
				)
				(arc
					(start 121.508012 -225.400108)
					(mid 121.647206 -225.342452)
					(end 121.704862 -225.203258)
				)
				(arc
					(start 121.704862 -225.203258)
					(mid 121.698105 -225.152377)
					(end 121.678446 -225.10496)
				)
			)
		)
	)
	(zone
		(layers "F.Cu" "B.Cu" "In1.Cu" "In2.Cu" "In3.Cu" "In4.Cu" "In5.Cu" "In6.Cu"
			"In7.Cu" "In8.Cu" "In9.Cu" "In10.Cu" "In11.Cu" "In12.Cu" "In13.Cu" "In14.Cu"
			"In15.Cu" "In16.Cu"
		)
		(hatch none 0.5)
		(connect_pads
			(clearance 0)
		)
		(min_thickness 0.25)
		(keepout
			(tracks not_allowed)
			(vias allowed)
			(pads allowed)
			(copperpour not_allowed)
			(footprints allowed)
		)
		(placement
			(enabled no)
			(sheetname "")
		)
		(fill
			(thermal_gap 0.5)
			(thermal_bridge_width 0.5)
			(island_removal_mode 0)
		)
		(polygon
			(pts
				(arc
					(start 106.330496 -217.878406)
					(mid 105.672636 -217.878406)
					(end 106.330496 -217.878406)
				)
			)
		)
	)
	(zone
		(layers "F.Cu" "B.Cu" "In1.Cu" "In2.Cu" "In3.Cu" "In4.Cu" "In5.Cu" "In6.Cu"
			"In7.Cu" "In8.Cu" "In9.Cu" "In10.Cu" "In11.Cu" "In12.Cu" "In13.Cu" "In14.Cu"
			"In15.Cu" "In16.Cu"
		)
		(hatch none 0.5)
		(connect_pads
			(clearance 0)
		)
		(min_thickness 0.25)
		(keepout
			(tracks not_allowed)
			(vias allowed)
			(pads allowed)
			(copperpour not_allowed)
			(footprints allowed)
		)
		(placement
			(enabled no)
			(sheetname "")
		)
		(fill
			(thermal_gap 0.5)
			(thermal_bridge_width 0.5)
			(island_removal_mode 0)
		)
		(polygon
			(pts
				(arc
					(start 105.390696 -217.878406)
					(mid 104.732836 -217.878406)
					(end 105.390696 -217.878406)
				)
			)
		)
	)
	(zone
		(layers "F.Cu" "B.Cu" "In1.Cu" "In2.Cu" "In3.Cu" "In4.Cu" "In5.Cu" "In6.Cu"
			"In7.Cu" "In8.Cu" "In9.Cu" "In10.Cu" "In11.Cu" "In12.Cu" "In13.Cu" "In14.Cu"
			"In15.Cu" "In16.Cu"
		)
		(hatch none 0.5)
		(connect_pads
			(clearance 0)
		)
		(min_thickness 0.25)
		(keepout
			(tracks not_allowed)
			(vias allowed)
			(pads allowed)
			(copperpour not_allowed)
			(footprints allowed)
		)
		(placement
			(enabled no)
			(sheetname "")
		)
		(fill
			(thermal_gap 0.5)
			(thermal_bridge_width 0.5)
			(island_removal_mode 0)
		)
		(polygon
			(pts
				(arc
					(start 348.003114 -220.418152)
					(mid 348.022798 -220.370742)
					(end 348.02953 -220.319854)
				)
				(arc
					(start 348.02953 -220.319854)
					(mid 347.971874 -220.18066)
					(end 347.83268 -220.123004)
				)
				(arc
					(start 347.83268 -220.123004)
					(mid 347.734249 -220.14942)
					(end 347.662246 -220.221556)
				)
				(arc
					(start 347.1926 -221.035626)
					(mid 347.172916 -221.083036)
					(end 347.166184 -221.133924)
				)
				(arc
					(start 347.166184 -221.133924)
					(mid 347.22384 -221.273118)
					(end 347.363034 -221.330774)
				)
				(arc
					(start 347.363034 -221.330774)
					(mid 347.461465 -221.304358)
					(end 347.533468 -221.232222)
				)
			)
		)
	)
	(zone
		(layers "F.Cu" "B.Cu" "In1.Cu" "In2.Cu" "In3.Cu" "In4.Cu" "In5.Cu" "In6.Cu"
			"In7.Cu" "In8.Cu" "In9.Cu" "In10.Cu" "In11.Cu" "In12.Cu" "In13.Cu" "In14.Cu"
			"In15.Cu" "In16.Cu"
		)
		(hatch none 0.5)
		(connect_pads
			(clearance 0)
		)
		(min_thickness 0.25)
		(keepout
			(tracks not_allowed)
			(vias allowed)
			(pads allowed)
			(copperpour not_allowed)
			(footprints allowed)
		)
		(placement
			(enabled no)
			(sheetname "")
		)
		(fill
			(thermal_gap 0.5)
			(thermal_bridge_width 0.5)
			(island_removal_mode 0)
		)
		(polygon
			(pts
				(arc
					(start 95.914718 -288.917126)
					(mid 96.572578 -288.917126)
					(end 95.914718 -288.917126)
				)
			)
		)
	)
	(zone
		(layers "F.Cu" "B.Cu" "In1.Cu" "In2.Cu" "In3.Cu" "In4.Cu" "In5.Cu" "In6.Cu"
			"In7.Cu" "In8.Cu" "In9.Cu" "In10.Cu" "In11.Cu" "In12.Cu" "In13.Cu" "In14.Cu"
			"In15.Cu" "In16.Cu"
		)
		(hatch none 0.5)
		(connect_pads
			(clearance 0)
		)
		(min_thickness 0.25)
		(keepout
			(tracks not_allowed)
			(vias allowed)
			(pads allowed)
			(copperpour not_allowed)
			(footprints allowed)
		)
		(placement
			(enabled no)
			(sheetname "")
		)
		(fill
			(thermal_gap 0.5)
			(thermal_bridge_width 0.5)
			(island_removal_mode 0)
		)
		(polygon
			(pts
				(arc
					(start 351.87255 -274.168362)
					(mid 351.800561 -274.096203)
					(end 351.702116 -274.06981)
				)
				(arc
					(start 351.702116 -274.06981)
					(mid 351.562922 -274.127466)
					(end 351.505266 -274.26666)
				)
				(arc
					(start 351.505266 -274.26666)
					(mid 351.512023 -274.317541)
					(end 351.531682 -274.364958)
				)
				(arc
					(start 352.001582 -275.179028)
					(mid 352.073571 -275.251187)
					(end 352.172016 -275.27758)
				)
				(arc
					(start 352.172016 -275.27758)
					(mid 352.31121 -275.219924)
					(end 352.368866 -275.08073)
				)
				(arc
					(start 352.368866 -275.08073)
					(mid 352.362109 -275.029849)
					(end 352.34245 -274.982432)
				)
			)
		)
	)
	(zone
		(layers "F.Cu" "B.Cu" "In1.Cu" "In2.Cu" "In3.Cu" "In4.Cu" "In5.Cu" "In6.Cu"
			"In7.Cu" "In8.Cu" "In9.Cu" "In10.Cu" "In11.Cu" "In12.Cu" "In13.Cu" "In14.Cu"
			"In15.Cu" "In16.Cu"
		)
		(hatch none 0.5)
		(connect_pads
			(clearance 0)
		)
		(min_thickness 0.25)
		(keepout
			(tracks not_allowed)
			(vias allowed)
			(pads allowed)
			(copperpour not_allowed)
			(footprints allowed)
		)
		(placement
			(enabled no)
			(sheetname "")
		)
		(fill
			(thermal_gap 0.5)
			(thermal_bridge_width 0.5)
			(island_removal_mode 0)
		)
		(polygon
			(pts
				(arc
					(start 124.968 -224.291144)
					(mid 124.896011 -224.218985)
					(end 124.797566 -224.192592)
				)
				(arc
					(start 124.797566 -224.192592)
					(mid 124.658372 -224.250248)
					(end 124.600716 -224.389442)
				)
				(arc
					(start 124.600716 -224.389442)
					(mid 124.607473 -224.440323)
					(end 124.627132 -224.48774)
				)
				(arc
					(start 125.096778 -225.301556)
					(mid 125.168767 -225.373715)
					(end 125.267212 -225.400108)
				)
				(arc
					(start 125.267212 -225.400108)
					(mid 125.406406 -225.342452)
					(end 125.464062 -225.203258)
				)
				(arc
					(start 125.464062 -225.203258)
					(mid 125.457305 -225.152377)
					(end 125.437646 -225.10496)
				)
			)
		)
	)
	(zone
		(layers "F.Cu" "B.Cu" "In1.Cu" "In2.Cu" "In3.Cu" "In4.Cu" "In5.Cu" "In6.Cu"
			"In7.Cu" "In8.Cu" "In9.Cu" "In10.Cu" "In11.Cu" "In12.Cu" "In13.Cu" "In14.Cu"
			"In15.Cu" "In16.Cu"
		)
		(hatch none 0.5)
		(connect_pads
			(clearance 0)
		)
		(min_thickness 0.25)
		(keepout
			(tracks not_allowed)
			(vias allowed)
			(pads allowed)
			(copperpour not_allowed)
			(footprints allowed)
		)
		(placement
			(enabled no)
			(sheetname "")
		)
		(fill
			(thermal_gap 0.5)
			(thermal_bridge_width 0.5)
			(island_removal_mode 0)
		)
		(polygon
			(pts
				(arc
					(start 391.14857 -409.649168)
					(mid 390.76757 -410.030168)
					(end 391.14857 -410.411168)
				)
				(arc
					(start 392.01217 -410.411168)
					(mid 392.39317 -410.030168)
					(end 392.01217 -409.649168)
				)
			)
		)
	)
	(zone
		(layers "F.Cu" "B.Cu" "In1.Cu" "In2.Cu" "In3.Cu" "In4.Cu" "In5.Cu" "In6.Cu"
			"In7.Cu" "In8.Cu" "In9.Cu" "In10.Cu" "In11.Cu" "In12.Cu" "In13.Cu" "In14.Cu"
			"In15.Cu" "In16.Cu"
		)
		(hatch none 0.5)
		(connect_pads
			(clearance 0)
		)
		(min_thickness 0.25)
		(keepout
			(tracks not_allowed)
			(vias allowed)
			(pads allowed)
			(copperpour not_allowed)
			(footprints allowed)
		)
		(placement
			(enabled no)
			(sheetname "")
		)
		(fill
			(thermal_gap 0.5)
			(thermal_bridge_width 0.5)
			(island_removal_mode 0)
		)
		(polygon
			(pts
				(arc
					(start 363.198664 -223.575626)
					(mid 362.540804 -223.575626)
					(end 363.198664 -223.575626)
				)
			)
		)
	)
	(zone
		(layers "F.Cu" "B.Cu" "In1.Cu" "In2.Cu" "In3.Cu" "In4.Cu" "In5.Cu" "In6.Cu"
			"In7.Cu" "In8.Cu" "In9.Cu" "In10.Cu" "In11.Cu" "In12.Cu" "In13.Cu" "In14.Cu"
			"In15.Cu" "In16.Cu"
		)
		(hatch none 0.5)
		(connect_pads
			(clearance 0)
		)
		(min_thickness 0.25)
		(keepout
			(tracks not_allowed)
			(vias allowed)
			(pads allowed)
			(copperpour not_allowed)
			(footprints allowed)
		)
		(placement
			(enabled no)
			(sheetname "")
		)
		(fill
			(thermal_gap 0.5)
			(thermal_bridge_width 0.5)
			(island_removal_mode 0)
		)
		(polygon
			(pts
				(arc
					(start 103.511096 -221.133924)
					(mid 102.853236 -221.133924)
					(end 103.511096 -221.133924)
				)
			)
		)
	)
	(zone
		(layers "F.Cu" "B.Cu" "In1.Cu" "In2.Cu" "In3.Cu" "In4.Cu" "In5.Cu" "In6.Cu"
			"In7.Cu" "In8.Cu" "In9.Cu" "In10.Cu" "In11.Cu" "In12.Cu" "In13.Cu" "In14.Cu"
			"In15.Cu" "In16.Cu"
		)
		(hatch none 0.5)
		(connect_pads
			(clearance 0)
		)
		(min_thickness 0.25)
		(keepout
			(tracks not_allowed)
			(vias allowed)
			(pads allowed)
			(copperpour not_allowed)
			(footprints allowed)
		)
		(placement
			(enabled no)
			(sheetname "")
		)
		(fill
			(thermal_gap 0.5)
			(thermal_bridge_width 0.5)
			(island_removal_mode 0)
		)
		(polygon
			(pts
				(arc
					(start 87.174578 -284.033722)
					(mid 86.516718 -284.033722)
					(end 87.174578 -284.033722)
				)
			)
		)
	)
	(zone
		(layers "F.Cu" "B.Cu" "In1.Cu" "In2.Cu" "In3.Cu" "In4.Cu" "In5.Cu" "In6.Cu"
			"In7.Cu" "In8.Cu" "In9.Cu" "In10.Cu" "In11.Cu" "In12.Cu" "In13.Cu" "In14.Cu"
			"In15.Cu" "In16.Cu"
		)
		(hatch none 0.5)
		(connect_pads
			(clearance 0)
		)
		(min_thickness 0.25)
		(keepout
			(tracks not_allowed)
			(vias allowed)
			(pads allowed)
			(copperpour not_allowed)
			(footprints allowed)
		)
		(placement
			(enabled no)
			(sheetname "")
		)
		(fill
			(thermal_gap 0.5)
			(thermal_bridge_width 0.5)
			(island_removal_mode 0)
		)
		(polygon
			(pts
				(arc
					(start 348.473268 -217.780108)
					(mid 348.401279 -217.707949)
					(end 348.302834 -217.681556)
				)
				(arc
					(start 348.302834 -217.681556)
					(mid 348.16364 -217.739212)
					(end 348.105984 -217.878406)
				)
				(arc
					(start 348.105984 -217.878406)
					(mid 348.112741 -217.929287)
					(end 348.1324 -217.976704)
				)
				(arc
					(start 348.602046 -218.79052)
					(mid 348.674035 -218.862679)
					(end 348.77248 -218.889072)
				)
				(arc
					(start 348.77248 -218.889072)
					(mid 348.911674 -218.831416)
					(end 348.96933 -218.692222)
				)
				(arc
					(start 348.96933 -218.692222)
					(mid 348.962573 -218.641341)
					(end 348.942914 -218.593924)
				)
			)
		)
	)
	(zone
		(layers "F.Cu" "B.Cu" "In1.Cu" "In2.Cu" "In3.Cu" "In4.Cu" "In5.Cu" "In6.Cu"
			"In7.Cu" "In8.Cu" "In9.Cu" "In10.Cu" "In11.Cu" "In12.Cu" "In13.Cu" "In14.Cu"
			"In15.Cu" "In16.Cu"
		)
		(hatch none 0.5)
		(connect_pads
			(clearance 0)
		)
		(min_thickness 0.25)
		(keepout
			(tracks not_allowed)
			(vias allowed)
			(pads allowed)
			(copperpour not_allowed)
			(footprints allowed)
		)
		(placement
			(enabled no)
			(sheetname "")
		)
		(fill
			(thermal_gap 0.5)
			(thermal_bridge_width 0.5)
			(island_removal_mode 0)
		)
		(polygon
			(pts
				(arc
					(start 317.579248 -406.62352)
					(mid 317.198248 -407.00452)
					(end 317.579248 -407.38552)
				)
				(arc
					(start 318.442848 -407.38552)
					(mid 318.823848 -407.00452)
					(end 318.442848 -406.62352)
				)
			)
		)
	)
	(zone
		(layers "F.Cu" "B.Cu" "In1.Cu" "In2.Cu" "In3.Cu" "In4.Cu" "In5.Cu" "In6.Cu"
			"In7.Cu" "In8.Cu" "In9.Cu" "In10.Cu" "In11.Cu" "In12.Cu" "In13.Cu" "In14.Cu"
			"In15.Cu" "In16.Cu"
		)
		(hatch none 0.5)
		(connect_pads
			(clearance 0)
		)
		(min_thickness 0.25)
		(keepout
			(tracks not_allowed)
			(vias allowed)
			(pads allowed)
			(copperpour not_allowed)
			(footprints allowed)
		)
		(placement
			(enabled no)
			(sheetname "")
		)
		(fill
			(thermal_gap 0.5)
			(thermal_bridge_width 0.5)
			(island_removal_mode 0)
		)
		(polygon
			(pts
				(arc
					(start 346.28201 -217.064336)
					(mid 345.62415 -217.064336)
					(end 346.28201 -217.064336)
				)
			)
		)
	)
	(zone
		(layers "F.Cu" "B.Cu" "In1.Cu" "In2.Cu" "In3.Cu" "In4.Cu" "In5.Cu" "In6.Cu"
			"In7.Cu" "In8.Cu" "In9.Cu" "In10.Cu" "In11.Cu" "In12.Cu" "In13.Cu" "In14.Cu"
			"In15.Cu" "In16.Cu"
		)
		(hatch none 0.5)
		(connect_pads
			(clearance 0)
		)
		(min_thickness 0.25)
		(keepout
			(tracks not_allowed)
			(vias allowed)
			(pads allowed)
			(copperpour not_allowed)
			(footprints allowed)
		)
		(placement
			(enabled no)
			(sheetname "")
		)
		(fill
			(thermal_gap 0.5)
			(thermal_bridge_width 0.5)
			(island_removal_mode 0)
		)
		(polygon
			(pts
				(arc
					(start 239.409986 -107.825794)
					(mid 239.028986 -107.444794)
					(end 238.647986 -107.825794)
				)
				(arc
					(start 238.647986 -108.689394)
					(mid 239.028986 -109.070394)
					(end 239.409986 -108.689394)
				)
			)
		)
	)
	(zone
		(layers "F.Cu" "B.Cu" "In1.Cu" "In2.Cu" "In3.Cu" "In4.Cu" "In5.Cu" "In6.Cu"
			"In7.Cu" "In8.Cu" "In9.Cu" "In10.Cu" "In11.Cu" "In12.Cu" "In13.Cu" "In14.Cu"
			"In15.Cu" "In16.Cu"
		)
		(hatch none 0.5)
		(connect_pads
			(clearance 0)
		)
		(min_thickness 0.25)
		(keepout
			(tracks not_allowed)
			(vias allowed)
			(pads allowed)
			(copperpour not_allowed)
			(footprints allowed)
		)
		(placement
			(enabled no)
			(sheetname "")
		)
		(fill
			(thermal_gap 0.5)
			(thermal_bridge_width 0.5)
			(island_removal_mode 0)
		)
		(polygon
			(pts
				(arc
					(start 352.941382 -283.121608)
					(mid 352.921698 -283.169018)
					(end 352.914966 -283.219906)
				)
				(arc
					(start 352.914966 -283.219906)
					(mid 352.972622 -283.3591)
					(end 353.111816 -283.416756)
				)
				(arc
					(start 353.111816 -283.416756)
					(mid 353.210247 -283.39034)
					(end 353.28225 -283.318204)
				)
				(arc
					(start 353.75215 -282.504134)
					(mid 353.771834 -282.456724)
					(end 353.778566 -282.405836)
				)
				(arc
					(start 353.778566 -282.405836)
					(mid 353.72091 -282.266642)
					(end 353.581716 -282.208986)
				)
				(arc
					(start 353.581716 -282.208986)
					(mid 353.483285 -282.235402)
					(end 353.411282 -282.307538)
				)
			)
		)
	)
	(zone
		(layers "F.Cu" "B.Cu" "In1.Cu" "In2.Cu" "In3.Cu" "In4.Cu" "In5.Cu" "In6.Cu"
			"In7.Cu" "In8.Cu" "In9.Cu" "In10.Cu" "In11.Cu" "In12.Cu" "In13.Cu" "In14.Cu"
			"In15.Cu" "In16.Cu"
		)
		(hatch none 0.5)
		(connect_pads
			(clearance 0)
		)
		(min_thickness 0.25)
		(keepout
			(tracks not_allowed)
			(vias allowed)
			(pads allowed)
			(copperpour not_allowed)
			(footprints allowed)
		)
		(placement
			(enabled no)
			(sheetname "")
		)
		(fill
			(thermal_gap 0.5)
			(thermal_bridge_width 0.5)
			(island_removal_mode 0)
		)
		(polygon
			(pts
				(arc
					(start 105.001314 -283.121608)
					(mid 104.98163 -283.169018)
					(end 104.974898 -283.219906)
				)
				(arc
					(start 104.974898 -283.219906)
					(mid 105.032554 -283.3591)
					(end 105.171748 -283.416756)
				)
				(arc
					(start 105.171748 -283.416756)
					(mid 105.270179 -283.39034)
					(end 105.342182 -283.318204)
				)
				(arc
					(start 105.812082 -282.504134)
					(mid 105.831766 -282.456724)
					(end 105.838498 -282.405836)
				)
				(arc
					(start 105.838498 -282.405836)
					(mid 105.780842 -282.266642)
					(end 105.641648 -282.208986)
				)
				(arc
					(start 105.641648 -282.208986)
					(mid 105.543217 -282.235402)
					(end 105.471214 -282.307538)
				)
			)
		)
	)
	(zone
		(layers "F.Cu" "B.Cu" "In1.Cu" "In2.Cu" "In3.Cu" "In4.Cu" "In5.Cu" "In6.Cu"
			"In7.Cu" "In8.Cu" "In9.Cu" "In10.Cu" "In11.Cu" "In12.Cu" "In13.Cu" "In14.Cu"
			"In15.Cu" "In16.Cu"
		)
		(hatch none 0.5)
		(connect_pads
			(clearance 0)
		)
		(min_thickness 0.25)
		(keepout
			(tracks not_allowed)
			(vias allowed)
			(pads allowed)
			(copperpour not_allowed)
			(footprints allowed)
		)
		(placement
			(enabled no)
			(sheetname "")
		)
		(fill
			(thermal_gap 0.5)
			(thermal_bridge_width 0.5)
			(island_removal_mode 0)
		)
		(polygon
			(pts
				(arc
					(start 106.581194 -275.69795)
					(mid 106.384344 -275.8948)
					(end 106.581194 -276.09165)
				)
				(arc
					(start 107.520994 -276.09165)
					(mid 107.717844 -275.8948)
					(end 107.520994 -275.69795)
				)
			)
		)
	)
	(zone
		(layers "F.Cu" "B.Cu" "In1.Cu" "In2.Cu" "In3.Cu" "In4.Cu" "In5.Cu" "In6.Cu"
			"In7.Cu" "In8.Cu" "In9.Cu" "In10.Cu" "In11.Cu" "In12.Cu" "In13.Cu" "In14.Cu"
			"In15.Cu" "In16.Cu"
		)
		(hatch none 0.5)
		(connect_pads
			(clearance 0)
		)
		(min_thickness 0.25)
		(keepout
			(tracks not_allowed)
			(vias allowed)
			(pads allowed)
			(copperpour not_allowed)
			(footprints allowed)
		)
		(placement
			(enabled no)
			(sheetname "")
		)
		(fill
			(thermal_gap 0.5)
			(thermal_bridge_width 0.5)
			(island_removal_mode 0)
		)
		(polygon
			(pts
				(arc
					(start 392.835384 -18.744438)
					(mid 392.454384 -19.125438)
					(end 392.835384 -19.506438)
				)
				(arc
					(start 393.698984 -19.506438)
					(mid 394.079984 -19.125438)
					(end 393.698984 -18.744438)
				)
			)
		)
	)
	(zone
		(layers "F.Cu" "B.Cu" "In1.Cu" "In2.Cu" "In3.Cu" "In4.Cu" "In5.Cu" "In6.Cu"
			"In7.Cu" "In8.Cu" "In9.Cu" "In10.Cu" "In11.Cu" "In12.Cu" "In13.Cu" "In14.Cu"
			"In15.Cu" "In16.Cu"
		)
		(hatch none 0.5)
		(connect_pads
			(clearance 0)
		)
		(min_thickness 0.25)
		(keepout
			(tracks not_allowed)
			(vias allowed)
			(pads allowed)
			(copperpour not_allowed)
			(footprints allowed)
		)
		(placement
			(enabled no)
			(sheetname "")
		)
		(fill
			(thermal_gap 0.5)
			(thermal_bridge_width 0.5)
			(island_removal_mode 0)
		)
		(polygon
			(pts
				(arc
					(start 102.963218 -275.08073)
					(mid 103.621078 -275.08073)
					(end 102.963218 -275.08073)
				)
			)
		)
	)
	(zone
		(layers "F.Cu" "B.Cu" "In1.Cu" "In2.Cu" "In3.Cu" "In4.Cu" "In5.Cu" "In6.Cu"
			"In7.Cu" "In8.Cu" "In9.Cu" "In10.Cu" "In11.Cu" "In12.Cu" "In13.Cu" "In14.Cu"
			"In15.Cu" "In16.Cu"
		)
		(hatch none 0.5)
		(connect_pads
			(clearance 0)
		)
		(min_thickness 0.25)
		(keepout
			(tracks not_allowed)
			(vias allowed)
			(pads allowed)
			(copperpour not_allowed)
			(footprints allowed)
		)
		(placement
			(enabled no)
			(sheetname "")
		)
		(fill
			(thermal_gap 0.5)
			(thermal_bridge_width 0.5)
			(island_removal_mode 0)
		)
		(polygon
			(pts
				(arc
					(start 122.307096 -224.389442)
					(mid 121.649236 -224.389442)
					(end 122.307096 -224.389442)
				)
			)
		)
	)
	(zone
		(layers "F.Cu" "B.Cu" "In1.Cu" "In2.Cu" "In3.Cu" "In4.Cu" "In5.Cu" "In6.Cu"
			"In7.Cu" "In8.Cu" "In9.Cu" "In10.Cu" "In11.Cu" "In12.Cu" "In13.Cu" "In14.Cu"
			"In15.Cu" "In16.Cu"
		)
		(hatch none 0.5)
		(connect_pads
			(clearance 0)
		)
		(min_thickness 0.25)
		(keepout
			(tracks not_allowed)
			(vias allowed)
			(pads allowed)
			(copperpour not_allowed)
			(footprints allowed)
		)
		(placement
			(enabled no)
			(sheetname "")
		)
		(fill
			(thermal_gap 0.5)
			(thermal_bridge_width 0.5)
			(island_removal_mode 0)
		)
		(polygon
			(pts
				(arc
					(start 93.173296 -221.133924)
					(mid 92.515436 -221.133924)
					(end 93.173296 -221.133924)
				)
			)
		)
	)
	(zone
		(layers "F.Cu" "B.Cu" "In1.Cu" "In2.Cu" "In3.Cu" "In4.Cu" "In5.Cu" "In6.Cu"
			"In7.Cu" "In8.Cu" "In9.Cu" "In10.Cu" "In11.Cu" "In12.Cu" "In13.Cu" "In14.Cu"
			"In15.Cu" "In16.Cu"
		)
		(hatch none 0.5)
		(connect_pads
			(clearance 0)
		)
		(min_thickness 0.25)
		(keepout
			(tracks not_allowed)
			(vias allowed)
			(pads allowed)
			(copperpour not_allowed)
			(footprints allowed)
		)
		(placement
			(enabled no)
			(sheetname "")
		)
		(fill
			(thermal_gap 0.5)
			(thermal_bridge_width 0.5)
			(island_removal_mode 0)
		)
		(polygon
			(pts
				(arc
					(start 377.29541 -225.203258)
					(mid 376.63755 -225.203258)
					(end 377.29541 -225.203258)
				)
			)
		)
	)
	(zone
		(layers "F.Cu" "B.Cu" "In1.Cu" "In2.Cu" "In3.Cu" "In4.Cu" "In5.Cu" "In6.Cu"
			"In7.Cu" "In8.Cu" "In9.Cu" "In10.Cu" "In11.Cu" "In12.Cu" "In13.Cu" "In14.Cu"
			"In15.Cu" "In16.Cu"
		)
		(hatch none 0.5)
		(connect_pads
			(clearance 0)
		)
		(min_thickness 0.25)
		(keepout
			(tracks not_allowed)
			(vias allowed)
			(pads allowed)
			(copperpour not_allowed)
			(footprints allowed)
		)
		(placement
			(enabled no)
			(sheetname "")
		)
		(fill
			(thermal_gap 0.5)
			(thermal_bridge_width 0.5)
			(island_removal_mode 0)
		)
		(polygon
			(pts
				(arc
					(start 15.533878 -17.23136)
					(mid 15.152878 -17.61236)
					(end 15.533878 -17.99336)
				)
				(arc
					(start 16.397478 -17.99336)
					(mid 16.778478 -17.61236)
					(end 16.397478 -17.23136)
				)
			)
		)
	)
	(zone
		(layers "F.Cu" "B.Cu" "In1.Cu" "In2.Cu" "In3.Cu" "In4.Cu" "In5.Cu" "In6.Cu"
			"In7.Cu" "In8.Cu" "In9.Cu" "In10.Cu" "In11.Cu" "In12.Cu" "In13.Cu" "In14.Cu"
			"In15.Cu" "In16.Cu"
		)
		(hatch none 0.5)
		(connect_pads
			(clearance 0)
		)
		(min_thickness 0.25)
		(keepout
			(tracks not_allowed)
			(vias allowed)
			(pads allowed)
			(copperpour not_allowed)
			(footprints allowed)
		)
		(placement
			(enabled no)
			(sheetname "")
		)
		(fill
			(thermal_gap 0.5)
			(thermal_bridge_width 0.5)
			(island_removal_mode 0)
		)
		(polygon
			(pts
				(arc
					(start 352.500946 -276.708616)
					(mid 351.843086 -276.708616)
					(end 352.500946 -276.708616)
				)
			)
		)
	)
	(zone
		(layers "F.Cu" "B.Cu" "In1.Cu" "In2.Cu" "In3.Cu" "In4.Cu" "In5.Cu" "In6.Cu"
			"In7.Cu" "In8.Cu" "In9.Cu" "In10.Cu" "In11.Cu" "In12.Cu" "In13.Cu" "In14.Cu"
			"In15.Cu" "In16.Cu"
		)
		(hatch none 0.5)
		(connect_pads
			(clearance 0)
		)
		(min_thickness 0.25)
		(keepout
			(tracks not_allowed)
			(vias allowed)
			(pads allowed)
			(copperpour not_allowed)
			(footprints allowed)
		)
		(placement
			(enabled no)
			(sheetname "")
		)
		(fill
			(thermal_gap 0.5)
			(thermal_bridge_width 0.5)
			(island_removal_mode 0)
		)
		(polygon
			(pts
				(arc
					(start 99.861878 -286.475424)
					(mid 99.204018 -286.475424)
					(end 99.861878 -286.475424)
				)
			)
		)
	)
	(zone
		(layers "F.Cu" "B.Cu" "In1.Cu" "In2.Cu" "In3.Cu" "In4.Cu" "In5.Cu" "In6.Cu"
			"In7.Cu" "In8.Cu" "In9.Cu" "In10.Cu" "In11.Cu" "In12.Cu" "In13.Cu" "In14.Cu"
			"In15.Cu" "In16.Cu"
		)
		(hatch none 0.5)
		(connect_pads
			(clearance 0)
		)
		(min_thickness 0.25)
		(keepout
			(tracks not_allowed)
			(vias allowed)
			(pads allowed)
			(copperpour not_allowed)
			(footprints allowed)
		)
		(placement
			(enabled no)
			(sheetname "")
		)
		(fill
			(thermal_gap 0.5)
			(thermal_bridge_width 0.5)
			(island_removal_mode 0)
		)
		(polygon
			(pts
				(arc
					(start 109.619542 -223.575626)
					(mid 108.961682 -223.575626)
					(end 109.619542 -223.575626)
				)
			)
		)
	)
	(zone
		(layers "F.Cu" "B.Cu" "In1.Cu" "In2.Cu" "In3.Cu" "In4.Cu" "In5.Cu" "In6.Cu"
			"In7.Cu" "In8.Cu" "In9.Cu" "In10.Cu" "In11.Cu" "In12.Cu" "In13.Cu" "In14.Cu"
			"In15.Cu" "In16.Cu"
		)
		(hatch none 0.5)
		(connect_pads
			(clearance 0)
		)
		(min_thickness 0.25)
		(keepout
			(tracks not_allowed)
			(vias allowed)
			(pads allowed)
			(copperpour not_allowed)
			(footprints allowed)
		)
		(placement
			(enabled no)
			(sheetname "")
		)
		(fill
			(thermal_gap 0.5)
			(thermal_bridge_width 0.5)
			(island_removal_mode 0)
		)
		(polygon
			(pts
				(arc
					(start 110.841282 -215.436704)
					(mid 111.499142 -215.436704)
					(end 110.841282 -215.436704)
				)
			)
		)
	)
	(zone
		(layers "F.Cu" "B.Cu" "In1.Cu" "In2.Cu" "In3.Cu" "In4.Cu" "In5.Cu" "In6.Cu"
			"In7.Cu" "In8.Cu" "In9.Cu" "In10.Cu" "In11.Cu" "In12.Cu" "In13.Cu" "In14.Cu"
			"In15.Cu" "In16.Cu"
		)
		(hatch none 0.5)
		(connect_pads
			(clearance 0)
		)
		(min_thickness 0.25)
		(keepout
			(tracks not_allowed)
			(vias allowed)
			(pads allowed)
			(copperpour not_allowed)
			(footprints allowed)
		)
		(placement
			(enabled no)
			(sheetname "")
		)
		(fill
			(thermal_gap 0.5)
			(thermal_bridge_width 0.5)
			(island_removal_mode 0)
		)
		(polygon
			(pts
				(arc
					(start 90.275918 -285.661354)
					(mid 90.933778 -285.661354)
					(end 90.275918 -285.661354)
				)
			)
		)
	)
	(zone
		(layers "F.Cu" "B.Cu" "In1.Cu" "In2.Cu" "In3.Cu" "In4.Cu" "In5.Cu" "In6.Cu"
			"In7.Cu" "In8.Cu" "In9.Cu" "In10.Cu" "In11.Cu" "In12.Cu" "In13.Cu" "In14.Cu"
			"In15.Cu" "In16.Cu"
		)
		(hatch none 0.5)
		(connect_pads
			(clearance 0)
		)
		(min_thickness 0.25)
		(keepout
			(tracks not_allowed)
			(vias allowed)
			(pads allowed)
			(copperpour not_allowed)
			(footprints allowed)
		)
		(placement
			(enabled no)
			(sheetname "")
		)
		(fill
			(thermal_gap 0.5)
			(thermal_bridge_width 0.5)
			(island_removal_mode 0)
		)
		(polygon
			(pts
				(arc
					(start 99.362514 -283.121608)
					(mid 99.34283 -283.169018)
					(end 99.336098 -283.219906)
				)
				(arc
					(start 99.336098 -283.219906)
					(mid 99.393754 -283.3591)
					(end 99.532948 -283.416756)
				)
				(arc
					(start 99.532948 -283.416756)
					(mid 99.631379 -283.39034)
					(end 99.703382 -283.318204)
				)
				(arc
					(start 100.173282 -282.504134)
					(mid 100.192966 -282.456724)
					(end 100.199698 -282.405836)
				)
				(arc
					(start 100.199698 -282.405836)
					(mid 100.142042 -282.266642)
					(end 100.002848 -282.208986)
				)
				(arc
					(start 100.002848 -282.208986)
					(mid 99.904417 -282.235402)
					(end 99.832414 -282.307538)
				)
			)
		)
	)
	(zone
		(layers "F.Cu" "B.Cu" "In1.Cu" "In2.Cu" "In3.Cu" "In4.Cu" "In5.Cu" "In6.Cu"
			"In7.Cu" "In8.Cu" "In9.Cu" "In10.Cu" "In11.Cu" "In12.Cu" "In13.Cu" "In14.Cu"
			"In15.Cu" "In16.Cu"
		)
		(hatch none 0.5)
		(connect_pads
			(clearance 0)
		)
		(min_thickness 0.25)
		(keepout
			(tracks not_allowed)
			(vias allowed)
			(pads allowed)
			(copperpour not_allowed)
			(footprints allowed)
		)
		(placement
			(enabled no)
			(sheetname "")
		)
		(fill
			(thermal_gap 0.5)
			(thermal_bridge_width 0.5)
			(island_removal_mode 0)
		)
		(polygon
			(pts
				(arc
					(start 326.768968 -406.62352)
					(mid 326.387968 -407.00452)
					(end 326.768968 -407.38552)
				)
				(arc
					(start 327.632568 -407.38552)
					(mid 328.013568 -407.00452)
					(end 327.632568 -406.62352)
				)
			)
		)
	)
	(zone
		(layers "F.Cu" "B.Cu" "In1.Cu" "In2.Cu" "In3.Cu" "In4.Cu" "In5.Cu" "In6.Cu"
			"In7.Cu" "In8.Cu" "In9.Cu" "In10.Cu" "In11.Cu" "In12.Cu" "In13.Cu" "In14.Cu"
			"In15.Cu" "In16.Cu"
		)
		(hatch none 0.5)
		(connect_pads
			(clearance 0)
		)
		(min_thickness 0.25)
		(keepout
			(tracks not_allowed)
			(vias allowed)
			(pads allowed)
			(copperpour not_allowed)
			(footprints allowed)
		)
		(placement
			(enabled no)
			(sheetname "")
		)
		(fill
			(thermal_gap 0.5)
			(thermal_bridge_width 0.5)
			(island_removal_mode 0)
		)
		(polygon
			(pts
				(arc
					(start 230.87838 -57.443116)
					(mid 230.49738 -57.062116)
					(end 230.11638 -57.443116)
				)
				(arc
					(start 230.11638 -58.306716)
					(mid 230.49738 -58.687716)
					(end 230.87838 -58.306716)
				)
			)
		)
	)
	(zone
		(layers "F.Cu" "B.Cu" "In1.Cu" "In2.Cu" "In3.Cu" "In4.Cu" "In5.Cu" "In6.Cu"
			"In7.Cu" "In8.Cu" "In9.Cu" "In10.Cu" "In11.Cu" "In12.Cu" "In13.Cu" "In14.Cu"
			"In15.Cu" "In16.Cu"
		)
		(hatch none 0.5)
		(connect_pads
			(clearance 0)
		)
		(min_thickness 0.25)
		(keepout
			(tracks not_allowed)
			(vias allowed)
			(pads allowed)
			(copperpour not_allowed)
			(footprints allowed)
		)
		(placement
			(enabled no)
			(sheetname "")
		)
		(fill
			(thermal_gap 0.5)
			(thermal_bridge_width 0.5)
			(island_removal_mode 0)
		)
		(polygon
			(pts
				(arc
					(start 368.83721 -223.575626)
					(mid 368.17935 -223.575626)
					(end 368.83721 -223.575626)
				)
			)
		)
	)
	(zone
		(layers "F.Cu" "B.Cu" "In1.Cu" "In2.Cu" "In3.Cu" "In4.Cu" "In5.Cu" "In6.Cu"
			"In7.Cu" "In8.Cu" "In9.Cu" "In10.Cu" "In11.Cu" "In12.Cu" "In13.Cu" "In14.Cu"
			"In15.Cu" "In16.Cu"
		)
		(hatch none 0.5)
		(connect_pads
			(clearance 0)
		)
		(min_thickness 0.25)
		(keepout
			(tracks not_allowed)
			(vias allowed)
			(pads allowed)
			(copperpour not_allowed)
			(footprints allowed)
		)
		(placement
			(enabled no)
			(sheetname "")
		)
		(fill
			(thermal_gap 0.5)
			(thermal_bridge_width 0.5)
			(island_removal_mode 0)
		)
		(polygon
			(pts
				(arc
					(start 229.445566 -130.23342)
					(mid 229.064566 -129.85242)
					(end 228.683566 -130.23342)
				)
				(arc
					(start 228.683566 -131.09702)
					(mid 229.064566 -131.47802)
					(end 229.445566 -131.09702)
				)
			)
		)
	)
	(zone
		(layers "F.Cu" "B.Cu" "In1.Cu" "In2.Cu" "In3.Cu" "In4.Cu" "In5.Cu" "In6.Cu"
			"In7.Cu" "In8.Cu" "In9.Cu" "In10.Cu" "In11.Cu" "In12.Cu" "In13.Cu" "In14.Cu"
			"In15.Cu" "In16.Cu"
		)
		(hatch none 0.5)
		(connect_pads
			(clearance 0)
		)
		(min_thickness 0.25)
		(keepout
			(tracks not_allowed)
			(vias allowed)
			(pads allowed)
			(copperpour not_allowed)
			(footprints allowed)
		)
		(placement
			(enabled no)
			(sheetname "")
		)
		(fill
			(thermal_gap 0.5)
			(thermal_bridge_width 0.5)
			(island_removal_mode 0)
		)
		(polygon
			(pts
				(arc
					(start 354.270056 -214.622634)
					(mid 353.612196 -214.622634)
					(end 354.270056 -214.622634)
				)
			)
		)
	)
	(zone
		(layers "F.Cu" "B.Cu" "In1.Cu" "In2.Cu" "In3.Cu" "In4.Cu" "In5.Cu" "In6.Cu"
			"In7.Cu" "In8.Cu" "In9.Cu" "In10.Cu" "In11.Cu" "In12.Cu" "In13.Cu" "In14.Cu"
			"In15.Cu" "In16.Cu"
		)
		(hatch none 0.5)
		(connect_pads
			(clearance 0)
		)
		(min_thickness 0.25)
		(keepout
			(tracks not_allowed)
			(vias allowed)
			(pads allowed)
			(copperpour not_allowed)
			(footprints allowed)
		)
		(placement
			(enabled no)
			(sheetname "")
		)
		(fill
			(thermal_gap 0.5)
			(thermal_bridge_width 0.5)
			(island_removal_mode 0)
		)
		(polygon
			(pts
				(arc
					(start 297.13428 -161.176208)
					(mid 296.75328 -161.557208)
					(end 297.13428 -161.938208)
				)
				(arc
					(start 297.99788 -161.938208)
					(mid 298.37888 -161.557208)
					(end 297.99788 -161.176208)
				)
			)
		)
	)
	(zone
		(layers "F.Cu" "B.Cu" "In1.Cu" "In2.Cu" "In3.Cu" "In4.Cu" "In5.Cu" "In6.Cu"
			"In7.Cu" "In8.Cu" "In9.Cu" "In10.Cu" "In11.Cu" "In12.Cu" "In13.Cu" "In14.Cu"
			"In15.Cu" "In16.Cu"
		)
		(hatch none 0.5)
		(connect_pads
			(clearance 0)
		)
		(min_thickness 0.25)
		(keepout
			(tracks not_allowed)
			(vias allowed)
			(pads allowed)
			(copperpour not_allowed)
			(footprints allowed)
		)
		(placement
			(enabled no)
			(sheetname "")
		)
		(fill
			(thermal_gap 0.5)
			(thermal_bridge_width 0.5)
			(island_removal_mode 0)
		)
		(polygon
			(pts
				(arc
					(start 349.882714 -217.162634)
					(mid 349.902398 -217.115224)
					(end 349.90913 -217.064336)
				)
				(arc
					(start 349.90913 -217.064336)
					(mid 349.851474 -216.925142)
					(end 349.71228 -216.867486)
				)
				(arc
					(start 349.71228 -216.867486)
					(mid 349.613849 -216.893902)
					(end 349.541846 -216.966038)
				)
				(arc
					(start 349.0722 -217.780108)
					(mid 349.052516 -217.827518)
					(end 349.045784 -217.878406)
				)
				(arc
					(start 349.045784 -217.878406)
					(mid 349.10344 -218.0176)
					(end 349.242634 -218.075256)
				)
				(arc
					(start 349.242634 -218.075256)
					(mid 349.341065 -218.04884)
					(end 349.413068 -217.976704)
				)
			)
		)
	)
	(zone
		(layers "F.Cu" "B.Cu" "In1.Cu" "In2.Cu" "In3.Cu" "In4.Cu" "In5.Cu" "In6.Cu"
			"In7.Cu" "In8.Cu" "In9.Cu" "In10.Cu" "In11.Cu" "In12.Cu" "In13.Cu" "In14.Cu"
			"In15.Cu" "In16.Cu"
		)
		(hatch none 0.5)
		(connect_pads
			(clearance 0)
		)
		(min_thickness 0.25)
		(keepout
			(tracks not_allowed)
			(vias allowed)
			(pads allowed)
			(copperpour not_allowed)
			(footprints allowed)
		)
		(placement
			(enabled no)
			(sheetname "")
		)
		(fill
			(thermal_gap 0.5)
			(thermal_bridge_width 0.5)
			(island_removal_mode 0)
		)
		(polygon
			(pts
				(arc
					(start 398.99209 -403.502876)
					(mid 398.61109 -403.883876)
					(end 398.99209 -404.264876)
				)
				(arc
					(start 399.85569 -404.264876)
					(mid 400.23669 -403.883876)
					(end 399.85569 -403.502876)
				)
			)
		)
	)
	(zone
		(layers "F.Cu" "B.Cu" "In1.Cu" "In2.Cu" "In3.Cu" "In4.Cu" "In5.Cu" "In6.Cu"
			"In7.Cu" "In8.Cu" "In9.Cu" "In10.Cu" "In11.Cu" "In12.Cu" "In13.Cu" "In14.Cu"
			"In15.Cu" "In16.Cu"
		)
		(hatch none 0.5)
		(connect_pads
			(clearance 0)
		)
		(min_thickness 0.25)
		(keepout
			(tracks not_allowed)
			(vias allowed)
			(pads allowed)
			(copperpour not_allowed)
			(footprints allowed)
		)
		(placement
			(enabled no)
			(sheetname "")
		)
		(fill
			(thermal_gap 0.5)
			(thermal_bridge_width 0.5)
			(island_removal_mode 0)
		)
		(polygon
			(pts
				(arc
					(start 383.984246 -288.917126)
					(mid 383.326386 -288.917126)
					(end 383.984246 -288.917126)
				)
			)
		)
	)
	(zone
		(layers "F.Cu" "B.Cu" "In1.Cu" "In2.Cu" "In3.Cu" "In4.Cu" "In5.Cu" "In6.Cu"
			"In7.Cu" "In8.Cu" "In9.Cu" "In10.Cu" "In11.Cu" "In12.Cu" "In13.Cu" "In14.Cu"
			"In15.Cu" "In16.Cu"
		)
		(hatch none 0.5)
		(connect_pads
			(clearance 0)
		)
		(min_thickness 0.25)
		(keepout
			(tracks not_allowed)
			(vias allowed)
			(pads allowed)
			(copperpour not_allowed)
			(footprints allowed)
		)
		(placement
			(enabled no)
			(sheetname "")
		)
		(fill
			(thermal_gap 0.5)
			(thermal_bridge_width 0.5)
			(island_removal_mode 0)
		)
		(polygon
			(pts
				(arc
					(start 127.945896 -217.878406)
					(mid 127.288036 -217.878406)
					(end 127.945896 -217.878406)
				)
			)
		)
	)
	(zone
		(layers "F.Cu" "B.Cu" "In1.Cu" "In2.Cu" "In3.Cu" "In4.Cu" "In5.Cu" "In6.Cu"
			"In7.Cu" "In8.Cu" "In9.Cu" "In10.Cu" "In11.Cu" "In12.Cu" "In13.Cu" "In14.Cu"
			"In15.Cu" "In16.Cu"
		)
		(hatch none 0.5)
		(connect_pads
			(clearance 0)
		)
		(min_thickness 0.25)
		(keepout
			(tracks not_allowed)
			(vias allowed)
			(pads allowed)
			(copperpour not_allowed)
			(footprints allowed)
		)
		(placement
			(enabled no)
			(sheetname "")
		)
		(fill
			(thermal_gap 0.5)
			(thermal_bridge_width 0.5)
			(island_removal_mode 0)
		)
		(polygon
			(pts
				(arc
					(start 135.642858 -297.515026)
					(mid 131.196842 -297.515026)
					(end 135.642858 -297.515026)
				)
			)
		)
	)
	(zone
		(layers "F.Cu" "B.Cu" "In1.Cu" "In2.Cu" "In3.Cu" "In4.Cu" "In5.Cu" "In6.Cu"
			"In7.Cu" "In8.Cu" "In9.Cu" "In10.Cu" "In11.Cu" "In12.Cu" "In13.Cu" "In14.Cu"
			"In15.Cu" "In16.Cu"
		)
		(hatch none 0.5)
		(connect_pads
			(clearance 0)
		)
		(min_thickness 0.25)
		(keepout
			(tracks not_allowed)
			(vias allowed)
			(pads allowed)
			(copperpour not_allowed)
			(footprints allowed)
		)
		(placement
			(enabled no)
			(sheetname "")
		)
		(fill
			(thermal_gap 0.5)
			(thermal_bridge_width 0.5)
			(island_removal_mode 0)
		)
		(polygon
			(pts
				(arc
					(start 355.789992 -277.522432)
					(mid 355.132132 -277.522432)
					(end 355.789992 -277.522432)
				)
			)
		)
	)
	(zone
		(layers "F.Cu" "B.Cu" "In1.Cu" "In2.Cu" "In3.Cu" "In4.Cu" "In5.Cu" "In6.Cu"
			"In7.Cu" "In8.Cu" "In9.Cu" "In10.Cu" "In11.Cu" "In12.Cu" "In13.Cu" "In14.Cu"
			"In15.Cu" "In16.Cu"
		)
		(hatch none 0.5)
		(connect_pads
			(clearance 0)
		)
		(min_thickness 0.25)
		(keepout
			(tracks not_allowed)
			(vias allowed)
			(pads allowed)
			(copperpour not_allowed)
			(footprints allowed)
		)
		(placement
			(enabled no)
			(sheetname "")
		)
		(fill
			(thermal_gap 0.5)
			(thermal_bridge_width 0.5)
			(island_removal_mode 0)
		)
		(polygon
			(pts
				(arc
					(start 111.029496 -214.546434)
					(mid 110.371636 -214.546434)
					(end 111.029496 -214.546434)
				)
			)
		)
	)
	(zone
		(layers "F.Cu" "B.Cu" "In1.Cu" "In2.Cu" "In3.Cu" "In4.Cu" "In5.Cu" "In6.Cu"
			"In7.Cu" "In8.Cu" "In9.Cu" "In10.Cu" "In11.Cu" "In12.Cu" "In13.Cu" "In14.Cu"
			"In15.Cu" "In16.Cu"
		)
		(hatch none 0.5)
		(connect_pads
			(clearance 0)
		)
		(min_thickness 0.25)
		(keepout
			(tracks not_allowed)
			(vias allowed)
			(pads allowed)
			(copperpour not_allowed)
			(footprints allowed)
		)
		(placement
			(enabled no)
			(sheetname "")
		)
		(fill
			(thermal_gap 0.5)
			(thermal_bridge_width 0.5)
			(island_removal_mode 0)
		)
		(polygon
			(pts
				(arc
					(start 97.684082 -220.319854)
					(mid 98.341942 -220.319854)
					(end 97.684082 -220.319854)
				)
			)
		)
	)
	(zone
		(layers "F.Cu" "B.Cu" "In1.Cu" "In2.Cu" "In3.Cu" "In4.Cu" "In5.Cu" "In6.Cu"
			"In7.Cu" "In8.Cu" "In9.Cu" "In10.Cu" "In11.Cu" "In12.Cu" "In13.Cu" "In14.Cu"
			"In15.Cu" "In16.Cu"
		)
		(hatch none 0.5)
		(connect_pads
			(clearance 0)
		)
		(min_thickness 0.25)
		(keepout
			(tracks not_allowed)
			(vias allowed)
			(pads allowed)
			(copperpour not_allowed)
			(footprints allowed)
		)
		(placement
			(enabled no)
			(sheetname "")
		)
		(fill
			(thermal_gap 0.5)
			(thermal_bridge_width 0.5)
			(island_removal_mode 0)
		)
		(polygon
			(pts
				(arc
					(start 333.013558 -82.421984)
					(mid 333.394558 -82.040984)
					(end 333.013558 -81.659984)
				)
				(arc
					(start 332.149958 -81.659984)
					(mid 331.768958 -82.040984)
					(end 332.149958 -82.421984)
				)
			)
		)
	)
	(zone
		(layers "F.Cu" "B.Cu" "In1.Cu" "In2.Cu" "In3.Cu" "In4.Cu" "In5.Cu" "In6.Cu"
			"In7.Cu" "In8.Cu" "In9.Cu" "In10.Cu" "In11.Cu" "In12.Cu" "In13.Cu" "In14.Cu"
			"In15.Cu" "In16.Cu"
		)
		(hatch none 0.5)
		(connect_pads
			(clearance 0)
		)
		(min_thickness 0.25)
		(keepout
			(tracks not_allowed)
			(vias allowed)
			(pads allowed)
			(copperpour not_allowed)
			(footprints allowed)
		)
		(placement
			(enabled no)
			(sheetname "")
		)
		(fill
			(thermal_gap 0.5)
			(thermal_bridge_width 0.5)
			(island_removal_mode 0)
		)
		(polygon
			(pts
				(arc
					(start 381.05461 -225.203258)
					(mid 380.39675 -225.203258)
					(end 381.05461 -225.203258)
				)
			)
		)
	)
	(zone
		(layers "F.Cu" "B.Cu" "In1.Cu" "In2.Cu" "In3.Cu" "In4.Cu" "In5.Cu" "In6.Cu"
			"In7.Cu" "In8.Cu" "In9.Cu" "In10.Cu" "In11.Cu" "In12.Cu" "In13.Cu" "In14.Cu"
			"In15.Cu" "In16.Cu"
		)
		(hatch none 0.5)
		(connect_pads
			(clearance 0)
		)
		(min_thickness 0.25)
		(keepout
			(tracks not_allowed)
			(vias allowed)
			(pads allowed)
			(copperpour not_allowed)
			(footprints allowed)
		)
		(placement
			(enabled no)
			(sheetname "")
		)
		(fill
			(thermal_gap 0.5)
			(thermal_bridge_width 0.5)
			(island_removal_mode 0)
		)
		(polygon
			(pts
				(arc
					(start 233.945938 -117.224048)
					(mid 233.564938 -117.605048)
					(end 233.945938 -117.986048)
				)
				(arc
					(start 234.809538 -117.986048)
					(mid 235.190538 -117.605048)
					(end 234.809538 -117.224048)
				)
			)
		)
	)
	(zone
		(layers "F.Cu" "B.Cu" "In1.Cu" "In2.Cu" "In3.Cu" "In4.Cu" "In5.Cu" "In6.Cu"
			"In7.Cu" "In8.Cu" "In9.Cu" "In10.Cu" "In11.Cu" "In12.Cu" "In13.Cu" "In14.Cu"
			"In15.Cu" "In16.Cu"
		)
		(hatch none 0.5)
		(connect_pads
			(clearance 0)
		)
		(min_thickness 0.25)
		(keepout
			(tracks not_allowed)
			(vias allowed)
			(pads allowed)
			(copperpour not_allowed)
			(footprints allowed)
		)
		(placement
			(enabled no)
			(sheetname "")
		)
		(fill
			(thermal_gap 0.5)
			(thermal_bridge_width 0.5)
			(island_removal_mode 0)
		)
		(polygon
			(pts
				(arc
					(start 337.43392 -82.652108)
					(mid 337.81492 -82.271108)
					(end 337.43392 -81.890108)
				)
				(arc
					(start 336.57032 -81.890108)
					(mid 336.18932 -82.271108)
					(end 336.57032 -82.652108)
				)
			)
		)
	)
	(zone
		(layers "F.Cu" "B.Cu" "In1.Cu" "In2.Cu" "In3.Cu" "In4.Cu" "In5.Cu" "In6.Cu"
			"In7.Cu" "In8.Cu" "In9.Cu" "In10.Cu" "In11.Cu" "In12.Cu" "In13.Cu" "In14.Cu"
			"In15.Cu" "In16.Cu"
		)
		(hatch none 0.5)
		(connect_pads
			(clearance 0)
		)
		(min_thickness 0.25)
		(keepout
			(tracks not_allowed)
			(vias allowed)
			(pads allowed)
			(copperpour not_allowed)
			(footprints allowed)
		)
		(placement
			(enabled no)
			(sheetname "")
		)
		(fill
			(thermal_gap 0.5)
			(thermal_bridge_width 0.5)
			(island_removal_mode 0)
		)
		(polygon
			(pts
				(arc
					(start 380.584964 -221.133924)
					(mid 379.927104 -221.133924)
					(end 380.584964 -221.133924)
				)
			)
		)
	)
	(zone
		(layers "F.Cu" "B.Cu" "In1.Cu" "In2.Cu" "In3.Cu" "In4.Cu" "In5.Cu" "In6.Cu"
			"In7.Cu" "In8.Cu" "In9.Cu" "In10.Cu" "In11.Cu" "In12.Cu" "In13.Cu" "In14.Cu"
			"In15.Cu" "In16.Cu"
		)
		(hatch none 0.5)
		(connect_pads
			(clearance 0)
		)
		(min_thickness 0.25)
		(keepout
			(tracks not_allowed)
			(vias allowed)
			(pads allowed)
			(copperpour not_allowed)
			(footprints allowed)
		)
		(placement
			(enabled no)
			(sheetname "")
		)
		(fill
			(thermal_gap 0.5)
			(thermal_bridge_width 0.5)
			(island_removal_mode 0)
		)
		(polygon
			(pts
				(arc
					(start 352.500946 -284.847538)
					(mid 351.843086 -284.847538)
					(end 352.500946 -284.847538)
				)
			)
		)
	)
	(zone
		(layers "F.Cu" "B.Cu" "In1.Cu" "In2.Cu" "In3.Cu" "In4.Cu" "In5.Cu" "In6.Cu"
			"In7.Cu" "In8.Cu" "In9.Cu" "In10.Cu" "In11.Cu" "In12.Cu" "In13.Cu" "In14.Cu"
			"In15.Cu" "In16.Cu"
		)
		(hatch none 0.5)
		(connect_pads
			(clearance 0)
		)
		(min_thickness 0.25)
		(keepout
			(tracks not_allowed)
			(vias allowed)
			(pads allowed)
			(copperpour not_allowed)
			(footprints allowed)
		)
		(placement
			(enabled no)
			(sheetname "")
		)
		(fill
			(thermal_gap 0.5)
			(thermal_bridge_width 0.5)
			(island_removal_mode 0)
		)
		(polygon
			(pts
				(arc
					(start 57.169558 -403.502876)
					(mid 56.788558 -403.883876)
					(end 57.169558 -404.264876)
				)
				(arc
					(start 58.033158 -404.264876)
					(mid 58.414158 -403.883876)
					(end 58.033158 -403.502876)
				)
			)
		)
	)
	(zone
		(layers "F.Cu" "B.Cu" "In1.Cu" "In2.Cu" "In3.Cu" "In4.Cu" "In5.Cu" "In6.Cu"
			"In7.Cu" "In8.Cu" "In9.Cu" "In10.Cu" "In11.Cu" "In12.Cu" "In13.Cu" "In14.Cu"
			"In15.Cu" "In16.Cu"
		)
		(hatch none 0.5)
		(connect_pads
			(clearance 0)
		)
		(min_thickness 0.25)
		(keepout
			(tracks not_allowed)
			(vias allowed)
			(pads allowed)
			(copperpour not_allowed)
			(footprints allowed)
		)
		(placement
			(enabled no)
			(sheetname "")
		)
		(fill
			(thermal_gap 0.5)
			(thermal_bridge_width 0.5)
			(island_removal_mode 0)
		)
		(polygon
			(pts
				(arc
					(start 35.462972 -153.766012)
					(mid 24.446992 -153.766012)
					(end 35.462972 -153.766012)
				)
			)
		)
	)
	(zone
		(layers "F.Cu" "B.Cu" "In1.Cu" "In2.Cu" "In3.Cu" "In4.Cu" "In5.Cu" "In6.Cu"
			"In7.Cu" "In8.Cu" "In9.Cu" "In10.Cu" "In11.Cu" "In12.Cu" "In13.Cu" "In14.Cu"
			"In15.Cu" "In16.Cu"
		)
		(hatch none 0.5)
		(connect_pads
			(clearance 0)
		)
		(min_thickness 0.25)
		(keepout
			(tracks not_allowed)
			(vias allowed)
			(pads allowed)
			(copperpour not_allowed)
			(footprints allowed)
		)
		(placement
			(enabled no)
			(sheetname "")
		)
		(fill
			(thermal_gap 0.5)
			(thermal_bridge_width 0.5)
			(island_removal_mode 0)
		)
		(polygon
			(pts
				(arc
					(start 362.570014 -217.97645)
					(mid 362.589698 -217.92904)
					(end 362.59643 -217.878152)
				)
				(arc
					(start 362.59643 -217.878152)
					(mid 362.538774 -217.738958)
					(end 362.39958 -217.681302)
				)
				(arc
					(start 362.39958 -217.681302)
					(mid 362.301149 -217.707718)
					(end 362.229146 -217.779854)
				)
				(arc
					(start 361.7595 -218.593924)
					(mid 361.739816 -218.641334)
					(end 361.733084 -218.692222)
				)
				(arc
					(start 361.733084 -218.692222)
					(mid 361.79074 -218.831416)
					(end 361.929934 -218.889072)
				)
				(arc
					(start 361.929934 -218.889072)
					(mid 362.028365 -218.862656)
					(end 362.100368 -218.79052)
				)
			)
		)
	)
	(zone
		(layers "F.Cu" "B.Cu" "In1.Cu" "In2.Cu" "In3.Cu" "In4.Cu" "In5.Cu" "In6.Cu"
			"In7.Cu" "In8.Cu" "In9.Cu" "In10.Cu" "In11.Cu" "In12.Cu" "In13.Cu" "In14.Cu"
			"In15.Cu" "In16.Cu"
		)
		(hatch none 0.5)
		(connect_pads
			(clearance 0)
		)
		(min_thickness 0.25)
		(keepout
			(tracks not_allowed)
			(vias allowed)
			(pads allowed)
			(copperpour not_allowed)
			(footprints allowed)
		)
		(placement
			(enabled no)
			(sheetname "")
		)
		(fill
			(thermal_gap 0.5)
			(thermal_bridge_width 0.5)
			(island_removal_mode 0)
		)
		(polygon
			(pts
				(arc
					(start 133.725412 -215.239854)
					(mid 133.528562 -215.436704)
					(end 133.725412 -215.633554)
				)
				(arc
					(start 134.665212 -215.633554)
					(mid 134.862062 -215.436704)
					(end 134.665212 -215.239854)
				)
			)
		)
	)
	(zone
		(layers "F.Cu" "B.Cu" "In1.Cu" "In2.Cu" "In3.Cu" "In4.Cu" "In5.Cu" "In6.Cu"
			"In7.Cu" "In8.Cu" "In9.Cu" "In10.Cu" "In11.Cu" "In12.Cu" "In13.Cu" "In14.Cu"
			"In15.Cu" "In16.Cu"
		)
		(hatch none 0.5)
		(connect_pads
			(clearance 0)
		)
		(min_thickness 0.25)
		(keepout
			(tracks not_allowed)
			(vias allowed)
			(pads allowed)
			(copperpour not_allowed)
			(footprints allowed)
		)
		(placement
			(enabled no)
			(sheetname "")
		)
		(fill
			(thermal_gap 0.5)
			(thermal_bridge_width 0.5)
			(island_removal_mode 0)
		)
		(polygon
			(pts
				(arc
					(start 432.311048 -66.06794)
					(mid 426.803058 -60.55995)
					(end 421.295068 -66.06794)
				)
				(arc
					(start 421.295068 -74.767948)
					(mid 426.803058 -80.275938)
					(end 432.311048 -74.767948)
				)
			)
		)
	)
	(zone
		(layers "F.Cu" "B.Cu" "In1.Cu" "In2.Cu" "In3.Cu" "In4.Cu" "In5.Cu" "In6.Cu"
			"In7.Cu" "In8.Cu" "In9.Cu" "In10.Cu" "In11.Cu" "In12.Cu" "In13.Cu" "In14.Cu"
			"In15.Cu" "In16.Cu"
		)
		(hatch none 0.5)
		(connect_pads
			(clearance 0)
		)
		(min_thickness 0.25)
		(keepout
			(tracks not_allowed)
			(vias allowed)
			(pads allowed)
			(copperpour not_allowed)
			(footprints allowed)
		)
		(placement
			(enabled no)
			(sheetname "")
		)
		(fill
			(thermal_gap 0.5)
			(thermal_bridge_width 0.5)
			(island_removal_mode 0)
		)
		(polygon
			(pts
				(arc
					(start 303.980088 -403.502876)
					(mid 303.599088 -403.883876)
					(end 303.980088 -404.264876)
				)
				(arc
					(start 304.843688 -404.264876)
					(mid 305.224688 -403.883876)
					(end 304.843688 -403.502876)
				)
			)
		)
	)
	(zone
		(layers "F.Cu" "B.Cu" "In1.Cu" "In2.Cu" "In3.Cu" "In4.Cu" "In5.Cu" "In6.Cu"
			"In7.Cu" "In8.Cu" "In9.Cu" "In10.Cu" "In11.Cu" "In12.Cu" "In13.Cu" "In14.Cu"
			"In15.Cu" "In16.Cu"
		)
		(hatch none 0.5)
		(connect_pads
			(clearance 0)
		)
		(min_thickness 0.25)
		(keepout
			(tracks not_allowed)
			(vias allowed)
			(pads allowed)
			(copperpour not_allowed)
			(footprints allowed)
		)
		(placement
			(enabled no)
			(sheetname "")
		)
		(fill
			(thermal_gap 0.5)
			(thermal_bridge_width 0.5)
			(island_removal_mode 0)
		)
		(polygon
			(pts
				(arc
					(start 110.86338 -214.460582)
					(mid 110.795672 -214.388731)
					(end 110.700566 -214.362284)
				)
				(arc
					(start 110.700566 -214.362284)
					(mid 110.570352 -214.41622)
					(end 110.516416 -214.546434)
				)
				(arc
					(start 110.516416 -214.546434)
					(mid 110.521867 -214.590655)
					(end 110.537752 -214.632286)
				)
				(arc
					(start 111.007398 -215.522556)
					(mid 111.075106 -215.594407)
					(end 111.170212 -215.620854)
				)
				(arc
					(start 111.170212 -215.620854)
					(mid 111.300426 -215.566918)
					(end 111.354362 -215.436704)
				)
				(arc
					(start 111.354362 -215.436704)
					(mid 111.348911 -215.392483)
					(end 111.333026 -215.350852)
				)
			)
		)
	)
	(zone
		(layers "F.Cu" "B.Cu" "In1.Cu" "In2.Cu" "In3.Cu" "In4.Cu" "In5.Cu" "In6.Cu"
			"In7.Cu" "In8.Cu" "In9.Cu" "In10.Cu" "In11.Cu" "In12.Cu" "In13.Cu" "In14.Cu"
			"In15.Cu" "In16.Cu"
		)
		(hatch none 0.5)
		(connect_pads
			(clearance 0)
		)
		(min_thickness 0.25)
		(keepout
			(tracks not_allowed)
			(vias allowed)
			(pads allowed)
			(copperpour not_allowed)
			(footprints allowed)
		)
		(placement
			(enabled no)
			(sheetname "")
		)
		(fill
			(thermal_gap 0.5)
			(thermal_bridge_width 0.5)
			(island_removal_mode 0)
		)
		(polygon
			(pts
				(arc
					(start 369.614704 -172.971968)
					(mid 369.763494 -173.331178)
					(end 370.122704 -173.479968)
				)
				(arc
					(start 370.123212 -173.479968)
					(mid 370.254421 -173.462731)
					(end 370.376704 -173.41215)
				)
				(arc
					(start 371.300756 -172.878496)
					(mid 371.486689 -172.69256)
					(end 371.554756 -172.438568)
				)
				(arc
					(start 371.554756 -172.438568)
					(mid 371.405966 -172.079358)
					(end 371.046756 -171.930568)
				)
				(arc
					(start 371.046248 -171.930568)
					(mid 370.915039 -171.947805)
					(end 370.792756 -171.998386)
				)
				(arc
					(start 369.868704 -172.53204)
					(mid 369.682771 -172.717976)
					(end 369.614704 -172.971968)
				)
			)
		)
	)
	(zone
		(layers "F.Cu" "B.Cu" "In1.Cu" "In2.Cu" "In3.Cu" "In4.Cu" "In5.Cu" "In6.Cu"
			"In7.Cu" "In8.Cu" "In9.Cu" "In10.Cu" "In11.Cu" "In12.Cu" "In13.Cu" "In14.Cu"
			"In15.Cu" "In16.Cu"
		)
		(hatch none 0.5)
		(connect_pads
			(clearance 0)
		)
		(min_thickness 0.25)
		(keepout
			(tracks not_allowed)
			(vias allowed)
			(pads allowed)
			(copperpour not_allowed)
			(footprints allowed)
		)
		(placement
			(enabled no)
			(sheetname "")
		)
		(fill
			(thermal_gap 0.5)
			(thermal_bridge_width 0.5)
			(island_removal_mode 0)
		)
		(polygon
			(pts
				(arc
					(start 365.07801 -223.575626)
					(mid 364.42015 -223.575626)
					(end 365.07801 -223.575626)
				)
			)
		)
	)
	(zone
		(layers "F.Cu" "B.Cu" "In1.Cu" "In2.Cu" "In3.Cu" "In4.Cu" "In5.Cu" "In6.Cu"
			"In7.Cu" "In8.Cu" "In9.Cu" "In10.Cu" "In11.Cu" "In12.Cu" "In13.Cu" "In14.Cu"
			"In15.Cu" "In16.Cu"
		)
		(hatch none 0.5)
		(connect_pads
			(clearance 0)
		)
		(min_thickness 0.25)
		(keepout
			(tracks not_allowed)
			(vias allowed)
			(pads allowed)
			(copperpour not_allowed)
			(footprints allowed)
		)
		(placement
			(enabled no)
			(sheetname "")
		)
		(fill
			(thermal_gap 0.5)
			(thermal_bridge_width 0.5)
			(island_removal_mode 0)
		)
		(polygon
			(pts
				(arc
					(start 102.992682 -285.563056)
					(mid 102.920693 -285.490897)
					(end 102.822248 -285.464504)
				)
				(arc
					(start 102.822248 -285.464504)
					(mid 102.683054 -285.52216)
					(end 102.625398 -285.661354)
				)
				(arc
					(start 102.625398 -285.661354)
					(mid 102.632155 -285.712235)
					(end 102.651814 -285.759652)
				)
				(arc
					(start 103.121714 -286.573722)
					(mid 103.193703 -286.645881)
					(end 103.292148 -286.672274)
				)
				(arc
					(start 103.292148 -286.672274)
					(mid 103.431342 -286.614618)
					(end 103.488998 -286.475424)
				)
				(arc
					(start 103.488998 -286.475424)
					(mid 103.482241 -286.424543)
					(end 103.462582 -286.377126)
				)
			)
		)
	)
	(zone
		(layers "F.Cu" "B.Cu" "In1.Cu" "In2.Cu" "In3.Cu" "In4.Cu" "In5.Cu" "In6.Cu"
			"In7.Cu" "In8.Cu" "In9.Cu" "In10.Cu" "In11.Cu" "In12.Cu" "In13.Cu" "In14.Cu"
			"In15.Cu" "In16.Cu"
		)
		(hatch none 0.5)
		(connect_pads
			(clearance 0)
		)
		(min_thickness 0.25)
		(keepout
			(tracks not_allowed)
			(vias allowed)
			(pads allowed)
			(copperpour not_allowed)
			(footprints allowed)
		)
		(placement
			(enabled no)
			(sheetname "")
		)
		(fill
			(thermal_gap 0.5)
			(thermal_bridge_width 0.5)
			(island_removal_mode 0)
		)
		(polygon
			(pts
				(arc
					(start 99.233482 -285.563056)
					(mid 99.161493 -285.490897)
					(end 99.063048 -285.464504)
				)
				(arc
					(start 99.063048 -285.464504)
					(mid 98.923854 -285.52216)
					(end 98.866198 -285.661354)
				)
				(arc
					(start 98.866198 -285.661354)
					(mid 98.872955 -285.712235)
					(end 98.892614 -285.759652)
				)
				(arc
					(start 99.362514 -286.573722)
					(mid 99.434503 -286.645881)
					(end 99.532948 -286.672274)
				)
				(arc
					(start 99.532948 -286.672274)
					(mid 99.672142 -286.614618)
					(end 99.729798 -286.475424)
				)
				(arc
					(start 99.729798 -286.475424)
					(mid 99.723041 -286.424543)
					(end 99.703382 -286.377126)
				)
			)
		)
	)
	(zone
		(layers "F.Cu" "B.Cu" "In1.Cu" "In2.Cu" "In3.Cu" "In4.Cu" "In5.Cu" "In6.Cu"
			"In7.Cu" "In8.Cu" "In9.Cu" "In10.Cu" "In11.Cu" "In12.Cu" "In13.Cu" "In14.Cu"
			"In15.Cu" "In16.Cu"
		)
		(hatch none 0.5)
		(connect_pads
			(clearance 0)
		)
		(min_thickness 0.25)
		(keepout
			(tracks not_allowed)
			(vias allowed)
			(pads allowed)
			(copperpour not_allowed)
			(footprints allowed)
		)
		(placement
			(enabled no)
			(sheetname "")
		)
		(fill
			(thermal_gap 0.5)
			(thermal_bridge_width 0.5)
			(island_removal_mode 0)
		)
		(polygon
			(pts
				(arc
					(start 355.68001 -220.319854)
					(mid 355.02215 -220.319854)
					(end 355.68001 -220.319854)
				)
			)
		)
	)
	(zone
		(layers "F.Cu" "B.Cu" "In1.Cu" "In2.Cu" "In3.Cu" "In4.Cu" "In5.Cu" "In6.Cu"
			"In7.Cu" "In8.Cu" "In9.Cu" "In10.Cu" "In11.Cu" "In12.Cu" "In13.Cu" "In14.Cu"
			"In15.Cu" "In16.Cu"
		)
		(hatch none 0.5)
		(connect_pads
			(clearance 0)
		)
		(min_thickness 0.25)
		(keepout
			(tracks not_allowed)
			(vias allowed)
			(pads allowed)
			(copperpour not_allowed)
			(footprints allowed)
		)
		(placement
			(enabled no)
			(sheetname "")
		)
		(fill
			(thermal_gap 0.5)
			(thermal_bridge_width 0.5)
			(island_removal_mode 0)
		)
		(polygon
			(pts
				(arc
					(start 357.48468 -55.503572)
					(mid 357.10368 -55.884572)
					(end 357.48468 -56.265572)
				)
				(arc
					(start 358.34828 -56.265572)
					(mid 358.72928 -55.884572)
					(end 358.34828 -55.503572)
				)
			)
		)
	)
	(zone
		(layers "F.Cu" "B.Cu" "In1.Cu" "In2.Cu" "In3.Cu" "In4.Cu" "In5.Cu" "In6.Cu"
			"In7.Cu" "In8.Cu" "In9.Cu" "In10.Cu" "In11.Cu" "In12.Cu" "In13.Cu" "In14.Cu"
			"In15.Cu" "In16.Cu"
		)
		(hatch none 0.5)
		(connect_pads
			(clearance 0)
		)
		(min_thickness 0.25)
		(keepout
			(tracks not_allowed)
			(vias allowed)
			(pads allowed)
			(copperpour not_allowed)
			(footprints allowed)
		)
		(placement
			(enabled no)
			(sheetname "")
		)
		(fill
			(thermal_gap 0.5)
			(thermal_bridge_width 0.5)
			(island_removal_mode 0)
		)
		(polygon
			(pts
				(arc
					(start 130.687064 -285.661354)
					(mid 131.344924 -285.661354)
					(end 130.687064 -285.661354)
				)
			)
		)
	)
	(zone
		(layers "F.Cu" "B.Cu" "In1.Cu" "In2.Cu" "In3.Cu" "In4.Cu" "In5.Cu" "In6.Cu"
			"In7.Cu" "In8.Cu" "In9.Cu" "In10.Cu" "In11.Cu" "In12.Cu" "In13.Cu" "In14.Cu"
			"In15.Cu" "In16.Cu"
		)
		(hatch none 0.5)
		(connect_pads
			(clearance 0)
		)
		(min_thickness 0.25)
		(keepout
			(tracks not_allowed)
			(vias allowed)
			(pads allowed)
			(copperpour not_allowed)
			(footprints allowed)
		)
		(placement
			(enabled no)
			(sheetname "")
		)
		(fill
			(thermal_gap 0.5)
			(thermal_bridge_width 0.5)
			(island_removal_mode 0)
		)
		(polygon
			(pts
				(arc
					(start 356.730046 -275.8948)
					(mid 356.072186 -275.8948)
					(end 356.730046 -275.8948)
				)
			)
		)
	)
	(zone
		(layers "F.Cu" "B.Cu" "In1.Cu" "In2.Cu" "In3.Cu" "In4.Cu" "In5.Cu" "In6.Cu"
			"In7.Cu" "In8.Cu" "In9.Cu" "In10.Cu" "In11.Cu" "In12.Cu" "In13.Cu" "In14.Cu"
			"In15.Cu" "In16.Cu"
		)
		(hatch none 0.5)
		(connect_pads
			(clearance 0)
		)
		(min_thickness 0.25)
		(keepout
			(tracks not_allowed)
			(vias allowed)
			(pads allowed)
			(copperpour not_allowed)
			(footprints allowed)
		)
		(placement
			(enabled no)
			(sheetname "")
		)
		(fill
			(thermal_gap 0.5)
			(thermal_bridge_width 0.5)
			(island_removal_mode 0)
		)
		(polygon
			(pts
				(arc
					(start 380.536704 -288.005012)
					(mid 380.464715 -287.932853)
					(end 380.36627 -287.90646)
				)
				(arc
					(start 380.36627 -287.90646)
					(mid 380.227076 -287.964116)
					(end 380.16942 -288.10331)
				)
				(arc
					(start 380.16942 -288.10331)
					(mid 380.176177 -288.154191)
					(end 380.195836 -288.201608)
				)
				(arc
					(start 380.665482 -289.015424)
					(mid 380.737471 -289.087583)
					(end 380.835916 -289.113976)
				)
				(arc
					(start 380.835916 -289.113976)
					(mid 380.97511 -289.05632)
					(end 381.032766 -288.917126)
				)
				(arc
					(start 381.032766 -288.917126)
					(mid 381.026009 -288.866245)
					(end 381.00635 -288.818828)
				)
			)
		)
	)
	(zone
		(layers "F.Cu" "B.Cu" "In1.Cu" "In2.Cu" "In3.Cu" "In4.Cu" "In5.Cu" "In6.Cu"
			"In7.Cu" "In8.Cu" "In9.Cu" "In10.Cu" "In11.Cu" "In12.Cu" "In13.Cu" "In14.Cu"
			"In15.Cu" "In16.Cu"
		)
		(hatch none 0.5)
		(connect_pads
			(clearance 0)
		)
		(min_thickness 0.25)
		(keepout
			(tracks not_allowed)
			(vias allowed)
			(pads allowed)
			(copperpour not_allowed)
			(footprints allowed)
		)
		(placement
			(enabled no)
			(sheetname "")
		)
		(fill
			(thermal_gap 0.5)
			(thermal_bridge_width 0.5)
			(island_removal_mode 0)
		)
		(polygon
			(pts
				(arc
					(start 342.053164 -221.133924)
					(mid 341.395304 -221.133924)
					(end 342.053164 -221.133924)
				)
			)
		)
	)
	(zone
		(layers "F.Cu" "B.Cu" "In1.Cu" "In2.Cu" "In3.Cu" "In4.Cu" "In5.Cu" "In6.Cu"
			"In7.Cu" "In8.Cu" "In9.Cu" "In10.Cu" "In11.Cu" "In12.Cu" "In13.Cu" "In14.Cu"
			"In15.Cu" "In16.Cu"
		)
		(hatch none 0.5)
		(connect_pads
			(clearance 0)
		)
		(min_thickness 0.25)
		(keepout
			(tracks not_allowed)
			(vias allowed)
			(pads allowed)
			(copperpour not_allowed)
			(footprints allowed)
		)
		(placement
			(enabled no)
			(sheetname "")
		)
		(fill
			(thermal_gap 0.5)
			(thermal_bridge_width 0.5)
			(island_removal_mode 0)
		)
		(polygon
			(pts
				(arc
					(start 428.244254 -6.332474)
					(mid 427.863254 -6.713474)
					(end 428.244254 -7.094474)
				)
				(arc
					(start 429.107854 -7.094474)
					(mid 429.488854 -6.713474)
					(end 429.107854 -6.332474)
				)
			)
		)
	)
	(zone
		(layers "F.Cu" "B.Cu" "In1.Cu" "In2.Cu" "In3.Cu" "In4.Cu" "In5.Cu" "In6.Cu"
			"In7.Cu" "In8.Cu" "In9.Cu" "In10.Cu" "In11.Cu" "In12.Cu" "In13.Cu" "In14.Cu"
			"In15.Cu" "In16.Cu"
		)
		(hatch none 0.5)
		(connect_pads
			(clearance 0)
		)
		(min_thickness 0.25)
		(keepout
			(tracks not_allowed)
			(vias allowed)
			(pads allowed)
			(copperpour not_allowed)
			(footprints allowed)
		)
		(placement
			(enabled no)
			(sheetname "")
		)
		(fill
			(thermal_gap 0.5)
			(thermal_bridge_width 0.5)
			(island_removal_mode 0)
		)
		(polygon
			(pts
				(arc
					(start 371.96776 -217.97645)
					(mid 371.987444 -217.92904)
					(end 371.994176 -217.878152)
				)
				(arc
					(start 371.994176 -217.878152)
					(mid 371.93652 -217.738958)
					(end 371.797326 -217.681302)
				)
				(arc
					(start 371.797326 -217.681302)
					(mid 371.698895 -217.707718)
					(end 371.626892 -217.779854)
				)
				(arc
					(start 371.157246 -218.593924)
					(mid 371.137562 -218.641334)
					(end 371.13083 -218.692222)
				)
				(arc
					(start 371.13083 -218.692222)
					(mid 371.188486 -218.831416)
					(end 371.32768 -218.889072)
				)
				(arc
					(start 371.32768 -218.889072)
					(mid 371.426111 -218.862656)
					(end 371.498114 -218.79052)
				)
			)
		)
	)
	(zone
		(layers "F.Cu" "B.Cu" "In1.Cu" "In2.Cu" "In3.Cu" "In4.Cu" "In5.Cu" "In6.Cu"
			"In7.Cu" "In8.Cu" "In9.Cu" "In10.Cu" "In11.Cu" "In12.Cu" "In13.Cu" "In14.Cu"
			"In15.Cu" "In16.Cu"
		)
		(hatch none 0.5)
		(connect_pads
			(clearance 0)
		)
		(min_thickness 0.25)
		(keepout
			(tracks not_allowed)
			(vias allowed)
			(pads allowed)
			(copperpour not_allowed)
			(footprints allowed)
		)
		(placement
			(enabled no)
			(sheetname "")
		)
		(fill
			(thermal_gap 0.5)
			(thermal_bridge_width 0.5)
			(island_removal_mode 0)
		)
		(polygon
			(pts
				(arc
					(start 131.516882 -220.319854)
					(mid 132.174742 -220.319854)
					(end 131.516882 -220.319854)
				)
			)
		)
	)
	(zone
		(layers "F.Cu" "B.Cu" "In1.Cu" "In2.Cu" "In3.Cu" "In4.Cu" "In5.Cu" "In6.Cu"
			"In7.Cu" "In8.Cu" "In9.Cu" "In10.Cu" "In11.Cu" "In12.Cu" "In13.Cu" "In14.Cu"
			"In15.Cu" "In16.Cu"
		)
		(hatch none 0.5)
		(connect_pads
			(clearance 0)
		)
		(min_thickness 0.25)
		(keepout
			(tracks not_allowed)
			(vias allowed)
			(pads allowed)
			(copperpour not_allowed)
			(footprints allowed)
		)
		(placement
			(enabled no)
			(sheetname "")
		)
		(fill
			(thermal_gap 0.5)
			(thermal_bridge_width 0.5)
			(island_removal_mode 0)
		)
		(polygon
			(pts
				(arc
					(start 91.403424 -288.103056)
					(mid 90.745564 -288.103056)
					(end 91.403424 -288.103056)
				)
			)
		)
	)
	(zone
		(layers "F.Cu" "B.Cu" "In1.Cu" "In2.Cu" "In3.Cu" "In4.Cu" "In5.Cu" "In6.Cu"
			"In7.Cu" "In8.Cu" "In9.Cu" "In10.Cu" "In11.Cu" "In12.Cu" "In13.Cu" "In14.Cu"
			"In15.Cu" "In16.Cu"
		)
		(hatch none 0.5)
		(connect_pads
			(clearance 0)
		)
		(min_thickness 0.25)
		(keepout
			(tracks not_allowed)
			(vias allowed)
			(pads allowed)
			(copperpour not_allowed)
			(footprints allowed)
		)
		(placement
			(enabled no)
			(sheetname "")
		)
		(fill
			(thermal_gap 0.5)
			(thermal_bridge_width 0.5)
			(island_removal_mode 0)
		)
		(polygon
			(pts
				(arc
					(start 127.006096 -221.133924)
					(mid 126.348236 -221.133924)
					(end 127.006096 -221.133924)
				)
			)
		)
	)
	(zone
		(layers "F.Cu" "B.Cu" "In1.Cu" "In2.Cu" "In3.Cu" "In4.Cu" "In5.Cu" "In6.Cu"
			"In7.Cu" "In8.Cu" "In9.Cu" "In10.Cu" "In11.Cu" "In12.Cu" "In13.Cu" "In14.Cu"
			"In15.Cu" "In16.Cu"
		)
		(hatch none 0.5)
		(connect_pads
			(clearance 0)
		)
		(min_thickness 0.25)
		(keepout
			(tracks not_allowed)
			(vias allowed)
			(pads allowed)
			(copperpour not_allowed)
			(footprints allowed)
		)
		(placement
			(enabled no)
			(sheetname "")
		)
		(fill
			(thermal_gap 0.5)
			(thermal_bridge_width 0.5)
			(island_removal_mode 0)
		)
		(polygon
			(pts
				(arc
					(start 311.452768 -406.62352)
					(mid 311.071768 -407.00452)
					(end 311.452768 -407.38552)
				)
				(arc
					(start 312.316368 -407.38552)
					(mid 312.697368 -407.00452)
					(end 312.316368 -406.62352)
				)
			)
		)
	)
	(zone
		(layers "F.Cu" "B.Cu" "In1.Cu" "In2.Cu" "In3.Cu" "In4.Cu" "In5.Cu" "In6.Cu"
			"In7.Cu" "In8.Cu" "In9.Cu" "In10.Cu" "In11.Cu" "In12.Cu" "In13.Cu" "In14.Cu"
			"In15.Cu" "In16.Cu"
		)
		(hatch none 0.5)
		(connect_pads
			(clearance 0)
		)
		(min_thickness 0.25)
		(keepout
			(tracks not_allowed)
			(vias allowed)
			(pads allowed)
			(copperpour not_allowed)
			(footprints allowed)
		)
		(placement
			(enabled no)
			(sheetname "")
		)
		(fill
			(thermal_gap 0.5)
			(thermal_bridge_width 0.5)
			(island_removal_mode 0)
		)
		(polygon
			(pts
				(arc
					(start 375.885964 -224.389442)
					(mid 375.228104 -224.389442)
					(end 375.885964 -224.389442)
				)
			)
		)
	)
	(zone
		(layers "F.Cu" "B.Cu" "In1.Cu" "In2.Cu" "In3.Cu" "In4.Cu" "In5.Cu" "In6.Cu"
			"In7.Cu" "In8.Cu" "In9.Cu" "In10.Cu" "In11.Cu" "In12.Cu" "In13.Cu" "In14.Cu"
			"In15.Cu" "In16.Cu"
		)
		(hatch none 0.5)
		(connect_pads
			(clearance 0)
		)
		(min_thickness 0.25)
		(keepout
			(tracks not_allowed)
			(vias allowed)
			(pads allowed)
			(copperpour not_allowed)
			(footprints allowed)
		)
		(placement
			(enabled no)
			(sheetname "")
		)
		(fill
			(thermal_gap 0.5)
			(thermal_bridge_width 0.5)
			(island_removal_mode 0)
		)
		(polygon
			(pts
				(arc
					(start 381.95885 -409.649168)
					(mid 381.57785 -410.030168)
					(end 381.95885 -410.411168)
				)
				(arc
					(start 382.82245 -410.411168)
					(mid 383.20345 -410.030168)
					(end 382.82245 -409.649168)
				)
			)
		)
	)
	(zone
		(layers "F.Cu" "B.Cu" "In1.Cu" "In2.Cu" "In3.Cu" "In4.Cu" "In5.Cu" "In6.Cu"
			"In7.Cu" "In8.Cu" "In9.Cu" "In10.Cu" "In11.Cu" "In12.Cu" "In13.Cu" "In14.Cu"
			"In15.Cu" "In16.Cu"
		)
		(hatch none 0.5)
		(connect_pads
			(clearance 0)
		)
		(min_thickness 0.25)
		(keepout
			(tracks not_allowed)
			(vias allowed)
			(pads allowed)
			(copperpour not_allowed)
			(footprints allowed)
		)
		(placement
			(enabled no)
			(sheetname "")
		)
		(fill
			(thermal_gap 0.5)
			(thermal_bridge_width 0.5)
			(island_removal_mode 0)
		)
		(polygon
			(pts
				(arc
					(start 421.0812 -18.744438)
					(mid 420.7002 -19.125438)
					(end 421.0812 -19.506438)
				)
				(arc
					(start 421.9448 -19.506438)
					(mid 422.3258 -19.125438)
					(end 421.9448 -18.744438)
				)
			)
		)
	)
	(zone
		(layers "F.Cu" "B.Cu" "In1.Cu" "In2.Cu" "In3.Cu" "In4.Cu" "In5.Cu" "In6.Cu"
			"In7.Cu" "In8.Cu" "In9.Cu" "In10.Cu" "In11.Cu" "In12.Cu" "In13.Cu" "In14.Cu"
			"In15.Cu" "In16.Cu"
		)
		(hatch none 0.5)
		(connect_pads
			(clearance 0)
		)
		(min_thickness 0.25)
		(keepout
			(tracks not_allowed)
			(vias allowed)
			(pads allowed)
			(copperpour not_allowed)
			(footprints allowed)
		)
		(placement
			(enabled no)
			(sheetname "")
		)
		(fill
			(thermal_gap 0.5)
			(thermal_bridge_width 0.5)
			(island_removal_mode 0)
		)
		(polygon
			(pts
				(arc
					(start 111.029496 -224.389442)
					(mid 110.371636 -224.389442)
					(end 111.029496 -224.389442)
				)
			)
		)
	)
	(zone
		(layers "F.Cu" "B.Cu" "In1.Cu" "In2.Cu" "In3.Cu" "In4.Cu" "In5.Cu" "In6.Cu"
			"In7.Cu" "In8.Cu" "In9.Cu" "In10.Cu" "In11.Cu" "In12.Cu" "In13.Cu" "In14.Cu"
			"In15.Cu" "In16.Cu"
		)
		(hatch none 0.5)
		(connect_pads
			(clearance 0)
		)
		(min_thickness 0.25)
		(keepout
			(tracks not_allowed)
			(vias allowed)
			(pads allowed)
			(copperpour not_allowed)
			(footprints allowed)
		)
		(placement
			(enabled no)
			(sheetname "")
		)
		(fill
			(thermal_gap 0.5)
			(thermal_bridge_width 0.5)
			(island_removal_mode 0)
		)
		(polygon
			(pts
				(arc
					(start 351.451164 -221.133924)
					(mid 350.793304 -221.133924)
					(end 351.451164 -221.133924)
				)
			)
		)
	)
	(zone
		(layers "F.Cu" "B.Cu" "In1.Cu" "In2.Cu" "In3.Cu" "In4.Cu" "In5.Cu" "In6.Cu"
			"In7.Cu" "In8.Cu" "In9.Cu" "In10.Cu" "In11.Cu" "In12.Cu" "In13.Cu" "In14.Cu"
			"In15.Cu" "In16.Cu"
		)
		(hatch none 0.5)
		(connect_pads
			(clearance 0)
		)
		(min_thickness 0.25)
		(keepout
			(tracks not_allowed)
			(vias allowed)
			(pads allowed)
			(copperpour not_allowed)
			(footprints allowed)
		)
		(placement
			(enabled no)
			(sheetname "")
		)
		(fill
			(thermal_gap 0.5)
			(thermal_bridge_width 0.5)
			(island_removal_mode 0)
		)
		(polygon
			(pts
				(arc
					(start 100.613464 -285.661354)
					(mid 101.271324 -285.661354)
					(end 100.613464 -285.661354)
				)
			)
		)
	)
	(zone
		(layers "F.Cu" "B.Cu" "In1.Cu" "In2.Cu" "In3.Cu" "In4.Cu" "In5.Cu" "In6.Cu"
			"In7.Cu" "In8.Cu" "In9.Cu" "In10.Cu" "In11.Cu" "In12.Cu" "In13.Cu" "In14.Cu"
			"In15.Cu" "In16.Cu"
		)
		(hatch none 0.5)
		(connect_pads
			(clearance 0)
		)
		(min_thickness 0.25)
		(keepout
			(tracks not_allowed)
			(vias allowed)
			(pads allowed)
			(copperpour not_allowed)
			(footprints allowed)
		)
		(placement
			(enabled no)
			(sheetname "")
		)
		(fill
			(thermal_gap 0.5)
			(thermal_bridge_width 0.5)
			(island_removal_mode 0)
		)
		(polygon
			(pts
				(arc
					(start 370.247164 -224.389442)
					(mid 369.589304 -224.389442)
					(end 370.247164 -224.389442)
				)
			)
		)
	)
	(zone
		(layers "F.Cu" "B.Cu" "In1.Cu" "In2.Cu" "In3.Cu" "In4.Cu" "In5.Cu" "In6.Cu"
			"In7.Cu" "In8.Cu" "In9.Cu" "In10.Cu" "In11.Cu" "In12.Cu" "In13.Cu" "In14.Cu"
			"In15.Cu" "In16.Cu"
		)
		(hatch none 0.5)
		(connect_pads
			(clearance 0)
		)
		(min_thickness 0.25)
		(keepout
			(tracks not_allowed)
			(vias allowed)
			(pads allowed)
			(copperpour not_allowed)
			(footprints allowed)
		)
		(placement
			(enabled no)
			(sheetname "")
		)
		(fill
			(thermal_gap 0.5)
			(thermal_bridge_width 0.5)
			(island_removal_mode 0)
		)
		(polygon
			(pts
				(arc
					(start 116.668296 -221.133924)
					(mid 116.010436 -221.133924)
					(end 116.668296 -221.133924)
				)
			)
		)
	)
	(zone
		(layers "F.Cu" "B.Cu" "In1.Cu" "In2.Cu" "In3.Cu" "In4.Cu" "In5.Cu" "In6.Cu"
			"In7.Cu" "In8.Cu" "In9.Cu" "In10.Cu" "In11.Cu" "In12.Cu" "In13.Cu" "In14.Cu"
			"In15.Cu" "In16.Cu"
		)
		(hatch none 0.5)
		(connect_pads
			(clearance 0)
		)
		(min_thickness 0.25)
		(keepout
			(tracks not_allowed)
			(vias allowed)
			(pads allowed)
			(copperpour not_allowed)
			(footprints allowed)
		)
		(placement
			(enabled no)
			(sheetname "")
		)
		(fill
			(thermal_gap 0.5)
			(thermal_bridge_width 0.5)
			(island_removal_mode 0)
		)
		(polygon
			(pts
				(arc
					(start 371.296946 -288.103056)
					(mid 370.639086 -288.103056)
					(end 371.296946 -288.103056)
				)
			)
		)
	)
	(zone
		(layers "F.Cu" "B.Cu" "In1.Cu" "In2.Cu" "In3.Cu" "In4.Cu" "In5.Cu" "In6.Cu"
			"In7.Cu" "In8.Cu" "In9.Cu" "In10.Cu" "In11.Cu" "In12.Cu" "In13.Cu" "In14.Cu"
			"In15.Cu" "In16.Cu"
		)
		(hatch none 0.5)
		(connect_pads
			(clearance 0)
		)
		(min_thickness 0.25)
		(keepout
			(tracks not_allowed)
			(vias allowed)
			(pads allowed)
			(copperpour not_allowed)
			(footprints allowed)
		)
		(placement
			(enabled no)
			(sheetname "")
		)
		(fill
			(thermal_gap 0.5)
			(thermal_bridge_width 0.5)
			(island_removal_mode 0)
		)
		(polygon
			(pts
				(arc
					(start 350.301052 -63.269876)
					(mid 350.682052 -63.650876)
					(end 351.063052 -63.269876)
				)
				(arc
					(start 351.063052 -62.406276)
					(mid 350.682052 -62.025276)
					(end 350.301052 -62.406276)
				)
			)
		)
	)
	(zone
		(layers "F.Cu" "B.Cu" "In1.Cu" "In2.Cu" "In3.Cu" "In4.Cu" "In5.Cu" "In6.Cu"
			"In7.Cu" "In8.Cu" "In9.Cu" "In10.Cu" "In11.Cu" "In12.Cu" "In13.Cu" "In14.Cu"
			"In15.Cu" "In16.Cu"
		)
		(hatch none 0.5)
		(connect_pads
			(clearance 0)
		)
		(min_thickness 0.25)
		(keepout
			(tracks not_allowed)
			(vias allowed)
			(pads allowed)
			(copperpour not_allowed)
			(footprints allowed)
		)
		(placement
			(enabled no)
			(sheetname "")
		)
		(fill
			(thermal_gap 0.5)
			(thermal_bridge_width 0.5)
			(island_removal_mode 0)
		)
		(polygon
			(pts
				(arc
					(start 354.74021 -221.94774)
					(mid 354.08235 -221.94774)
					(end 354.74021 -221.94774)
				)
			)
		)
	)
	(zone
		(layers "F.Cu" "B.Cu" "In1.Cu" "In2.Cu" "In3.Cu" "In4.Cu" "In5.Cu" "In6.Cu"
			"In7.Cu" "In8.Cu" "In9.Cu" "In10.Cu" "In11.Cu" "In12.Cu" "In13.Cu" "In14.Cu"
			"In15.Cu" "In16.Cu"
		)
		(hatch none 0.5)
		(connect_pads
			(clearance 0)
		)
		(min_thickness 0.25)
		(keepout
			(tracks not_allowed)
			(vias allowed)
			(pads allowed)
			(copperpour not_allowed)
			(footprints allowed)
		)
		(placement
			(enabled no)
			(sheetname "")
		)
		(fill
			(thermal_gap 0.5)
			(thermal_bridge_width 0.5)
			(island_removal_mode 0)
		)
		(polygon
			(pts
				(arc
					(start 336.118962 -76.371704)
					(mid 336.499962 -75.990704)
					(end 336.118962 -75.609704)
				)
				(arc
					(start 335.255362 -75.609704)
					(mid 334.874362 -75.990704)
					(end 335.255362 -76.371704)
				)
			)
		)
	)
	(zone
		(layers "F.Cu" "B.Cu" "In1.Cu" "In2.Cu" "In3.Cu" "In4.Cu" "In5.Cu" "In6.Cu"
			"In7.Cu" "In8.Cu" "In9.Cu" "In10.Cu" "In11.Cu" "In12.Cu" "In13.Cu" "In14.Cu"
			"In15.Cu" "In16.Cu"
		)
		(hatch none 0.5)
		(connect_pads
			(clearance 0)
		)
		(min_thickness 0.25)
		(keepout
			(tracks not_allowed)
			(vias allowed)
			(pads allowed)
			(copperpour not_allowed)
			(footprints allowed)
		)
		(placement
			(enabled no)
			(sheetname "")
		)
		(fill
			(thermal_gap 0.5)
			(thermal_bridge_width 0.5)
			(island_removal_mode 0)
		)
		(polygon
			(pts
				(arc
					(start 337.463892 -279.964134)
					(mid 336.806032 -279.964134)
					(end 337.463892 -279.964134)
				)
			)
		)
	)
	(zone
		(layers "F.Cu" "B.Cu" "In1.Cu" "In2.Cu" "In3.Cu" "In4.Cu" "In5.Cu" "In6.Cu"
			"In7.Cu" "In8.Cu" "In9.Cu" "In10.Cu" "In11.Cu" "In12.Cu" "In13.Cu" "In14.Cu"
			"In15.Cu" "In16.Cu"
		)
		(hatch none 0.5)
		(connect_pads
			(clearance 0)
		)
		(min_thickness 0.25)
		(keepout
			(tracks not_allowed)
			(vias allowed)
			(pads allowed)
			(copperpour not_allowed)
			(footprints allowed)
		)
		(placement
			(enabled no)
			(sheetname "")
		)
		(fill
			(thermal_gap 0.5)
			(thermal_bridge_width 0.5)
			(island_removal_mode 0)
		)
		(polygon
			(pts
				(arc
					(start 365.07801 -217.064336)
					(mid 364.42015 -217.064336)
					(end 365.07801 -217.064336)
				)
			)
		)
	)
	(zone
		(layers "F.Cu" "B.Cu" "In1.Cu" "In2.Cu" "In3.Cu" "In4.Cu" "In5.Cu" "In6.Cu"
			"In7.Cu" "In8.Cu" "In9.Cu" "In10.Cu" "In11.Cu" "In12.Cu" "In13.Cu" "In14.Cu"
			"In15.Cu" "In16.Cu"
		)
		(hatch none 0.5)
		(connect_pads
			(clearance 0)
		)
		(min_thickness 0.25)
		(keepout
			(tracks not_allowed)
			(vias allowed)
			(pads allowed)
			(copperpour not_allowed)
			(footprints allowed)
		)
		(placement
			(enabled no)
			(sheetname "")
		)
		(fill
			(thermal_gap 0.5)
			(thermal_bridge_width 0.5)
			(island_removal_mode 0)
		)
		(polygon
			(pts
				(arc
					(start 73.831958 -406.62352)
					(mid 73.450958 -407.00452)
					(end 73.831958 -407.38552)
				)
				(arc
					(start 74.695558 -407.38552)
					(mid 75.076558 -407.00452)
					(end 74.695558 -406.62352)
				)
			)
		)
	)
	(zone
		(layers "F.Cu" "B.Cu" "In1.Cu" "In2.Cu" "In3.Cu" "In4.Cu" "In5.Cu" "In6.Cu"
			"In7.Cu" "In8.Cu" "In9.Cu" "In10.Cu" "In11.Cu" "In12.Cu" "In13.Cu" "In14.Cu"
			"In15.Cu" "In16.Cu"
		)
		(hatch none 0.5)
		(connect_pads
			(clearance 0)
		)
		(min_thickness 0.25)
		(keepout
			(tracks not_allowed)
			(vias allowed)
			(pads allowed)
			(copperpour not_allowed)
			(footprints allowed)
		)
		(placement
			(enabled no)
			(sheetname "")
		)
		(fill
			(thermal_gap 0.5)
			(thermal_bridge_width 0.5)
			(island_removal_mode 0)
		)
		(polygon
			(pts
				(arc
					(start 373.01805 -284.74924)
					(mid 372.946061 -284.677081)
					(end 372.847616 -284.650688)
				)
				(arc
					(start 372.847616 -284.650688)
					(mid 372.708422 -284.708344)
					(end 372.650766 -284.847538)
				)
				(arc
					(start 372.650766 -284.847538)
					(mid 372.657523 -284.898419)
					(end 372.677182 -284.945836)
				)
				(arc
					(start 373.146828 -285.759652)
					(mid 373.218817 -285.831811)
					(end 373.317262 -285.858204)
				)
				(arc
					(start 373.317262 -285.858204)
					(mid 373.456456 -285.800548)
					(end 373.514112 -285.661354)
				)
				(arc
					(start 373.514112 -285.661354)
					(mid 373.507355 -285.610473)
					(end 373.487696 -285.563056)
				)
			)
		)
	)
	(zone
		(layers "F.Cu" "B.Cu" "In1.Cu" "In2.Cu" "In3.Cu" "In4.Cu" "In5.Cu" "In6.Cu"
			"In7.Cu" "In8.Cu" "In9.Cu" "In10.Cu" "In11.Cu" "In12.Cu" "In13.Cu" "In14.Cu"
			"In15.Cu" "In16.Cu"
		)
		(hatch none 0.5)
		(connect_pads
			(clearance 0)
		)
		(min_thickness 0.25)
		(keepout
			(tracks not_allowed)
			(vias allowed)
			(pads allowed)
			(copperpour not_allowed)
			(footprints allowed)
		)
		(placement
			(enabled no)
			(sheetname "")
		)
		(fill
			(thermal_gap 0.5)
			(thermal_bridge_width 0.5)
			(island_removal_mode 0)
		)
		(polygon
			(pts
				(arc
					(start 122.776742 -223.575626)
					(mid 122.118882 -223.575626)
					(end 122.776742 -223.575626)
				)
			)
		)
	)
	(zone
		(layers "F.Cu" "B.Cu" "In1.Cu" "In2.Cu" "In3.Cu" "In4.Cu" "In5.Cu" "In6.Cu"
			"In7.Cu" "In8.Cu" "In9.Cu" "In10.Cu" "In11.Cu" "In12.Cu" "In13.Cu" "In14.Cu"
			"In15.Cu" "In16.Cu"
		)
		(hatch none 0.5)
		(connect_pads
			(clearance 0)
		)
		(min_thickness 0.25)
		(keepout
			(tracks not_allowed)
			(vias allowed)
			(pads allowed)
			(copperpour not_allowed)
			(footprints allowed)
		)
		(placement
			(enabled no)
			(sheetname "")
		)
		(fill
			(thermal_gap 0.5)
			(thermal_bridge_width 0.5)
			(island_removal_mode 0)
		)
		(polygon
			(pts
				(arc
					(start 379.285246 -288.917126)
					(mid 378.627386 -288.917126)
					(end 379.285246 -288.917126)
				)
			)
		)
	)
	(zone
		(layers "F.Cu" "B.Cu" "In1.Cu" "In2.Cu" "In3.Cu" "In4.Cu" "In5.Cu" "In6.Cu"
			"In7.Cu" "In8.Cu" "In9.Cu" "In10.Cu" "In11.Cu" "In12.Cu" "In13.Cu" "In14.Cu"
			"In15.Cu" "In16.Cu"
		)
		(hatch none 0.5)
		(connect_pads
			(clearance 0)
		)
		(min_thickness 0.25)
		(keepout
			(tracks not_allowed)
			(vias allowed)
			(pads allowed)
			(copperpour not_allowed)
			(footprints allowed)
		)
		(placement
			(enabled no)
			(sheetname "")
		)
		(fill
			(thermal_gap 0.5)
			(thermal_bridge_width 0.5)
			(island_removal_mode 0)
		)
		(polygon
			(pts
				(arc
					(start 335.958688 -409.649168)
					(mid 335.577688 -410.030168)
					(end 335.958688 -410.411168)
				)
				(arc
					(start 336.822288 -410.411168)
					(mid 337.203288 -410.030168)
					(end 336.822288 -409.649168)
				)
			)
		)
	)
	(zone
		(layers "F.Cu" "B.Cu" "In1.Cu" "In2.Cu" "In3.Cu" "In4.Cu" "In5.Cu" "In6.Cu"
			"In7.Cu" "In8.Cu" "In9.Cu" "In10.Cu" "In11.Cu" "In12.Cu" "In13.Cu" "In14.Cu"
			"In15.Cu" "In16.Cu"
		)
		(hatch none 0.5)
		(connect_pads
			(clearance 0)
		)
		(min_thickness 0.25)
		(keepout
			(tracks not_allowed)
			(vias allowed)
			(pads allowed)
			(copperpour not_allowed)
			(footprints allowed)
		)
		(placement
			(enabled no)
			(sheetname "")
		)
		(fill
			(thermal_gap 0.5)
			(thermal_bridge_width 0.5)
			(island_removal_mode 0)
		)
		(polygon
			(pts
				(arc
					(start 124.186696 -224.389442)
					(mid 123.528836 -224.389442)
					(end 124.186696 -224.389442)
				)
			)
		)
	)
	(zone
		(layers "F.Cu" "B.Cu" "In1.Cu" "In2.Cu" "In3.Cu" "In4.Cu" "In5.Cu" "In6.Cu"
			"In7.Cu" "In8.Cu" "In9.Cu" "In10.Cu" "In11.Cu" "In12.Cu" "In13.Cu" "In14.Cu"
			"In15.Cu" "In16.Cu"
		)
		(hatch none 0.5)
		(connect_pads
			(clearance 0)
		)
		(min_thickness 0.25)
		(keepout
			(tracks not_allowed)
			(vias allowed)
			(pads allowed)
			(copperpour not_allowed)
			(footprints allowed)
		)
		(placement
			(enabled no)
			(sheetname "")
		)
		(fill
			(thermal_gap 0.5)
			(thermal_bridge_width 0.5)
			(island_removal_mode 0)
		)
		(polygon
			(pts
				(arc
					(start 101.553264 -279.150318)
					(mid 102.211124 -279.150318)
					(end 101.553264 -279.150318)
				)
			)
		)
	)
	(zone
		(layers "F.Cu" "B.Cu" "In1.Cu" "In2.Cu" "In3.Cu" "In4.Cu" "In5.Cu" "In6.Cu"
			"In7.Cu" "In8.Cu" "In9.Cu" "In10.Cu" "In11.Cu" "In12.Cu" "In13.Cu" "In14.Cu"
			"In15.Cu" "In16.Cu"
		)
		(hatch none 0.5)
		(connect_pads
			(clearance 0)
		)
		(min_thickness 0.25)
		(keepout
			(tracks not_allowed)
			(vias allowed)
			(pads allowed)
			(copperpour not_allowed)
			(footprints allowed)
		)
		(placement
			(enabled no)
			(sheetname "")
		)
		(fill
			(thermal_gap 0.5)
			(thermal_bridge_width 0.5)
			(island_removal_mode 0)
		)
		(polygon
			(pts
				(arc
					(start 342.133682 -288.818828)
					(mid 342.113998 -288.866238)
					(end 342.107266 -288.917126)
				)
				(arc
					(start 342.107266 -288.917126)
					(mid 342.164922 -289.05632)
					(end 342.304116 -289.113976)
				)
				(arc
					(start 342.304116 -289.113976)
					(mid 342.402547 -289.08756)
					(end 342.47455 -289.015424)
				)
				(arc
					(start 342.94445 -288.201354)
					(mid 342.964134 -288.153944)
					(end 342.970866 -288.103056)
				)
				(arc
					(start 342.970866 -288.103056)
					(mid 342.91321 -287.963862)
					(end 342.774016 -287.906206)
				)
				(arc
					(start 342.774016 -287.906206)
					(mid 342.675585 -287.932622)
					(end 342.603582 -288.004758)
				)
			)
		)
	)
	(zone
		(layers "F.Cu" "B.Cu" "In1.Cu" "In2.Cu" "In3.Cu" "In4.Cu" "In5.Cu" "In6.Cu"
			"In7.Cu" "In8.Cu" "In9.Cu" "In10.Cu" "In11.Cu" "In12.Cu" "In13.Cu" "In14.Cu"
			"In15.Cu" "In16.Cu"
		)
		(hatch none 0.5)
		(connect_pads
			(clearance 0)
		)
		(min_thickness 0.25)
		(keepout
			(tracks not_allowed)
			(vias allowed)
			(pads allowed)
			(copperpour not_allowed)
			(footprints allowed)
		)
		(placement
			(enabled no)
			(sheetname "")
		)
		(fill
			(thermal_gap 0.5)
			(thermal_bridge_width 0.5)
			(island_removal_mode 0)
		)
		(polygon
			(pts
				(arc
					(start 372.236492 -289.807142)
					(mid 371.578632 -289.807142)
					(end 372.236492 -289.807142)
				)
			)
		)
	)
	(zone
		(layers "F.Cu" "B.Cu" "In1.Cu" "In2.Cu" "In3.Cu" "In4.Cu" "In5.Cu" "In6.Cu"
			"In7.Cu" "In8.Cu" "In9.Cu" "In10.Cu" "In11.Cu" "In12.Cu" "In13.Cu" "In14.Cu"
			"In15.Cu" "In16.Cu"
		)
		(hatch none 0.5)
		(connect_pads
			(clearance 0)
		)
		(min_thickness 0.25)
		(keepout
			(tracks not_allowed)
			(vias allowed)
			(pads allowed)
			(copperpour not_allowed)
			(footprints allowed)
		)
		(placement
			(enabled no)
			(sheetname "")
		)
		(fill
			(thermal_gap 0.5)
			(thermal_bridge_width 0.5)
			(island_removal_mode 0)
		)
		(polygon
			(pts
				(arc
					(start 340.602824 -297.515026)
					(mid 336.156808 -297.515026)
					(end 340.602824 -297.515026)
				)
			)
		)
	)
	(zone
		(layers "F.Cu" "B.Cu" "In1.Cu" "In2.Cu" "In3.Cu" "In4.Cu" "In5.Cu" "In6.Cu"
			"In7.Cu" "In8.Cu" "In9.Cu" "In10.Cu" "In11.Cu" "In12.Cu" "In13.Cu" "In14.Cu"
			"In15.Cu" "In16.Cu"
		)
		(hatch none 0.5)
		(connect_pads
			(clearance 0)
		)
		(min_thickness 0.25)
		(keepout
			(tracks not_allowed)
			(vias allowed)
			(pads allowed)
			(copperpour not_allowed)
			(footprints allowed)
		)
		(placement
			(enabled no)
			(sheetname "")
		)
		(fill
			(thermal_gap 0.5)
			(thermal_bridge_width 0.5)
			(island_removal_mode 0)
		)
		(polygon
			(pts
				(arc
					(start 97.872296 -221.133924)
					(mid 97.214436 -221.133924)
					(end 97.872296 -221.133924)
				)
			)
		)
	)
	(zone
		(layers "F.Cu" "B.Cu" "In1.Cu" "In2.Cu" "In3.Cu" "In4.Cu" "In5.Cu" "In6.Cu"
			"In7.Cu" "In8.Cu" "In9.Cu" "In10.Cu" "In11.Cu" "In12.Cu" "In13.Cu" "In14.Cu"
			"In15.Cu" "In16.Cu"
		)
		(hatch none 0.5)
		(connect_pads
			(clearance 0)
		)
		(min_thickness 0.25)
		(keepout
			(tracks not_allowed)
			(vias allowed)
			(pads allowed)
			(copperpour not_allowed)
			(footprints allowed)
		)
		(placement
			(enabled no)
			(sheetname "")
		)
		(fill
			(thermal_gap 0.5)
			(thermal_bridge_width 0.5)
			(island_removal_mode 0)
		)
		(polygon
			(pts
				(arc
					(start 242.80368 -129.858008)
					(mid 242.42268 -129.477008)
					(end 242.04168 -129.858008)
				)
				(arc
					(start 242.04168 -130.721608)
					(mid 242.42268 -131.102608)
					(end 242.80368 -130.721608)
				)
			)
		)
	)
	(zone
		(layers "F.Cu" "B.Cu" "In1.Cu" "In2.Cu" "In3.Cu" "In4.Cu" "In5.Cu" "In6.Cu"
			"In7.Cu" "In8.Cu" "In9.Cu" "In10.Cu" "In11.Cu" "In12.Cu" "In13.Cu" "In14.Cu"
			"In15.Cu" "In16.Cu"
		)
		(hatch none 0.5)
		(connect_pads
			(clearance 0)
		)
		(min_thickness 0.25)
		(keepout
			(tracks not_allowed)
			(vias allowed)
			(pads allowed)
			(copperpour not_allowed)
			(footprints allowed)
		)
		(placement
			(enabled no)
			(sheetname "")
		)
		(fill
			(thermal_gap 0.5)
			(thermal_bridge_width 0.5)
			(island_removal_mode 0)
		)
		(polygon
			(pts
				(arc
					(start 379.755146 -286.475424)
					(mid 379.097286 -286.475424)
					(end 379.755146 -286.475424)
				)
			)
		)
	)
	(zone
		(layers "F.Cu" "B.Cu" "In1.Cu" "In2.Cu" "In3.Cu" "In4.Cu" "In5.Cu" "In6.Cu"
			"In7.Cu" "In8.Cu" "In9.Cu" "In10.Cu" "In11.Cu" "In12.Cu" "In13.Cu" "In14.Cu"
			"In15.Cu" "In16.Cu"
		)
		(hatch none 0.5)
		(connect_pads
			(clearance 0)
		)
		(min_thickness 0.25)
		(keepout
			(tracks not_allowed)
			(vias allowed)
			(pads allowed)
			(copperpour not_allowed)
			(footprints allowed)
		)
		(placement
			(enabled no)
			(sheetname "")
		)
		(fill
			(thermal_gap 0.5)
			(thermal_bridge_width 0.5)
			(island_removal_mode 0)
		)
		(polygon
			(pts
				(arc
					(start 109.071664 -274.266914)
					(mid 109.729524 -274.266914)
					(end 109.071664 -274.266914)
				)
			)
		)
	)
	(zone
		(layers "F.Cu" "B.Cu" "In1.Cu" "In2.Cu" "In3.Cu" "In4.Cu" "In5.Cu" "In6.Cu"
			"In7.Cu" "In8.Cu" "In9.Cu" "In10.Cu" "In11.Cu" "In12.Cu" "In13.Cu" "In14.Cu"
			"In15.Cu" "In16.Cu"
		)
		(hatch none 0.5)
		(connect_pads
			(clearance 0)
		)
		(min_thickness 0.25)
		(keepout
			(tracks not_allowed)
			(vias allowed)
			(pads allowed)
			(copperpour not_allowed)
			(footprints allowed)
		)
		(placement
			(enabled no)
			(sheetname "")
		)
		(fill
			(thermal_gap 0.5)
			(thermal_bridge_width 0.5)
			(island_removal_mode 0)
		)
		(polygon
			(pts
				(arc
					(start 371.186964 -221.133924)
					(mid 370.529104 -221.133924)
					(end 371.186964 -221.133924)
				)
			)
		)
	)
	(zone
		(layers "F.Cu" "B.Cu" "In1.Cu" "In2.Cu" "In3.Cu" "In4.Cu" "In5.Cu" "In6.Cu"
			"In7.Cu" "In8.Cu" "In9.Cu" "In10.Cu" "In11.Cu" "In12.Cu" "In13.Cu" "In14.Cu"
			"In15.Cu" "In16.Cu"
		)
		(hatch none 0.5)
		(connect_pads
			(clearance 0)
		)
		(min_thickness 0.25)
		(keepout
			(tracks not_allowed)
			(vias allowed)
			(pads allowed)
			(copperpour not_allowed)
			(footprints allowed)
		)
		(placement
			(enabled no)
			(sheetname "")
		)
		(fill
			(thermal_gap 0.5)
			(thermal_bridge_width 0.5)
			(island_removal_mode 0)
		)
		(polygon
			(pts
				(arc
					(start 378.23521 -220.319854)
					(mid 377.57735 -220.319854)
					(end 378.23521 -220.319854)
				)
			)
		)
	)
	(zone
		(layers "F.Cu" "B.Cu" "In1.Cu" "In2.Cu" "In3.Cu" "In4.Cu" "In5.Cu" "In6.Cu"
			"In7.Cu" "In8.Cu" "In9.Cu" "In10.Cu" "In11.Cu" "In12.Cu" "In13.Cu" "In14.Cu"
			"In15.Cu" "In16.Cu"
		)
		(hatch none 0.5)
		(connect_pads
			(clearance 0)
		)
		(min_thickness 0.25)
		(keepout
			(tracks not_allowed)
			(vias allowed)
			(pads allowed)
			(copperpour not_allowed)
			(footprints allowed)
		)
		(placement
			(enabled no)
			(sheetname "")
		)
		(fill
			(thermal_gap 0.5)
			(thermal_bridge_width 0.5)
			(island_removal_mode 0)
		)
		(polygon
			(pts
				(arc
					(start 374.427496 -285.759652)
					(mid 374.44718 -285.712242)
					(end 374.453912 -285.661354)
				)
				(arc
					(start 374.453912 -285.661354)
					(mid 374.396256 -285.52216)
					(end 374.257062 -285.464504)
				)
				(arc
					(start 374.257062 -285.464504)
					(mid 374.158631 -285.49092)
					(end 374.086628 -285.563056)
				)
				(arc
					(start 373.616982 -286.377126)
					(mid 373.597298 -286.424536)
					(end 373.590566 -286.475424)
				)
				(arc
					(start 373.590566 -286.475424)
					(mid 373.648222 -286.614618)
					(end 373.787416 -286.672274)
				)
				(arc
					(start 373.787416 -286.672274)
					(mid 373.885847 -286.645858)
					(end 373.95785 -286.573722)
				)
			)
		)
	)
	(zone
		(layers "F.Cu" "B.Cu" "In1.Cu" "In2.Cu" "In3.Cu" "In4.Cu" "In5.Cu" "In6.Cu"
			"In7.Cu" "In8.Cu" "In9.Cu" "In10.Cu" "In11.Cu" "In12.Cu" "In13.Cu" "In14.Cu"
			"In15.Cu" "In16.Cu"
		)
		(hatch none 0.5)
		(connect_pads
			(clearance 0)
		)
		(min_thickness 0.25)
		(keepout
			(tracks not_allowed)
			(vias allowed)
			(pads allowed)
			(copperpour not_allowed)
			(footprints allowed)
		)
		(placement
			(enabled no)
			(sheetname "")
		)
		(fill
			(thermal_gap 0.5)
			(thermal_bridge_width 0.5)
			(island_removal_mode 0)
		)
		(polygon
			(pts
				(arc
					(start 110.559596 -218.692222)
					(mid 109.901736 -218.692222)
					(end 110.559596 -218.692222)
				)
			)
		)
	)
	(zone
		(layers "F.Cu" "B.Cu" "In1.Cu" "In2.Cu" "In3.Cu" "In4.Cu" "In5.Cu" "In6.Cu"
			"In7.Cu" "In8.Cu" "In9.Cu" "In10.Cu" "In11.Cu" "In12.Cu" "In13.Cu" "In14.Cu"
			"In15.Cu" "In16.Cu"
		)
		(hatch none 0.5)
		(connect_pads
			(clearance 0)
		)
		(min_thickness 0.25)
		(keepout
			(tracks not_allowed)
			(vias allowed)
			(pads allowed)
			(copperpour not_allowed)
			(footprints allowed)
		)
		(placement
			(enabled no)
			(sheetname "")
		)
		(fill
			(thermal_gap 0.5)
			(thermal_bridge_width 0.5)
			(island_removal_mode 0)
		)
		(polygon
			(pts
				(arc
					(start 127.945388 -214.622634)
					(mid 127.287528 -214.622634)
					(end 127.945388 -214.622634)
				)
			)
		)
	)
	(zone
		(layers "F.Cu" "B.Cu" "In1.Cu" "In2.Cu" "In3.Cu" "In4.Cu" "In5.Cu" "In6.Cu"
			"In7.Cu" "In8.Cu" "In9.Cu" "In10.Cu" "In11.Cu" "In12.Cu" "In13.Cu" "In14.Cu"
			"In15.Cu" "In16.Cu"
		)
		(hatch none 0.5)
		(connect_pads
			(clearance 0)
		)
		(min_thickness 0.25)
		(keepout
			(tracks not_allowed)
			(vias allowed)
			(pads allowed)
			(copperpour not_allowed)
			(footprints allowed)
		)
		(placement
			(enabled no)
			(sheetname "")
		)
		(fill
			(thermal_gap 0.5)
			(thermal_bridge_width 0.5)
			(island_removal_mode 0)
		)
		(polygon
			(pts
				(arc
					(start 104.560878 -288.103056)
					(mid 103.903018 -288.103056)
					(end 104.560878 -288.103056)
				)
			)
		)
	)
	(zone
		(layers "F.Cu" "B.Cu" "In1.Cu" "In2.Cu" "In3.Cu" "In4.Cu" "In5.Cu" "In6.Cu"
			"In7.Cu" "In8.Cu" "In9.Cu" "In10.Cu" "In11.Cu" "In12.Cu" "In13.Cu" "In14.Cu"
			"In15.Cu" "In16.Cu"
		)
		(hatch none 0.5)
		(connect_pads
			(clearance 0)
		)
		(min_thickness 0.25)
		(keepout
			(tracks not_allowed)
			(vias allowed)
			(pads allowed)
			(copperpour not_allowed)
			(footprints allowed)
		)
		(placement
			(enabled no)
			(sheetname "")
		)
		(fill
			(thermal_gap 0.5)
			(thermal_bridge_width 0.5)
			(island_removal_mode 0)
		)
		(polygon
			(pts
				(arc
					(start 90.665046 -217.162634)
					(mid 90.68473 -217.115224)
					(end 90.691462 -217.064336)
				)
				(arc
					(start 90.691462 -217.064336)
					(mid 90.633806 -216.925142)
					(end 90.494612 -216.867486)
				)
				(arc
					(start 90.494612 -216.867486)
					(mid 90.396181 -216.893902)
					(end 90.324178 -216.966038)
				)
				(arc
					(start 89.854532 -217.780108)
					(mid 89.834848 -217.827518)
					(end 89.828116 -217.878406)
				)
				(arc
					(start 89.828116 -217.878406)
					(mid 89.885772 -218.0176)
					(end 90.024966 -218.075256)
				)
				(arc
					(start 90.024966 -218.075256)
					(mid 90.123397 -218.04884)
					(end 90.1954 -217.976704)
				)
			)
		)
	)
	(zone
		(layers "F.Cu" "B.Cu" "In1.Cu" "In2.Cu" "In3.Cu" "In4.Cu" "In5.Cu" "In6.Cu"
			"In7.Cu" "In8.Cu" "In9.Cu" "In10.Cu" "In11.Cu" "In12.Cu" "In13.Cu" "In14.Cu"
			"In15.Cu" "In16.Cu"
		)
		(hatch none 0.5)
		(connect_pads
			(clearance 0)
		)
		(min_thickness 0.25)
		(keepout
			(tracks not_allowed)
			(vias allowed)
			(pads allowed)
			(copperpour not_allowed)
			(footprints allowed)
		)
		(placement
			(enabled no)
			(sheetname "")
		)
		(fill
			(thermal_gap 0.5)
			(thermal_bridge_width 0.5)
			(island_removal_mode 0)
		)
		(polygon
			(pts
				(arc
					(start 103.903018 -276.708616)
					(mid 104.560878 -276.708616)
					(end 103.903018 -276.708616)
				)
			)
		)
	)
	(zone
		(layers "F.Cu" "B.Cu" "In1.Cu" "In2.Cu" "In3.Cu" "In4.Cu" "In5.Cu" "In6.Cu"
			"In7.Cu" "In8.Cu" "In9.Cu" "In10.Cu" "In11.Cu" "In12.Cu" "In13.Cu" "In14.Cu"
			"In15.Cu" "In16.Cu"
		)
		(hatch none 0.5)
		(connect_pads
			(clearance 0)
		)
		(min_thickness 0.25)
		(keepout
			(tracks not_allowed)
			(vias allowed)
			(pads allowed)
			(copperpour not_allowed)
			(footprints allowed)
		)
		(placement
			(enabled no)
			(sheetname "")
		)
		(fill
			(thermal_gap 0.5)
			(thermal_bridge_width 0.5)
			(island_removal_mode 0)
		)
		(polygon
			(pts
				(arc
					(start 130.765296 -217.878406)
					(mid 130.107436 -217.878406)
					(end 130.765296 -217.878406)
				)
			)
		)
	)
	(zone
		(layers "F.Cu" "B.Cu" "In1.Cu" "In2.Cu" "In3.Cu" "In4.Cu" "In5.Cu" "In6.Cu"
			"In7.Cu" "In8.Cu" "In9.Cu" "In10.Cu" "In11.Cu" "In12.Cu" "In13.Cu" "In14.Cu"
			"In15.Cu" "In16.Cu"
		)
		(hatch none 0.5)
		(connect_pads
			(clearance 0)
		)
		(min_thickness 0.25)
		(keepout
			(tracks not_allowed)
			(vias allowed)
			(pads allowed)
			(copperpour not_allowed)
			(footprints allowed)
		)
		(placement
			(enabled no)
			(sheetname "")
		)
		(fill
			(thermal_gap 0.5)
			(thermal_bridge_width 0.5)
			(island_removal_mode 0)
		)
		(polygon
			(pts
				(arc
					(start 61.578998 -409.649168)
					(mid 61.197998 -410.030168)
					(end 61.578998 -410.411168)
				)
				(arc
					(start 62.442598 -410.411168)
					(mid 62.823598 -410.030168)
					(end 62.442598 -409.649168)
				)
			)
		)
	)
	(zone
		(layers "F.Cu" "B.Cu" "In1.Cu" "In2.Cu" "In3.Cu" "In4.Cu" "In5.Cu" "In6.Cu"
			"In7.Cu" "In8.Cu" "In9.Cu" "In10.Cu" "In11.Cu" "In12.Cu" "In13.Cu" "In14.Cu"
			"In15.Cu" "In16.Cu"
		)
		(hatch none 0.5)
		(connect_pads
			(clearance 0)
		)
		(min_thickness 0.25)
		(keepout
			(tracks not_allowed)
			(vias allowed)
			(pads allowed)
			(copperpour not_allowed)
			(footprints allowed)
		)
		(placement
			(enabled no)
			(sheetname "")
		)
		(fill
			(thermal_gap 0.5)
			(thermal_bridge_width 0.5)
			(island_removal_mode 0)
		)
		(polygon
			(pts
				(arc
					(start 132.596636 -288.005012)
					(mid 132.524647 -287.932853)
					(end 132.426202 -287.90646)
				)
				(arc
					(start 132.426202 -287.90646)
					(mid 132.287008 -287.964116)
					(end 132.229352 -288.10331)
				)
				(arc
					(start 132.229352 -288.10331)
					(mid 132.236109 -288.154191)
					(end 132.255768 -288.201608)
				)
				(arc
					(start 132.725414 -289.015424)
					(mid 132.797403 -289.087583)
					(end 132.895848 -289.113976)
				)
				(arc
					(start 132.895848 -289.113976)
					(mid 133.035042 -289.05632)
					(end 133.092698 -288.917126)
				)
				(arc
					(start 133.092698 -288.917126)
					(mid 133.085941 -288.866245)
					(end 133.066282 -288.818828)
				)
			)
		)
	)
	(zone
		(layers "F.Cu" "B.Cu" "In1.Cu" "In2.Cu" "In3.Cu" "In4.Cu" "In5.Cu" "In6.Cu"
			"In7.Cu" "In8.Cu" "In9.Cu" "In10.Cu" "In11.Cu" "In12.Cu" "In13.Cu" "In14.Cu"
			"In15.Cu" "In16.Cu"
		)
		(hatch none 0.5)
		(connect_pads
			(clearance 0)
		)
		(min_thickness 0.25)
		(keepout
			(tracks not_allowed)
			(vias allowed)
			(pads allowed)
			(copperpour not_allowed)
			(footprints allowed)
		)
		(placement
			(enabled no)
			(sheetname "")
		)
		(fill
			(thermal_gap 0.5)
			(thermal_bridge_width 0.5)
			(island_removal_mode 0)
		)
		(polygon
			(pts
				(arc
					(start 155.196794 -409.649168)
					(mid 154.815794 -410.030168)
					(end 155.196794 -410.411168)
				)
				(arc
					(start 156.060394 -410.411168)
					(mid 156.441394 -410.030168)
					(end 156.060394 -409.649168)
				)
			)
		)
	)
	(zone
		(layers "F.Cu" "B.Cu" "In1.Cu" "In2.Cu" "In3.Cu" "In4.Cu" "In5.Cu" "In6.Cu"
			"In7.Cu" "In8.Cu" "In9.Cu" "In10.Cu" "In11.Cu" "In12.Cu" "In13.Cu" "In14.Cu"
			"In15.Cu" "In16.Cu"
		)
		(hatch none 0.5)
		(connect_pads
			(clearance 0)
		)
		(min_thickness 0.25)
		(keepout
			(tracks not_allowed)
			(vias allowed)
			(pads allowed)
			(copperpour not_allowed)
			(footprints allowed)
		)
		(placement
			(enabled no)
			(sheetname "")
		)
		(fill
			(thermal_gap 0.5)
			(thermal_bridge_width 0.5)
			(island_removal_mode 0)
		)
		(polygon
			(pts
				(arc
					(start 98.922078 -284.847538)
					(mid 98.264218 -284.847538)
					(end 98.922078 -284.847538)
				)
			)
		)
	)
	(zone
		(layers "F.Cu" "B.Cu" "In1.Cu" "In2.Cu" "In3.Cu" "In4.Cu" "In5.Cu" "In6.Cu"
			"In7.Cu" "In8.Cu" "In9.Cu" "In10.Cu" "In11.Cu" "In12.Cu" "In13.Cu" "In14.Cu"
			"In15.Cu" "In16.Cu"
		)
		(hatch none 0.5)
		(connect_pads
			(clearance 0)
		)
		(min_thickness 0.25)
		(keepout
			(tracks not_allowed)
			(vias allowed)
			(pads allowed)
			(copperpour not_allowed)
			(footprints allowed)
		)
		(placement
			(enabled no)
			(sheetname "")
		)
		(fill
			(thermal_gap 0.5)
			(thermal_bridge_width 0.5)
			(island_removal_mode 0)
		)
		(polygon
			(pts
				(arc
					(start 94.974918 -288.917126)
					(mid 95.632778 -288.917126)
					(end 94.974918 -288.917126)
				)
			)
		)
	)
	(zone
		(layers "F.Cu" "B.Cu" "In1.Cu" "In2.Cu" "In3.Cu" "In4.Cu" "In5.Cu" "In6.Cu"
			"In7.Cu" "In8.Cu" "In9.Cu" "In10.Cu" "In11.Cu" "In12.Cu" "In13.Cu" "In14.Cu"
			"In15.Cu" "In16.Cu"
		)
		(hatch none 0.5)
		(connect_pads
			(clearance 0)
		)
		(min_thickness 0.25)
		(keepout
			(tracks not_allowed)
			(vias allowed)
			(pads allowed)
			(copperpour not_allowed)
			(footprints allowed)
		)
		(placement
			(enabled no)
			(sheetname "")
		)
		(fill
			(thermal_gap 0.5)
			(thermal_bridge_width 0.5)
			(island_removal_mode 0)
		)
		(polygon
			(pts
				(arc
					(start 349.681546 -286.475424)
					(mid 349.023686 -286.475424)
					(end 349.681546 -286.475424)
				)
			)
		)
	)
	(zone
		(layers "F.Cu" "B.Cu" "In1.Cu" "In2.Cu" "In3.Cu" "In4.Cu" "In5.Cu" "In6.Cu"
			"In7.Cu" "In8.Cu" "In9.Cu" "In10.Cu" "In11.Cu" "In12.Cu" "In13.Cu" "In14.Cu"
			"In15.Cu" "In16.Cu"
		)
		(hatch none 0.5)
		(connect_pads
			(clearance 0)
		)
		(min_thickness 0.25)
		(keepout
			(tracks not_allowed)
			(vias allowed)
			(pads allowed)
			(copperpour not_allowed)
			(footprints allowed)
		)
		(placement
			(enabled no)
			(sheetname "")
		)
		(fill
			(thermal_gap 0.5)
			(thermal_bridge_width 0.5)
			(island_removal_mode 0)
		)
		(polygon
			(pts
				(arc
					(start 120.848628 -285.759652)
					(mid 120.868312 -285.712242)
					(end 120.875044 -285.661354)
				)
				(arc
					(start 120.875044 -285.661354)
					(mid 120.817388 -285.52216)
					(end 120.678194 -285.464504)
				)
				(arc
					(start 120.678194 -285.464504)
					(mid 120.579763 -285.49092)
					(end 120.50776 -285.563056)
				)
				(arc
					(start 120.038114 -286.377126)
					(mid 120.01843 -286.424536)
					(end 120.011698 -286.475424)
				)
				(arc
					(start 120.011698 -286.475424)
					(mid 120.069354 -286.614618)
					(end 120.208548 -286.672274)
				)
				(arc
					(start 120.208548 -286.672274)
					(mid 120.306979 -286.645858)
					(end 120.378982 -286.573722)
				)
			)
		)
	)
	(zone
		(layers "F.Cu" "B.Cu" "In1.Cu" "In2.Cu" "In3.Cu" "In4.Cu" "In5.Cu" "In6.Cu"
			"In7.Cu" "In8.Cu" "In9.Cu" "In10.Cu" "In11.Cu" "In12.Cu" "In13.Cu" "In14.Cu"
			"In15.Cu" "In16.Cu"
		)
		(hatch none 0.5)
		(connect_pads
			(clearance 0)
		)
		(min_thickness 0.25)
		(keepout
			(tracks not_allowed)
			(vias allowed)
			(pads allowed)
			(copperpour not_allowed)
			(footprints allowed)
		)
		(placement
			(enabled no)
			(sheetname "")
		)
		(fill
			(thermal_gap 0.5)
			(thermal_bridge_width 0.5)
			(island_removal_mode 0)
		)
		(polygon
			(pts
				(arc
					(start 337.675728 -403.502876)
					(mid 337.294728 -403.883876)
					(end 337.675728 -404.264876)
				)
				(arc
					(start 338.539328 -404.264876)
					(mid 338.920328 -403.883876)
					(end 338.539328 -403.502876)
				)
			)
		)
	)
	(zone
		(layers "F.Cu" "B.Cu" "In1.Cu" "In2.Cu" "In3.Cu" "In4.Cu" "In5.Cu" "In6.Cu"
			"In7.Cu" "In8.Cu" "In9.Cu" "In10.Cu" "In11.Cu" "In12.Cu" "In13.Cu" "In14.Cu"
			"In15.Cu" "In16.Cu"
		)
		(hatch none 0.5)
		(connect_pads
			(clearance 0)
		)
		(min_thickness 0.25)
		(keepout
			(tracks not_allowed)
			(vias allowed)
			(pads allowed)
			(copperpour not_allowed)
			(footprints allowed)
		)
		(placement
			(enabled no)
			(sheetname "")
		)
		(fill
			(thermal_gap 0.5)
			(thermal_bridge_width 0.5)
			(island_removal_mode 0)
		)
		(polygon
			(pts
				(arc
					(start 357.089964 -221.133924)
					(mid 356.432104 -221.133924)
					(end 357.089964 -221.133924)
				)
			)
		)
	)
	(zone
		(layers "F.Cu" "B.Cu" "In1.Cu" "In2.Cu" "In3.Cu" "In4.Cu" "In5.Cu" "In6.Cu"
			"In7.Cu" "In8.Cu" "In9.Cu" "In10.Cu" "In11.Cu" "In12.Cu" "In13.Cu" "In14.Cu"
			"In15.Cu" "In16.Cu"
		)
		(hatch none 0.5)
		(connect_pads
			(clearance 0)
		)
		(min_thickness 0.25)
		(keepout
			(tracks not_allowed)
			(vias allowed)
			(pads allowed)
			(copperpour not_allowed)
			(footprints allowed)
		)
		(placement
			(enabled no)
			(sheetname "")
		)
		(fill
			(thermal_gap 0.5)
			(thermal_bridge_width 0.5)
			(island_removal_mode 0)
		)
		(polygon
			(pts
				(arc
					(start 372.126764 -224.389442)
					(mid 371.468904 -224.389442)
					(end 372.126764 -224.389442)
				)
			)
		)
	)
	(zone
		(layers "F.Cu" "B.Cu" "In1.Cu" "In2.Cu" "In3.Cu" "In4.Cu" "In5.Cu" "In6.Cu"
			"In7.Cu" "In8.Cu" "In9.Cu" "In10.Cu" "In11.Cu" "In12.Cu" "In13.Cu" "In14.Cu"
			"In15.Cu" "In16.Cu"
		)
		(hatch none 0.5)
		(connect_pads
			(clearance 0)
		)
		(min_thickness 0.25)
		(keepout
			(tracks not_allowed)
			(vias allowed)
			(pads allowed)
			(copperpour not_allowed)
			(footprints allowed)
		)
		(placement
			(enabled no)
			(sheetname "")
		)
		(fill
			(thermal_gap 0.5)
			(thermal_bridge_width 0.5)
			(island_removal_mode 0)
		)
		(polygon
			(pts
				(arc
					(start 331.549248 -403.502876)
					(mid 331.168248 -403.883876)
					(end 331.549248 -404.264876)
				)
				(arc
					(start 332.412848 -404.264876)
					(mid 332.793848 -403.883876)
					(end 332.412848 -403.502876)
				)
			)
		)
	)
	(zone
		(layers "F.Cu" "B.Cu" "In1.Cu" "In2.Cu" "In3.Cu" "In4.Cu" "In5.Cu" "In6.Cu"
			"In7.Cu" "In8.Cu" "In9.Cu" "In10.Cu" "In11.Cu" "In12.Cu" "In13.Cu" "In14.Cu"
			"In15.Cu" "In16.Cu"
		)
		(hatch none 0.5)
		(connect_pads
			(clearance 0)
		)
		(min_thickness 0.25)
		(keepout
			(tracks not_allowed)
			(vias allowed)
			(pads allowed)
			(copperpour not_allowed)
			(footprints allowed)
		)
		(placement
			(enabled no)
			(sheetname "")
		)
		(fill
			(thermal_gap 0.5)
			(thermal_bridge_width 0.5)
			(island_removal_mode 0)
		)
		(polygon
			(pts
				(arc
					(start 371.186964 -217.878406)
					(mid 370.529104 -217.878406)
					(end 371.186964 -217.878406)
				)
			)
		)
	)
	(zone
		(layers "F.Cu" "B.Cu" "In1.Cu" "In2.Cu" "In3.Cu" "In4.Cu" "In5.Cu" "In6.Cu"
			"In7.Cu" "In8.Cu" "In9.Cu" "In10.Cu" "In11.Cu" "In12.Cu" "In13.Cu" "In14.Cu"
			"In15.Cu" "In16.Cu"
		)
		(hatch none 0.5)
		(connect_pads
			(clearance 0)
		)
		(min_thickness 0.25)
		(keepout
			(tracks not_allowed)
			(vias allowed)
			(pads allowed)
			(copperpour not_allowed)
			(footprints allowed)
		)
		(placement
			(enabled no)
			(sheetname "")
		)
		(fill
			(thermal_gap 0.5)
			(thermal_bridge_width 0.5)
			(island_removal_mode 0)
		)
		(polygon
			(pts
				(arc
					(start 341.112856 -214.622634)
					(mid 340.454996 -214.622634)
					(end 341.112856 -214.622634)
				)
			)
		)
	)
	(zone
		(layers "F.Cu" "B.Cu" "In1.Cu" "In2.Cu" "In3.Cu" "In4.Cu" "In5.Cu" "In6.Cu"
			"In7.Cu" "In8.Cu" "In9.Cu" "In10.Cu" "In11.Cu" "In12.Cu" "In13.Cu" "In14.Cu"
			"In15.Cu" "In16.Cu"
		)
		(hatch none 0.5)
		(connect_pads
			(clearance 0)
		)
		(min_thickness 0.25)
		(keepout
			(tracks not_allowed)
			(vias allowed)
			(pads allowed)
			(copperpour not_allowed)
			(footprints allowed)
		)
		(placement
			(enabled no)
			(sheetname "")
		)
		(fill
			(thermal_gap 0.5)
			(thermal_bridge_width 0.5)
			(island_removal_mode 0)
		)
		(polygon
			(pts
				(arc
					(start 341.223092 -283.219906)
					(mid 340.565232 -283.219906)
					(end 341.223092 -283.219906)
				)
			)
		)
	)
	(zone
		(layers "F.Cu" "B.Cu" "In1.Cu" "In2.Cu" "In3.Cu" "In4.Cu" "In5.Cu" "In6.Cu"
			"In7.Cu" "In8.Cu" "In9.Cu" "In10.Cu" "In11.Cu" "In12.Cu" "In13.Cu" "In14.Cu"
			"In15.Cu" "In16.Cu"
		)
		(hatch none 0.5)
		(connect_pads
			(clearance 0)
		)
		(min_thickness 0.25)
		(keepout
			(tracks not_allowed)
			(vias allowed)
			(pads allowed)
			(copperpour not_allowed)
			(footprints allowed)
		)
		(placement
			(enabled no)
			(sheetname "")
		)
		(fill
			(thermal_gap 0.5)
			(thermal_bridge_width 0.5)
			(island_removal_mode 0)
		)
		(polygon
			(pts
				(arc
					(start 118.547896 -217.878406)
					(mid 117.890036 -217.878406)
					(end 118.547896 -217.878406)
				)
			)
		)
	)
	(zone
		(layers "F.Cu" "B.Cu" "In1.Cu" "In2.Cu" "In3.Cu" "In4.Cu" "In5.Cu" "In6.Cu"
			"In7.Cu" "In8.Cu" "In9.Cu" "In10.Cu" "In11.Cu" "In12.Cu" "In13.Cu" "In14.Cu"
			"In15.Cu" "In16.Cu"
		)
		(hatch none 0.5)
		(connect_pads
			(clearance 0)
		)
		(min_thickness 0.25)
		(keepout
			(tracks not_allowed)
			(vias allowed)
			(pads allowed)
			(copperpour not_allowed)
			(footprints allowed)
		)
		(placement
			(enabled no)
			(sheetname "")
		)
		(fill
			(thermal_gap 0.5)
			(thermal_bridge_width 0.5)
			(island_removal_mode 0)
		)
		(polygon
			(pts
				(arc
					(start 108.990892 -221.231968)
					(mid 109.010576 -221.184558)
					(end 109.017308 -221.13367)
				)
				(arc
					(start 109.017308 -221.13367)
					(mid 108.959652 -220.994476)
					(end 108.820458 -220.93682)
				)
				(arc
					(start 108.820458 -220.93682)
					(mid 108.722027 -220.963236)
					(end 108.650024 -221.035372)
				)
				(arc
					(start 108.180378 -221.849442)
					(mid 108.160694 -221.896852)
					(end 108.153962 -221.94774)
				)
				(arc
					(start 108.153962 -221.94774)
					(mid 108.211618 -222.086934)
					(end 108.350812 -222.14459)
				)
				(arc
					(start 108.350812 -222.14459)
					(mid 108.449243 -222.118174)
					(end 108.521246 -222.046038)
				)
			)
		)
	)
	(zone
		(layers "F.Cu" "B.Cu" "In1.Cu" "In2.Cu" "In3.Cu" "In4.Cu" "In5.Cu" "In6.Cu"
			"In7.Cu" "In8.Cu" "In9.Cu" "In10.Cu" "In11.Cu" "In12.Cu" "In13.Cu" "In14.Cu"
			"In15.Cu" "In16.Cu"
		)
		(hatch none 0.5)
		(connect_pads
			(clearance 0)
		)
		(min_thickness 0.25)
		(keepout
			(tracks not_allowed)
			(vias allowed)
			(pads allowed)
			(copperpour not_allowed)
			(footprints allowed)
		)
		(placement
			(enabled no)
			(sheetname "")
		)
		(fill
			(thermal_gap 0.5)
			(thermal_bridge_width 0.5)
			(island_removal_mode 0)
		)
		(polygon
			(pts
				(arc
					(start 409.52801 -406.62352)
					(mid 409.14701 -407.00452)
					(end 409.52801 -407.38552)
				)
				(arc
					(start 410.39161 -407.38552)
					(mid 410.77261 -407.00452)
					(end 410.39161 -406.62352)
				)
			)
		)
	)
	(zone
		(layers "F.Cu" "B.Cu" "In1.Cu" "In2.Cu" "In3.Cu" "In4.Cu" "In5.Cu" "In6.Cu"
			"In7.Cu" "In8.Cu" "In9.Cu" "In10.Cu" "In11.Cu" "In12.Cu" "In13.Cu" "In14.Cu"
			"In15.Cu" "In16.Cu"
		)
		(hatch none 0.5)
		(connect_pads
			(clearance 0)
		)
		(min_thickness 0.25)
		(keepout
			(tracks not_allowed)
			(vias allowed)
			(pads allowed)
			(copperpour not_allowed)
			(footprints allowed)
		)
		(placement
			(enabled no)
			(sheetname "")
		)
		(fill
			(thermal_gap 0.5)
			(thermal_bridge_width 0.5)
			(island_removal_mode 0)
		)
		(polygon
			(pts
				(arc
					(start 376.667268 -224.291144)
					(mid 376.595279 -224.218985)
					(end 376.496834 -224.192592)
				)
				(arc
					(start 376.496834 -224.192592)
					(mid 376.35764 -224.250248)
					(end 376.299984 -224.389442)
				)
				(arc
					(start 376.299984 -224.389442)
					(mid 376.306741 -224.440323)
					(end 376.3264 -224.48774)
				)
				(arc
					(start 376.796046 -225.301556)
					(mid 376.868035 -225.373715)
					(end 376.96648 -225.400108)
				)
				(arc
					(start 376.96648 -225.400108)
					(mid 377.105674 -225.342452)
					(end 377.16333 -225.203258)
				)
				(arc
					(start 377.16333 -225.203258)
					(mid 377.156573 -225.152377)
					(end 377.136914 -225.10496)
				)
			)
		)
	)
	(zone
		(layers "F.Cu" "B.Cu" "In1.Cu" "In2.Cu" "In3.Cu" "In4.Cu" "In5.Cu" "In6.Cu"
			"In7.Cu" "In8.Cu" "In9.Cu" "In10.Cu" "In11.Cu" "In12.Cu" "In13.Cu" "In14.Cu"
			"In15.Cu" "In16.Cu"
		)
		(hatch none 0.5)
		(connect_pads
			(clearance 0)
		)
		(min_thickness 0.25)
		(keepout
			(tracks not_allowed)
			(vias allowed)
			(pads allowed)
			(copperpour not_allowed)
			(footprints allowed)
		)
		(placement
			(enabled no)
			(sheetname "")
		)
		(fill
			(thermal_gap 0.5)
			(thermal_bridge_width 0.5)
			(island_removal_mode 0)
		)
		(polygon
			(pts
				(arc
					(start 98.17608 -213.646766)
					(mid 98.108372 -213.574915)
					(end 98.013266 -213.548468)
				)
				(arc
					(start 98.013266 -213.548468)
					(mid 97.883052 -213.602404)
					(end 97.829116 -213.732618)
				)
				(arc
					(start 97.829116 -213.732618)
					(mid 97.834567 -213.776839)
					(end 97.850452 -213.81847)
				)
				(arc
					(start 98.319844 -214.708486)
					(mid 98.387552 -214.780337)
					(end 98.482658 -214.806784)
				)
				(arc
					(start 98.482658 -214.806784)
					(mid 98.612872 -214.752848)
					(end 98.666808 -214.622634)
				)
				(arc
					(start 98.666808 -214.622634)
					(mid 98.661357 -214.578413)
					(end 98.645472 -214.536782)
				)
			)
		)
	)
	(zone
		(layers "F.Cu" "B.Cu" "In1.Cu" "In2.Cu" "In3.Cu" "In4.Cu" "In5.Cu" "In6.Cu"
			"In7.Cu" "In8.Cu" "In9.Cu" "In10.Cu" "In11.Cu" "In12.Cu" "In13.Cu" "In14.Cu"
			"In15.Cu" "In16.Cu"
		)
		(hatch none 0.5)
		(connect_pads
			(clearance 0)
		)
		(min_thickness 0.25)
		(keepout
			(tracks not_allowed)
			(vias allowed)
			(pads allowed)
			(copperpour not_allowed)
			(footprints allowed)
		)
		(placement
			(enabled no)
			(sheetname "")
		)
		(fill
			(thermal_gap 0.5)
			(thermal_bridge_width 0.5)
			(island_removal_mode 0)
		)
		(polygon
			(pts
				(arc
					(start 139.20978 -19.779488)
					(mid 138.82878 -20.160488)
					(end 139.20978 -20.541488)
				)
				(arc
					(start 140.07338 -20.541488)
					(mid 140.45438 -20.160488)
					(end 140.07338 -19.779488)
				)
			)
		)
	)
	(zone
		(layers "F.Cu" "B.Cu" "In1.Cu" "In2.Cu" "In3.Cu" "In4.Cu" "In5.Cu" "In6.Cu"
			"In7.Cu" "In8.Cu" "In9.Cu" "In10.Cu" "In11.Cu" "In12.Cu" "In13.Cu" "In14.Cu"
			"In15.Cu" "In16.Cu"
		)
		(hatch none 0.5)
		(connect_pads
			(clearance 0)
		)
		(min_thickness 0.25)
		(keepout
			(tracks not_allowed)
			(vias allowed)
			(pads allowed)
			(copperpour not_allowed)
			(footprints allowed)
		)
		(placement
			(enabled no)
			(sheetname "")
		)
		(fill
			(thermal_gap 0.5)
			(thermal_bridge_width 0.5)
			(island_removal_mode 0)
		)
		(polygon
			(pts
				(arc
					(start 101.443282 -220.319854)
					(mid 102.101142 -220.319854)
					(end 101.443282 -220.319854)
				)
			)
		)
	)
	(zone
		(layers "F.Cu" "B.Cu" "In1.Cu" "In2.Cu" "In3.Cu" "In4.Cu" "In5.Cu" "In6.Cu"
			"In7.Cu" "In8.Cu" "In9.Cu" "In10.Cu" "In11.Cu" "In12.Cu" "In13.Cu" "In14.Cu"
			"In15.Cu" "In16.Cu"
		)
		(hatch none 0.5)
		(connect_pads
			(clearance 0)
		)
		(min_thickness 0.25)
		(keepout
			(tracks not_allowed)
			(vias allowed)
			(pads allowed)
			(copperpour not_allowed)
			(footprints allowed)
		)
		(placement
			(enabled no)
			(sheetname "")
		)
		(fill
			(thermal_gap 0.5)
			(thermal_bridge_width 0.5)
			(island_removal_mode 0)
		)
		(polygon
			(pts
				(arc
					(start 366.799622 -220.22181)
					(mid 366.727633 -220.149651)
					(end 366.629188 -220.123258)
				)
				(arc
					(start 366.629188 -220.123258)
					(mid 366.489994 -220.180914)
					(end 366.432338 -220.320108)
				)
				(arc
					(start 366.432338 -220.320108)
					(mid 366.439095 -220.370989)
					(end 366.458754 -220.418406)
				)
				(arc
					(start 366.9284 -221.232222)
					(mid 367.000389 -221.304381)
					(end 367.098834 -221.330774)
				)
				(arc
					(start 367.098834 -221.330774)
					(mid 367.238028 -221.273118)
					(end 367.295684 -221.133924)
				)
				(arc
					(start 367.295684 -221.133924)
					(mid 367.288927 -221.083043)
					(end 367.269268 -221.035626)
				)
			)
		)
	)
	(zone
		(layers "F.Cu" "B.Cu" "In1.Cu" "In2.Cu" "In3.Cu" "In4.Cu" "In5.Cu" "In6.Cu"
			"In7.Cu" "In8.Cu" "In9.Cu" "In10.Cu" "In11.Cu" "In12.Cu" "In13.Cu" "In14.Cu"
			"In15.Cu" "In16.Cu"
		)
		(hatch none 0.5)
		(connect_pads
			(clearance 0)
		)
		(min_thickness 0.25)
		(keepout
			(tracks not_allowed)
			(vias allowed)
			(pads allowed)
			(copperpour not_allowed)
			(footprints allowed)
		)
		(placement
			(enabled no)
			(sheetname "")
		)
		(fill
			(thermal_gap 0.5)
			(thermal_bridge_width 0.5)
			(island_removal_mode 0)
		)
		(polygon
			(pts
				(arc
					(start 116.198142 -225.203258)
					(mid 115.540282 -225.203258)
					(end 116.198142 -225.203258)
				)
			)
		)
	)
	(zone
		(layers "F.Cu" "B.Cu" "In1.Cu" "In2.Cu" "In3.Cu" "In4.Cu" "In5.Cu" "In6.Cu"
			"In7.Cu" "In8.Cu" "In9.Cu" "In10.Cu" "In11.Cu" "In12.Cu" "In13.Cu" "In14.Cu"
			"In15.Cu" "In16.Cu"
		)
		(hatch none 0.5)
		(connect_pads
			(clearance 0)
		)
		(min_thickness 0.25)
		(keepout
			(tracks not_allowed)
			(vias allowed)
			(pads allowed)
			(copperpour not_allowed)
			(footprints allowed)
		)
		(placement
			(enabled no)
			(sheetname "")
		)
		(fill
			(thermal_gap 0.5)
			(thermal_bridge_width 0.5)
			(island_removal_mode 0)
		)
		(polygon
			(pts
				(arc
					(start 362.728764 -224.389442)
					(mid 362.070904 -224.389442)
					(end 362.728764 -224.389442)
				)
			)
		)
	)
	(zone
		(layers "F.Cu" "B.Cu" "In1.Cu" "In2.Cu" "In3.Cu" "In4.Cu" "In5.Cu" "In6.Cu"
			"In7.Cu" "In8.Cu" "In9.Cu" "In10.Cu" "In11.Cu" "In12.Cu" "In13.Cu" "In14.Cu"
			"In15.Cu" "In16.Cu"
		)
		(hatch none 0.5)
		(connect_pads
			(clearance 0)
		)
		(min_thickness 0.25)
		(keepout
			(tracks not_allowed)
			(vias allowed)
			(pads allowed)
			(copperpour not_allowed)
			(footprints allowed)
		)
		(placement
			(enabled no)
			(sheetname "")
		)
		(fill
			(thermal_gap 0.5)
			(thermal_bridge_width 0.5)
			(island_removal_mode 0)
		)
		(polygon
			(pts
				(arc
					(start 401.217384 -17.220438)
					(mid 400.836384 -17.601438)
					(end 401.217384 -17.982438)
				)
				(arc
					(start 402.080984 -17.982438)
					(mid 402.461984 -17.601438)
					(end 402.080984 -17.220438)
				)
			)
		)
	)
	(zone
		(layers "F.Cu" "B.Cu" "In1.Cu" "In2.Cu" "In3.Cu" "In4.Cu" "In5.Cu" "In6.Cu"
			"In7.Cu" "In8.Cu" "In9.Cu" "In10.Cu" "In11.Cu" "In12.Cu" "In13.Cu" "In14.Cu"
			"In15.Cu" "In16.Cu"
		)
		(hatch none 0.5)
		(connect_pads
			(clearance 0)
		)
		(min_thickness 0.25)
		(keepout
			(tracks not_allowed)
			(vias allowed)
			(pads allowed)
			(copperpour not_allowed)
			(footprints allowed)
		)
		(placement
			(enabled no)
			(sheetname "")
		)
		(fill
			(thermal_gap 0.5)
			(thermal_bridge_width 0.5)
			(island_removal_mode 0)
		)
		(polygon
			(pts
				(arc
					(start 344.2208 -86.193122)
					(mid 344.6018 -85.812122)
					(end 344.2208 -85.431122)
				)
				(arc
					(start 343.3572 -85.431122)
					(mid 342.9762 -85.812122)
					(end 343.3572 -86.193122)
				)
			)
		)
	)
	(zone
		(layers "F.Cu" "B.Cu" "In1.Cu" "In2.Cu" "In3.Cu" "In4.Cu" "In5.Cu" "In6.Cu"
			"In7.Cu" "In8.Cu" "In9.Cu" "In10.Cu" "In11.Cu" "In12.Cu" "In13.Cu" "In14.Cu"
			"In15.Cu" "In16.Cu"
		)
		(hatch none 0.5)
		(connect_pads
			(clearance 0)
		)
		(min_thickness 0.25)
		(keepout
			(tracks not_allowed)
			(vias allowed)
			(pads allowed)
			(copperpour not_allowed)
			(footprints allowed)
		)
		(placement
			(enabled no)
			(sheetname "")
		)
		(fill
			(thermal_gap 0.5)
			(thermal_bridge_width 0.5)
			(island_removal_mode 0)
		)
		(polygon
			(pts
				(arc
					(start 341.693246 -288.917126)
					(mid 341.035386 -288.917126)
					(end 341.693246 -288.917126)
				)
			)
		)
	)
	(zone
		(layers "F.Cu" "B.Cu" "In1.Cu" "In2.Cu" "In3.Cu" "In4.Cu" "In5.Cu" "In6.Cu"
			"In7.Cu" "In8.Cu" "In9.Cu" "In10.Cu" "In11.Cu" "In12.Cu" "In13.Cu" "In14.Cu"
			"In15.Cu" "In16.Cu"
		)
		(hatch none 0.5)
		(connect_pads
			(clearance 0)
		)
		(min_thickness 0.25)
		(keepout
			(tracks not_allowed)
			(vias allowed)
			(pads allowed)
			(copperpour not_allowed)
			(footprints allowed)
		)
		(placement
			(enabled no)
			(sheetname "")
		)
		(fill
			(thermal_gap 0.5)
			(thermal_bridge_width 0.5)
			(island_removal_mode 0)
		)
		(polygon
			(pts
				(arc
					(start 108.76026 -276.610318)
					(mid 108.740576 -276.657728)
					(end 108.733844 -276.708616)
				)
				(arc
					(start 108.733844 -276.708616)
					(mid 108.7915 -276.84781)
					(end 108.930694 -276.905466)
				)
				(arc
					(start 108.930694 -276.905466)
					(mid 109.029125 -276.87905)
					(end 109.101128 -276.806914)
				)
				(arc
					(start 109.571028 -275.992844)
					(mid 109.590712 -275.945434)
					(end 109.597444 -275.894546)
				)
				(arc
					(start 109.597444 -275.894546)
					(mid 109.539788 -275.755352)
					(end 109.400594 -275.697696)
				)
				(arc
					(start 109.400594 -275.697696)
					(mid 109.302163 -275.724112)
					(end 109.23016 -275.796248)
				)
			)
		)
	)
	(zone
		(layers "F.Cu" "B.Cu" "In1.Cu" "In2.Cu" "In3.Cu" "In4.Cu" "In5.Cu" "In6.Cu"
			"In7.Cu" "In8.Cu" "In9.Cu" "In10.Cu" "In11.Cu" "In12.Cu" "In13.Cu" "In14.Cu"
			"In15.Cu" "In16.Cu"
		)
		(hatch none 0.5)
		(connect_pads
			(clearance 0)
		)
		(min_thickness 0.25)
		(keepout
			(tracks not_allowed)
			(vias allowed)
			(pads allowed)
			(copperpour not_allowed)
			(footprints allowed)
		)
		(placement
			(enabled no)
			(sheetname "")
		)
		(fill
			(thermal_gap 0.5)
			(thermal_bridge_width 0.5)
			(island_removal_mode 0)
		)
		(polygon
			(pts
				(arc
					(start 351.091246 -288.917126)
					(mid 350.433386 -288.917126)
					(end 351.091246 -288.917126)
				)
			)
		)
	)
	(zone
		(layers "F.Cu" "B.Cu" "In1.Cu" "In2.Cu" "In3.Cu" "In4.Cu" "In5.Cu" "In6.Cu"
			"In7.Cu" "In8.Cu" "In9.Cu" "In10.Cu" "In11.Cu" "In12.Cu" "In13.Cu" "In14.Cu"
			"In15.Cu" "In16.Cu"
		)
		(hatch none 0.5)
		(connect_pads
			(clearance 0)
		)
		(min_thickness 0.25)
		(keepout
			(tracks not_allowed)
			(vias allowed)
			(pads allowed)
			(copperpour not_allowed)
			(footprints allowed)
		)
		(placement
			(enabled no)
			(sheetname "")
		)
		(fill
			(thermal_gap 0.5)
			(thermal_bridge_width 0.5)
			(island_removal_mode 0)
		)
		(polygon
			(pts
				(arc
					(start 356.61981 -221.94774)
					(mid 355.96195 -221.94774)
					(end 356.61981 -221.94774)
				)
			)
		)
	)
	(zone
		(layers "F.Cu" "B.Cu" "In1.Cu" "In2.Cu" "In3.Cu" "In4.Cu" "In5.Cu" "In6.Cu"
			"In7.Cu" "In8.Cu" "In9.Cu" "In10.Cu" "In11.Cu" "In12.Cu" "In13.Cu" "In14.Cu"
			"In15.Cu" "In16.Cu"
		)
		(hatch none 0.5)
		(connect_pads
			(clearance 0)
		)
		(min_thickness 0.25)
		(keepout
			(tracks not_allowed)
			(vias allowed)
			(pads allowed)
			(copperpour not_allowed)
			(footprints allowed)
		)
		(placement
			(enabled no)
			(sheetname "")
		)
		(fill
			(thermal_gap 0.5)
			(thermal_bridge_width 0.5)
			(island_removal_mode 0)
		)
		(polygon
			(pts
				(arc
					(start 101.083364 -289.807142)
					(mid 101.741224 -289.807142)
					(end 101.083364 -289.807142)
				)
			)
		)
	)
	(zone
		(layers "F.Cu" "B.Cu" "In1.Cu" "In2.Cu" "In3.Cu" "In4.Cu" "In5.Cu" "In6.Cu"
			"In7.Cu" "In8.Cu" "In9.Cu" "In10.Cu" "In11.Cu" "In12.Cu" "In13.Cu" "In14.Cu"
			"In15.Cu" "In16.Cu"
		)
		(hatch none 0.5)
		(connect_pads
			(clearance 0)
		)
		(min_thickness 0.25)
		(keepout
			(tracks not_allowed)
			(vias allowed)
			(pads allowed)
			(copperpour not_allowed)
			(footprints allowed)
		)
		(placement
			(enabled no)
			(sheetname "")
		)
		(fill
			(thermal_gap 0.5)
			(thermal_bridge_width 0.5)
			(island_removal_mode 0)
		)
		(polygon
			(pts
				(arc
					(start 364.920022 -216.966292)
					(mid 364.848033 -216.894133)
					(end 364.749588 -216.86774)
				)
				(arc
					(start 364.749588 -216.86774)
					(mid 364.610394 -216.925396)
					(end 364.552738 -217.06459)
				)
				(arc
					(start 364.552738 -217.06459)
					(mid 364.559495 -217.115471)
					(end 364.579154 -217.162888)
				)
				(arc
					(start 365.0488 -217.976704)
					(mid 365.120789 -218.048863)
					(end 365.219234 -218.075256)
				)
				(arc
					(start 365.219234 -218.075256)
					(mid 365.358428 -218.0176)
					(end 365.416084 -217.878406)
				)
				(arc
					(start 365.416084 -217.878406)
					(mid 365.409327 -217.827525)
					(end 365.389668 -217.780108)
				)
			)
		)
	)
	(zone
		(layers "F.Cu" "B.Cu" "In1.Cu" "In2.Cu" "In3.Cu" "In4.Cu" "In5.Cu" "In6.Cu"
			"In7.Cu" "In8.Cu" "In9.Cu" "In10.Cu" "In11.Cu" "In12.Cu" "In13.Cu" "In14.Cu"
			"In15.Cu" "In16.Cu"
		)
		(hatch none 0.5)
		(connect_pads
			(clearance 0)
		)
		(min_thickness 0.25)
		(keepout
			(tracks not_allowed)
			(vias allowed)
			(pads allowed)
			(copperpour not_allowed)
			(footprints allowed)
		)
		(placement
			(enabled no)
			(sheetname "")
		)
		(fill
			(thermal_gap 0.5)
			(thermal_bridge_width 0.5)
			(island_removal_mode 0)
		)
		(polygon
			(pts
				(arc
					(start 105.702354 -220.22181)
					(mid 105.630365 -220.149651)
					(end 105.53192 -220.123258)
				)
				(arc
					(start 105.53192 -220.123258)
					(mid 105.392726 -220.180914)
					(end 105.33507 -220.320108)
				)
				(arc
					(start 105.33507 -220.320108)
					(mid 105.341827 -220.370989)
					(end 105.361486 -220.418406)
				)
				(arc
					(start 105.831132 -221.232222)
					(mid 105.903121 -221.304381)
					(end 106.001566 -221.330774)
				)
				(arc
					(start 106.001566 -221.330774)
					(mid 106.14076 -221.273118)
					(end 106.198416 -221.133924)
				)
				(arc
					(start 106.198416 -221.133924)
					(mid 106.191659 -221.083043)
					(end 106.172 -221.035626)
				)
			)
		)
	)
	(zone
		(layers "F.Cu" "B.Cu" "In1.Cu" "In2.Cu" "In3.Cu" "In4.Cu" "In5.Cu" "In6.Cu"
			"In7.Cu" "In8.Cu" "In9.Cu" "In10.Cu" "In11.Cu" "In12.Cu" "In13.Cu" "In14.Cu"
			"In15.Cu" "In16.Cu"
		)
		(hatch none 0.5)
		(connect_pads
			(clearance 0)
		)
		(min_thickness 0.25)
		(keepout
			(tracks not_allowed)
			(vias allowed)
			(pads allowed)
			(copperpour not_allowed)
			(footprints allowed)
		)
		(placement
			(enabled no)
			(sheetname "")
		)
		(fill
			(thermal_gap 0.5)
			(thermal_bridge_width 0.5)
			(island_removal_mode 0)
		)
		(polygon
			(pts
				(arc
					(start 337.354164 -221.133924)
					(mid 336.696304 -221.133924)
					(end 337.354164 -221.133924)
				)
			)
		)
	)
	(zone
		(layers "F.Cu" "B.Cu" "In1.Cu" "In2.Cu" "In3.Cu" "In4.Cu" "In5.Cu" "In6.Cu"
			"In7.Cu" "In8.Cu" "In9.Cu" "In10.Cu" "In11.Cu" "In12.Cu" "In13.Cu" "In14.Cu"
			"In15.Cu" "In16.Cu"
		)
		(hatch none 0.5)
		(connect_pads
			(clearance 0)
		)
		(min_thickness 0.25)
		(keepout
			(tracks not_allowed)
			(vias allowed)
			(pads allowed)
			(copperpour not_allowed)
			(footprints allowed)
		)
		(placement
			(enabled no)
			(sheetname "")
		)
		(fill
			(thermal_gap 0.5)
			(thermal_bridge_width 0.5)
			(island_removal_mode 0)
		)
		(polygon
			(pts
				(arc
					(start 139.880594 -406.62352)
					(mid 139.499594 -407.00452)
					(end 139.880594 -407.38552)
				)
				(arc
					(start 140.744194 -407.38552)
					(mid 141.125194 -407.00452)
					(end 140.744194 -406.62352)
				)
			)
		)
	)
	(zone
		(layers "F.Cu" "B.Cu" "In1.Cu" "In2.Cu" "In3.Cu" "In4.Cu" "In5.Cu" "In6.Cu"
			"In7.Cu" "In8.Cu" "In9.Cu" "In10.Cu" "In11.Cu" "In12.Cu" "In13.Cu" "In14.Cu"
			"In15.Cu" "In16.Cu"
		)
		(hatch none 0.5)
		(connect_pads
			(clearance 0)
		)
		(min_thickness 0.25)
		(keepout
			(tracks not_allowed)
			(vias allowed)
			(pads allowed)
			(copperpour not_allowed)
			(footprints allowed)
		)
		(placement
			(enabled no)
			(sheetname "")
		)
		(fill
			(thermal_gap 0.5)
			(thermal_bridge_width 0.5)
			(island_removal_mode 0)
		)
		(polygon
			(pts
				(arc
					(start 55.452518 -409.649168)
					(mid 55.071518 -410.030168)
					(end 55.452518 -410.411168)
				)
				(arc
					(start 56.316118 -410.411168)
					(mid 56.697118 -410.030168)
					(end 56.316118 -409.649168)
				)
			)
		)
	)
	(zone
		(layers "F.Cu" "B.Cu" "In1.Cu" "In2.Cu" "In3.Cu" "In4.Cu" "In5.Cu" "In6.Cu"
			"In7.Cu" "In8.Cu" "In9.Cu" "In10.Cu" "In11.Cu" "In12.Cu" "In13.Cu" "In14.Cu"
			"In15.Cu" "In16.Cu"
		)
		(hatch none 0.5)
		(connect_pads
			(clearance 0)
		)
		(min_thickness 0.25)
		(keepout
			(tracks not_allowed)
			(vias allowed)
			(pads allowed)
			(copperpour not_allowed)
			(footprints allowed)
		)
		(placement
			(enabled no)
			(sheetname "")
		)
		(fill
			(thermal_gap 0.5)
			(thermal_bridge_width 0.5)
			(island_removal_mode 0)
		)
		(polygon
			(pts
				(arc
					(start 102.101396 -213.732618)
					(mid 101.443536 -213.732618)
					(end 102.101396 -213.732618)
				)
			)
		)
	)
	(zone
		(layers "F.Cu" "B.Cu" "In1.Cu" "In2.Cu" "In3.Cu" "In4.Cu" "In5.Cu" "In6.Cu"
			"In7.Cu" "In8.Cu" "In9.Cu" "In10.Cu" "In11.Cu" "In12.Cu" "In13.Cu" "In14.Cu"
			"In15.Cu" "In16.Cu"
		)
		(hatch none 0.5)
		(connect_pads
			(clearance 0)
		)
		(min_thickness 0.25)
		(keepout
			(tracks not_allowed)
			(vias allowed)
			(pads allowed)
			(copperpour not_allowed)
			(footprints allowed)
		)
		(placement
			(enabled no)
			(sheetname "")
		)
		(fill
			(thermal_gap 0.5)
			(thermal_bridge_width 0.5)
			(island_removal_mode 0)
		)
		(polygon
			(pts
				(arc
					(start 355.789992 -275.8948)
					(mid 355.132132 -275.8948)
					(end 355.789992 -275.8948)
				)
			)
		)
	)
	(zone
		(layers "F.Cu" "B.Cu" "In1.Cu" "In2.Cu" "In3.Cu" "In4.Cu" "In5.Cu" "In6.Cu"
			"In7.Cu" "In8.Cu" "In9.Cu" "In10.Cu" "In11.Cu" "In12.Cu" "In13.Cu" "In14.Cu"
			"In15.Cu" "In16.Cu"
		)
		(hatch none 0.5)
		(connect_pads
			(clearance 0)
		)
		(min_thickness 0.25)
		(keepout
			(tracks not_allowed)
			(vias allowed)
			(pads allowed)
			(copperpour not_allowed)
			(footprints allowed)
		)
		(placement
			(enabled no)
			(sheetname "")
		)
		(fill
			(thermal_gap 0.5)
			(thermal_bridge_width 0.5)
			(island_removal_mode 0)
		)
		(polygon
			(pts
				(arc
					(start 352.390456 -214.622634)
					(mid 351.732596 -214.622634)
					(end 352.390456 -214.622634)
				)
			)
		)
	)
	(zone
		(layers "F.Cu" "B.Cu" "In1.Cu" "In2.Cu" "In3.Cu" "In4.Cu" "In5.Cu" "In6.Cu"
			"In7.Cu" "In8.Cu" "In9.Cu" "In10.Cu" "In11.Cu" "In12.Cu" "In13.Cu" "In14.Cu"
			"In15.Cu" "In16.Cu"
		)
		(hatch none 0.5)
		(connect_pads
			(clearance 0)
		)
		(min_thickness 0.25)
		(keepout
			(tracks not_allowed)
			(vias allowed)
			(pads allowed)
			(copperpour not_allowed)
			(footprints allowed)
		)
		(placement
			(enabled no)
			(sheetname "")
		)
		(fill
			(thermal_gap 0.5)
			(thermal_bridge_width 0.5)
			(island_removal_mode 0)
		)
		(polygon
			(pts
				(arc
					(start 344.714068 -221.035626)
					(mid 344.642079 -220.963467)
					(end 344.543634 -220.937074)
				)
				(arc
					(start 344.543634 -220.937074)
					(mid 344.40444 -220.99473)
					(end 344.346784 -221.133924)
				)
				(arc
					(start 344.346784 -221.133924)
					(mid 344.353541 -221.184805)
					(end 344.3732 -221.232222)
				)
				(arc
					(start 344.842846 -222.046038)
					(mid 344.914835 -222.118197)
					(end 345.01328 -222.14459)
				)
				(arc
					(start 345.01328 -222.14459)
					(mid 345.152474 -222.086934)
					(end 345.21013 -221.94774)
				)
				(arc
					(start 345.21013 -221.94774)
					(mid 345.203373 -221.896859)
					(end 345.183714 -221.849442)
				)
			)
		)
	)
	(zone
		(layers "F.Cu" "B.Cu" "In1.Cu" "In2.Cu" "In3.Cu" "In4.Cu" "In5.Cu" "In6.Cu"
			"In7.Cu" "In8.Cu" "In9.Cu" "In10.Cu" "In11.Cu" "In12.Cu" "In13.Cu" "In14.Cu"
			"In15.Cu" "In16.Cu"
		)
		(hatch none 0.5)
		(connect_pads
			(clearance 0)
		)
		(min_thickness 0.25)
		(keepout
			(tracks not_allowed)
			(vias allowed)
			(pads allowed)
			(copperpour not_allowed)
			(footprints allowed)
		)
		(placement
			(enabled no)
			(sheetname "")
		)
		(fill
			(thermal_gap 0.5)
			(thermal_bridge_width 0.5)
			(island_removal_mode 0)
		)
		(polygon
			(pts
				(arc
					(start 370.558314 -223.67367)
					(mid 370.577998 -223.62626)
					(end 370.58473 -223.575372)
				)
				(arc
					(start 370.58473 -223.575372)
					(mid 370.527074 -223.436178)
					(end 370.38788 -223.378522)
				)
				(arc
					(start 370.38788 -223.378522)
					(mid 370.289449 -223.404938)
					(end 370.217446 -223.477074)
				)
				(arc
					(start 369.7478 -224.291144)
					(mid 369.728116 -224.338554)
					(end 369.721384 -224.389442)
				)
				(arc
					(start 369.721384 -224.389442)
					(mid 369.77904 -224.528636)
					(end 369.918234 -224.586292)
				)
				(arc
					(start 369.918234 -224.586292)
					(mid 370.016665 -224.559876)
					(end 370.088668 -224.48774)
				)
			)
		)
	)
	(zone
		(layers "F.Cu" "B.Cu" "In1.Cu" "In2.Cu" "In3.Cu" "In4.Cu" "In5.Cu" "In6.Cu"
			"In7.Cu" "In8.Cu" "In9.Cu" "In10.Cu" "In11.Cu" "In12.Cu" "In13.Cu" "In14.Cu"
			"In15.Cu" "In16.Cu"
		)
		(hatch none 0.5)
		(connect_pads
			(clearance 0)
		)
		(min_thickness 0.25)
		(keepout
			(tracks not_allowed)
			(vias allowed)
			(pads allowed)
			(copperpour not_allowed)
			(footprints allowed)
		)
		(placement
			(enabled no)
			(sheetname "")
		)
		(fill
			(thermal_gap 0.5)
			(thermal_bridge_width 0.5)
			(island_removal_mode 0)
		)
		(polygon
			(pts
				(arc
					(start 340.723474 -82.345022)
					(mid 341.104474 -81.964022)
					(end 340.723474 -81.583022)
				)
				(arc
					(start 339.859874 -81.583022)
					(mid 339.478874 -81.964022)
					(end 339.859874 -82.345022)
				)
			)
		)
	)
	(zone
		(layers "F.Cu" "B.Cu" "In1.Cu" "In2.Cu" "In3.Cu" "In4.Cu" "In5.Cu" "In6.Cu"
			"In7.Cu" "In8.Cu" "In9.Cu" "In10.Cu" "In11.Cu" "In12.Cu" "In13.Cu" "In14.Cu"
			"In15.Cu" "In16.Cu"
		)
		(hatch none 0.5)
		(connect_pads
			(clearance 0)
		)
		(min_thickness 0.25)
		(keepout
			(tracks not_allowed)
			(vias allowed)
			(pads allowed)
			(copperpour not_allowed)
			(footprints allowed)
		)
		(placement
			(enabled no)
			(sheetname "")
		)
		(fill
			(thermal_gap 0.5)
			(thermal_bridge_width 0.5)
			(island_removal_mode 0)
		)
		(polygon
			(pts
				(arc
					(start 183.271414 5.0292)
					(mid 183.652414 4.6482)
					(end 184.033414 5.0292)
				)
				(arc
					(start 184.033414 5.8928)
					(mid 183.652414 6.2738)
					(end 183.271414 5.8928)
				)
			)
		)
	)
	(zone
		(layers "F.Cu" "B.Cu" "In1.Cu" "In2.Cu" "In3.Cu" "In4.Cu" "In5.Cu" "In6.Cu"
			"In7.Cu" "In8.Cu" "In9.Cu" "In10.Cu" "In11.Cu" "In12.Cu" "In13.Cu" "In14.Cu"
			"In15.Cu" "In16.Cu"
		)
		(hatch none 0.5)
		(connect_pads
			(clearance 0)
		)
		(min_thickness 0.25)
		(keepout
			(tracks not_allowed)
			(vias allowed)
			(pads allowed)
			(copperpour not_allowed)
			(footprints allowed)
		)
		(placement
			(enabled no)
			(sheetname "")
		)
		(fill
			(thermal_gap 0.5)
			(thermal_bridge_width 0.5)
			(island_removal_mode 0)
		)
		(polygon
			(pts
				(arc
					(start 70.1421 -424.360594)
					(mid 70.164418 -424.414476)
					(end 70.2183 -424.436794)
				)
				(arc
					(start 71.1581 -424.436794)
					(mid 71.211982 -424.414476)
					(end 71.2343 -424.360594)
				)
				(arc
					(start 71.2343 -421.81907)
					(mid 71.211982 -421.765188)
					(end 71.1581 -421.74287)
				)
				(arc
					(start 70.2183 -421.74287)
					(mid 70.164418 -421.765188)
					(end 70.1421 -421.81907)
				)
			)
		)
	)
	(zone
		(layers "F.Cu" "B.Cu" "In1.Cu" "In2.Cu" "In3.Cu" "In4.Cu" "In5.Cu" "In6.Cu"
			"In7.Cu" "In8.Cu" "In9.Cu" "In10.Cu" "In11.Cu" "In12.Cu" "In13.Cu" "In14.Cu"
			"In15.Cu" "In16.Cu"
		)
		(hatch none 0.5)
		(connect_pads
			(clearance 0)
		)
		(min_thickness 0.25)
		(keepout
			(tracks not_allowed)
			(vias allowed)
			(pads allowed)
			(copperpour not_allowed)
			(footprints allowed)
		)
		(placement
			(enabled no)
			(sheetname "")
		)
		(fill
			(thermal_gap 0.5)
			(thermal_bridge_width 0.5)
			(island_removal_mode 0)
		)
		(polygon
			(pts
				(arc
					(start 219.18422 -17.417288)
					(mid 218.80322 -17.798288)
					(end 219.18422 -18.179288)
				)
				(arc
					(start 220.04782 -18.179288)
					(mid 220.42882 -17.798288)
					(end 220.04782 -17.417288)
				)
			)
		)
	)
	(zone
		(layers "F.Cu" "B.Cu" "In1.Cu" "In2.Cu" "In3.Cu" "In4.Cu" "In5.Cu" "In6.Cu"
			"In7.Cu" "In8.Cu" "In9.Cu" "In10.Cu" "In11.Cu" "In12.Cu" "In13.Cu" "In14.Cu"
			"In15.Cu" "In16.Cu"
		)
		(hatch none 0.5)
		(connect_pads
			(clearance 0)
		)
		(min_thickness 0.25)
		(keepout
			(tracks not_allowed)
			(vias allowed)
			(pads allowed)
			(copperpour not_allowed)
			(footprints allowed)
		)
		(placement
			(enabled no)
			(sheetname "")
		)
		(fill
			(thermal_gap 0.5)
			(thermal_bridge_width 0.5)
			(island_removal_mode 0)
		)
		(polygon
			(pts
				(arc
					(start 342.162892 -281.59202)
					(mid 341.505032 -281.59202)
					(end 342.162892 -281.59202)
				)
			)
		)
	)
	(zone
		(layers "F.Cu" "B.Cu" "In1.Cu" "In2.Cu" "In3.Cu" "In4.Cu" "In5.Cu" "In6.Cu"
			"In7.Cu" "In8.Cu" "In9.Cu" "In10.Cu" "In11.Cu" "In12.Cu" "In13.Cu" "In14.Cu"
			"In15.Cu" "In16.Cu"
		)
		(hatch none 0.5)
		(connect_pads
			(clearance 0)
		)
		(min_thickness 0.25)
		(keepout
			(tracks not_allowed)
			(vias allowed)
			(pads allowed)
			(copperpour not_allowed)
			(footprints allowed)
		)
		(placement
			(enabled no)
			(sheetname "")
		)
		(fill
			(thermal_gap 0.5)
			(thermal_bridge_width 0.5)
			(island_removal_mode 0)
		)
		(polygon
			(pts
				(arc
					(start 358.969056 -214.622634)
					(mid 358.311196 -214.622634)
					(end 358.969056 -214.622634)
				)
			)
		)
	)
	(zone
		(layers "F.Cu" "B.Cu" "In1.Cu" "In2.Cu" "In3.Cu" "In4.Cu" "In5.Cu" "In6.Cu"
			"In7.Cu" "In8.Cu" "In9.Cu" "In10.Cu" "In11.Cu" "In12.Cu" "In13.Cu" "In14.Cu"
			"In15.Cu" "In16.Cu"
		)
		(hatch none 0.5)
		(connect_pads
			(clearance 0)
		)
		(min_thickness 0.25)
		(keepout
			(tracks not_allowed)
			(vias allowed)
			(pads allowed)
			(copperpour not_allowed)
			(footprints allowed)
		)
		(placement
			(enabled no)
			(sheetname "")
		)
		(fill
			(thermal_gap 0.5)
			(thermal_bridge_width 0.5)
			(island_removal_mode 0)
		)
		(polygon
			(pts
				(arc
					(start 342.992964 -217.878406)
					(mid 342.335104 -217.878406)
					(end 342.992964 -217.878406)
				)
			)
		)
	)
	(zone
		(layers "F.Cu" "B.Cu" "In1.Cu" "In2.Cu" "In3.Cu" "In4.Cu" "In5.Cu" "In6.Cu"
			"In7.Cu" "In8.Cu" "In9.Cu" "In10.Cu" "In11.Cu" "In12.Cu" "In13.Cu" "In14.Cu"
			"In15.Cu" "In16.Cu"
		)
		(hatch none 0.5)
		(connect_pads
			(clearance 0)
		)
		(min_thickness 0.25)
		(keepout
			(tracks not_allowed)
			(vias allowed)
			(pads allowed)
			(copperpour not_allowed)
			(footprints allowed)
		)
		(placement
			(enabled no)
			(sheetname "")
		)
		(fill
			(thermal_gap 0.5)
			(thermal_bridge_width 0.5)
			(island_removal_mode 0)
		)
		(polygon
			(pts
				(arc
					(start 373.84736 -217.97645)
					(mid 373.867044 -217.92904)
					(end 373.873776 -217.878152)
				)
				(arc
					(start 373.873776 -217.878152)
					(mid 373.81612 -217.738958)
					(end 373.676926 -217.681302)
				)
				(arc
					(start 373.676926 -217.681302)
					(mid 373.578495 -217.707718)
					(end 373.506492 -217.779854)
				)
				(arc
					(start 373.036846 -218.593924)
					(mid 373.017162 -218.641334)
					(end 373.01043 -218.692222)
				)
				(arc
					(start 373.01043 -218.692222)
					(mid 373.068086 -218.831416)
					(end 373.20728 -218.889072)
				)
				(arc
					(start 373.20728 -218.889072)
					(mid 373.305711 -218.862656)
					(end 373.377714 -218.79052)
				)
			)
		)
	)
	(zone
		(layers "F.Cu" "B.Cu" "In1.Cu" "In2.Cu" "In3.Cu" "In4.Cu" "In5.Cu" "In6.Cu"
			"In7.Cu" "In8.Cu" "In9.Cu" "In10.Cu" "In11.Cu" "In12.Cu" "In13.Cu" "In14.Cu"
			"In15.Cu" "In16.Cu"
		)
		(hatch none 0.5)
		(connect_pads
			(clearance 0)
		)
		(min_thickness 0.25)
		(keepout
			(tracks not_allowed)
			(vias allowed)
			(pads allowed)
			(copperpour not_allowed)
			(footprints allowed)
		)
		(placement
			(enabled no)
			(sheetname "")
		)
		(fill
			(thermal_gap 0.5)
			(thermal_bridge_width 0.5)
			(island_removal_mode 0)
		)
		(polygon
			(pts
				(arc
					(start 66.359278 -400.477228)
					(mid 65.978278 -400.858228)
					(end 66.359278 -401.239228)
				)
				(arc
					(start 67.222878 -401.239228)
					(mid 67.603878 -400.858228)
					(end 67.222878 -400.477228)
				)
			)
		)
	)
	(zone
		(layers "F.Cu" "B.Cu" "In1.Cu" "In2.Cu" "In3.Cu" "In4.Cu" "In5.Cu" "In6.Cu"
			"In7.Cu" "In8.Cu" "In9.Cu" "In10.Cu" "In11.Cu" "In12.Cu" "In13.Cu" "In14.Cu"
			"In15.Cu" "In16.Cu"
		)
		(hatch none 0.5)
		(connect_pads
			(clearance 0)
		)
		(min_thickness 0.25)
		(keepout
			(tracks not_allowed)
			(vias allowed)
			(pads allowed)
			(copperpour not_allowed)
			(footprints allowed)
		)
		(placement
			(enabled no)
			(sheetname "")
		)
		(fill
			(thermal_gap 0.5)
			(thermal_bridge_width 0.5)
			(island_removal_mode 0)
		)
		(polygon
			(pts
				(arc
					(start 417.37153 -403.502876)
					(mid 416.99053 -403.883876)
					(end 417.37153 -404.264876)
				)
				(arc
					(start 418.23513 -404.264876)
					(mid 418.61613 -403.883876)
					(end 418.23513 -403.502876)
				)
			)
		)
	)
	(zone
		(layers "F.Cu" "B.Cu" "In1.Cu" "In2.Cu" "In3.Cu" "In4.Cu" "In5.Cu" "In6.Cu"
			"In7.Cu" "In8.Cu" "In9.Cu" "In10.Cu" "In11.Cu" "In12.Cu" "In13.Cu" "In14.Cu"
			"In15.Cu" "In16.Cu"
		)
		(hatch none 0.5)
		(connect_pads
			(clearance 0)
		)
		(min_thickness 0.25)
		(keepout
			(tracks not_allowed)
			(vias allowed)
			(pads allowed)
			(copperpour not_allowed)
			(footprints allowed)
		)
		(placement
			(enabled no)
			(sheetname "")
		)
		(fill
			(thermal_gap 0.5)
			(thermal_bridge_width 0.5)
			(island_removal_mode 0)
		)
		(polygon
			(pts
				(arc
					(start 57.78373 -18.75536)
					(mid 57.40273 -19.13636)
					(end 57.78373 -19.51736)
				)
				(arc
					(start 58.64733 -19.51736)
					(mid 59.02833 -19.13636)
					(end 58.64733 -18.75536)
				)
			)
		)
	)
	(zone
		(layers "F.Cu" "B.Cu" "In1.Cu" "In2.Cu" "In3.Cu" "In4.Cu" "In5.Cu" "In6.Cu"
			"In7.Cu" "In8.Cu" "In9.Cu" "In10.Cu" "In11.Cu" "In12.Cu" "In13.Cu" "In14.Cu"
			"In15.Cu" "In16.Cu"
		)
		(hatch none 0.5)
		(connect_pads
			(clearance 0)
		)
		(min_thickness 0.25)
		(keepout
			(tracks not_allowed)
			(vias allowed)
			(pads allowed)
			(copperpour not_allowed)
			(footprints allowed)
		)
		(placement
			(enabled no)
			(sheetname "")
		)
		(fill
			(thermal_gap 0.5)
			(thermal_bridge_width 0.5)
			(island_removal_mode 0)
		)
		(polygon
			(pts
				(arc
					(start 132.644896 -221.133924)
					(mid 131.987036 -221.133924)
					(end 132.644896 -221.133924)
				)
			)
		)
	)
	(zone
		(layers "F.Cu" "B.Cu" "In1.Cu" "In2.Cu" "In3.Cu" "In4.Cu" "In5.Cu" "In6.Cu"
			"In7.Cu" "In8.Cu" "In9.Cu" "In10.Cu" "In11.Cu" "In12.Cu" "In13.Cu" "In14.Cu"
			"In15.Cu" "In16.Cu"
		)
		(hatch none 0.5)
		(connect_pads
			(clearance 0)
		)
		(min_thickness 0.25)
		(keepout
			(tracks not_allowed)
			(vias allowed)
			(pads allowed)
			(copperpour not_allowed)
			(footprints allowed)
		)
		(placement
			(enabled no)
			(sheetname "")
		)
		(fill
			(thermal_gap 0.5)
			(thermal_bridge_width 0.5)
			(island_removal_mode 0)
		)
		(polygon
			(pts
				(arc
					(start 103.510588 -214.622634)
					(mid 102.852728 -214.622634)
					(end 103.510588 -214.622634)
				)
			)
		)
	)
	(zone
		(layers "F.Cu" "B.Cu" "In1.Cu" "In2.Cu" "In3.Cu" "In4.Cu" "In5.Cu" "In6.Cu"
			"In7.Cu" "In8.Cu" "In9.Cu" "In10.Cu" "In11.Cu" "In12.Cu" "In13.Cu" "In14.Cu"
			"In15.Cu" "In16.Cu"
		)
		(hatch none 0.5)
		(connect_pads
			(clearance 0)
		)
		(min_thickness 0.25)
		(keepout
			(tracks not_allowed)
			(vias allowed)
			(pads allowed)
			(copperpour not_allowed)
			(footprints allowed)
		)
		(placement
			(enabled no)
			(sheetname "")
		)
		(fill
			(thermal_gap 0.5)
			(thermal_bridge_width 0.5)
			(island_removal_mode 0)
		)
		(polygon
			(pts
				(arc
					(start 345.892628 -285.563056)
					(mid 345.872944 -285.610466)
					(end 345.866212 -285.661354)
				)
				(arc
					(start 345.866212 -285.661354)
					(mid 345.923868 -285.800548)
					(end 346.063062 -285.858204)
				)
				(arc
					(start 346.063062 -285.858204)
					(mid 346.161493 -285.831788)
					(end 346.233496 -285.759652)
				)
				(arc
					(start 346.703396 -284.945582)
					(mid 346.72308 -284.898172)
					(end 346.729812 -284.847284)
				)
				(arc
					(start 346.729812 -284.847284)
					(mid 346.672156 -284.70809)
					(end 346.532962 -284.650434)
				)
				(arc
					(start 346.532962 -284.650434)
					(mid 346.434531 -284.67685)
					(end 346.362528 -284.748986)
				)
			)
		)
	)
	(zone
		(layers "F.Cu" "B.Cu" "In1.Cu" "In2.Cu" "In3.Cu" "In4.Cu" "In5.Cu" "In6.Cu"
			"In7.Cu" "In8.Cu" "In9.Cu" "In10.Cu" "In11.Cu" "In12.Cu" "In13.Cu" "In14.Cu"
			"In15.Cu" "In16.Cu"
		)
		(hatch none 0.5)
		(connect_pads
			(clearance 0)
		)
		(min_thickness 0.25)
		(keepout
			(tracks not_allowed)
			(vias allowed)
			(pads allowed)
			(copperpour not_allowed)
			(footprints allowed)
		)
		(placement
			(enabled no)
			(sheetname "")
		)
		(fill
			(thermal_gap 0.5)
			(thermal_bridge_width 0.5)
			(island_removal_mode 0)
		)
		(polygon
			(pts
				(arc
					(start 117.608096 -221.133924)
					(mid 116.950236 -221.133924)
					(end 117.608096 -221.133924)
				)
			)
		)
	)
	(zone
		(layers "F.Cu" "B.Cu" "In1.Cu" "In2.Cu" "In3.Cu" "In4.Cu" "In5.Cu" "In6.Cu"
			"In7.Cu" "In8.Cu" "In9.Cu" "In10.Cu" "In11.Cu" "In12.Cu" "In13.Cu" "In14.Cu"
			"In15.Cu" "In16.Cu"
		)
		(hatch none 0.5)
		(connect_pads
			(clearance 0)
		)
		(min_thickness 0.25)
		(keepout
			(tracks not_allowed)
			(vias allowed)
			(pads allowed)
			(copperpour not_allowed)
			(footprints allowed)
		)
		(placement
			(enabled no)
			(sheetname "")
		)
		(fill
			(thermal_gap 0.5)
			(thermal_bridge_width 0.5)
			(island_removal_mode 0)
		)
		(polygon
			(pts
				(arc
					(start 355.210364 -221.133924)
					(mid 354.552504 -221.133924)
					(end 355.210364 -221.133924)
				)
			)
		)
	)
	(zone
		(layers "F.Cu" "B.Cu" "In1.Cu" "In2.Cu" "In3.Cu" "In4.Cu" "In5.Cu" "In6.Cu"
			"In7.Cu" "In8.Cu" "In9.Cu" "In10.Cu" "In11.Cu" "In12.Cu" "In13.Cu" "In14.Cu"
			"In15.Cu" "In16.Cu"
		)
		(hatch none 0.5)
		(connect_pads
			(clearance 0)
		)
		(min_thickness 0.25)
		(keepout
			(tracks not_allowed)
			(vias allowed)
			(pads allowed)
			(copperpour not_allowed)
			(footprints allowed)
		)
		(placement
			(enabled no)
			(sheetname "")
		)
		(fill
			(thermal_gap 0.5)
			(thermal_bridge_width 0.5)
			(island_removal_mode 0)
		)
		(polygon
			(pts
				(arc
					(start 240.165128 -110.294674)
					(mid 239.784128 -109.913674)
					(end 239.403128 -110.294674)
				)
				(arc
					(start 239.403128 -111.158274)
					(mid 239.784128 -111.539274)
					(end 240.165128 -111.158274)
				)
			)
		)
	)
	(zone
		(layers "F.Cu" "B.Cu" "In1.Cu" "In2.Cu" "In3.Cu" "In4.Cu" "In5.Cu" "In6.Cu"
			"In7.Cu" "In8.Cu" "In9.Cu" "In10.Cu" "In11.Cu" "In12.Cu" "In13.Cu" "In14.Cu"
			"In15.Cu" "In16.Cu"
		)
		(hatch none 0.5)
		(connect_pads
			(clearance 0)
		)
		(min_thickness 0.25)
		(keepout
			(tracks not_allowed)
			(vias allowed)
			(pads allowed)
			(copperpour not_allowed)
			(footprints allowed)
		)
		(placement
			(enabled no)
			(sheetname "")
		)
		(fill
			(thermal_gap 0.5)
			(thermal_bridge_width 0.5)
			(island_removal_mode 0)
		)
		(polygon
			(pts
				(arc
					(start 369.307364 -224.389442)
					(mid 368.649504 -224.389442)
					(end 369.307364 -224.389442)
				)
			)
		)
	)
	(zone
		(layers "F.Cu" "B.Cu" "In1.Cu" "In2.Cu" "In3.Cu" "In4.Cu" "In5.Cu" "In6.Cu"
			"In7.Cu" "In8.Cu" "In9.Cu" "In10.Cu" "In11.Cu" "In12.Cu" "In13.Cu" "In14.Cu"
			"In15.Cu" "In16.Cu"
		)
		(hatch none 0.5)
		(connect_pads
			(clearance 0)
		)
		(min_thickness 0.25)
		(keepout
			(tracks not_allowed)
			(vias allowed)
			(pads allowed)
			(copperpour not_allowed)
			(footprints allowed)
		)
		(placement
			(enabled no)
			(sheetname "")
		)
		(fill
			(thermal_gap 0.5)
			(thermal_bridge_width 0.5)
			(island_removal_mode 0)
		)
		(polygon
			(pts
				(arc
					(start 112.909096 -221.133924)
					(mid 112.251236 -221.133924)
					(end 112.909096 -221.133924)
				)
			)
		)
	)
	(zone
		(layers "F.Cu" "B.Cu" "In1.Cu" "In2.Cu" "In3.Cu" "In4.Cu" "In5.Cu" "In6.Cu"
			"In7.Cu" "In8.Cu" "In9.Cu" "In10.Cu" "In11.Cu" "In12.Cu" "In13.Cu" "In14.Cu"
			"In15.Cu" "In16.Cu"
		)
		(hatch none 0.5)
		(connect_pads
			(clearance 0)
		)
		(min_thickness 0.25)
		(keepout
			(tracks not_allowed)
			(vias allowed)
			(pads allowed)
			(copperpour not_allowed)
			(footprints allowed)
		)
		(placement
			(enabled no)
			(sheetname "")
		)
		(fill
			(thermal_gap 0.5)
			(thermal_bridge_width 0.5)
			(island_removal_mode 0)
		)
		(polygon
			(pts
				(arc
					(start 383.67589 -400.477228)
					(mid 383.29489 -400.858228)
					(end 383.67589 -401.239228)
				)
				(arc
					(start 384.53949 -401.239228)
					(mid 384.92049 -400.858228)
					(end 384.53949 -400.477228)
				)
			)
		)
	)
	(zone
		(layers "F.Cu" "B.Cu" "In1.Cu" "In2.Cu" "In3.Cu" "In4.Cu" "In5.Cu" "In6.Cu"
			"In7.Cu" "In8.Cu" "In9.Cu" "In10.Cu" "In11.Cu" "In12.Cu" "In13.Cu" "In14.Cu"
			"In15.Cu" "In16.Cu"
		)
		(hatch none 0.5)
		(connect_pads
			(clearance 0)
		)
		(min_thickness 0.25)
		(keepout
			(tracks not_allowed)
			(vias allowed)
			(pads allowed)
			(copperpour not_allowed)
			(footprints allowed)
		)
		(placement
			(enabled no)
			(sheetname "")
		)
		(fill
			(thermal_gap 0.5)
			(thermal_bridge_width 0.5)
			(island_removal_mode 0)
		)
		(polygon
			(pts
				(arc
					(start 369.417346 -288.103056)
					(mid 368.759486 -288.103056)
					(end 369.417346 -288.103056)
				)
			)
		)
	)
	(zone
		(layers "F.Cu" "B.Cu" "In1.Cu" "In2.Cu" "In3.Cu" "In4.Cu" "In5.Cu" "In6.Cu"
			"In7.Cu" "In8.Cu" "In9.Cu" "In10.Cu" "In11.Cu" "In12.Cu" "In13.Cu" "In14.Cu"
			"In15.Cu" "In16.Cu"
		)
		(hatch none 0.5)
		(connect_pads
			(clearance 0)
		)
		(min_thickness 0.25)
		(keepout
			(tracks not_allowed)
			(vias allowed)
			(pads allowed)
			(copperpour not_allowed)
			(footprints allowed)
		)
		(placement
			(enabled no)
			(sheetname "")
		)
		(fill
			(thermal_gap 0.5)
			(thermal_bridge_width 0.5)
			(island_removal_mode 0)
		)
		(polygon
			(pts
				(arc
					(start 132.644388 -214.622634)
					(mid 131.986528 -214.622634)
					(end 132.644388 -214.622634)
				)
			)
		)
	)
	(zone
		(layers "F.Cu" "B.Cu" "In1.Cu" "In2.Cu" "In3.Cu" "In4.Cu" "In5.Cu" "In6.Cu"
			"In7.Cu" "In8.Cu" "In9.Cu" "In10.Cu" "In11.Cu" "In12.Cu" "In13.Cu" "In14.Cu"
			"In15.Cu" "In16.Cu"
		)
		(hatch none 0.5)
		(connect_pads
			(clearance 0)
		)
		(min_thickness 0.25)
		(keepout
			(tracks not_allowed)
			(vias allowed)
			(pads allowed)
			(copperpour not_allowed)
			(footprints allowed)
		)
		(placement
			(enabled no)
			(sheetname "")
		)
		(fill
			(thermal_gap 0.5)
			(thermal_bridge_width 0.5)
			(island_removal_mode 0)
		)
		(polygon
			(pts
				(arc
					(start 364.920022 -220.22181)
					(mid 364.848033 -220.149651)
					(end 364.749588 -220.123258)
				)
				(arc
					(start 364.749588 -220.123258)
					(mid 364.610394 -220.180914)
					(end 364.552738 -220.320108)
				)
				(arc
					(start 364.552738 -220.320108)
					(mid 364.559495 -220.370989)
					(end 364.579154 -220.418406)
				)
				(arc
					(start 365.0488 -221.232222)
					(mid 365.120789 -221.304381)
					(end 365.219234 -221.330774)
				)
				(arc
					(start 365.219234 -221.330774)
					(mid 365.358428 -221.273118)
					(end 365.416084 -221.133924)
				)
				(arc
					(start 365.416084 -221.133924)
					(mid 365.409327 -221.083043)
					(end 365.389668 -221.035626)
				)
			)
		)
	)
	(zone
		(layers "F.Cu" "B.Cu" "In1.Cu" "In2.Cu" "In3.Cu" "In4.Cu" "In5.Cu" "In6.Cu"
			"In7.Cu" "In8.Cu" "In9.Cu" "In10.Cu" "In11.Cu" "In12.Cu" "In13.Cu" "In14.Cu"
			"In15.Cu" "In16.Cu"
		)
		(hatch none 0.5)
		(connect_pads
			(clearance 0)
		)
		(min_thickness 0.25)
		(keepout
			(tracks not_allowed)
			(vias allowed)
			(pads allowed)
			(copperpour not_allowed)
			(footprints allowed)
		)
		(placement
			(enabled no)
			(sheetname "")
		)
		(fill
			(thermal_gap 0.5)
			(thermal_bridge_width 0.5)
			(island_removal_mode 0)
		)
		(polygon
			(pts
				(arc
					(start 91.403424 -284.847538)
					(mid 90.745564 -284.847538)
					(end 91.403424 -284.847538)
				)
			)
		)
	)
	(zone
		(layers "F.Cu" "B.Cu" "In1.Cu" "In2.Cu" "In3.Cu" "In4.Cu" "In5.Cu" "In6.Cu"
			"In7.Cu" "In8.Cu" "In9.Cu" "In10.Cu" "In11.Cu" "In12.Cu" "In13.Cu" "In14.Cu"
			"In15.Cu" "In16.Cu"
		)
		(hatch none 0.5)
		(connect_pads
			(clearance 0)
		)
		(min_thickness 0.25)
		(keepout
			(tracks not_allowed)
			(vias allowed)
			(pads allowed)
			(copperpour not_allowed)
			(footprints allowed)
		)
		(placement
			(enabled no)
			(sheetname "")
		)
		(fill
			(thermal_gap 0.5)
			(thermal_bridge_width 0.5)
			(island_removal_mode 0)
		)
		(polygon
			(pts
				(arc
					(start 345.452192 -285.661354)
					(mid 344.794332 -285.661354)
					(end 345.452192 -285.661354)
				)
			)
		)
	)
	(zone
		(layers "F.Cu" "B.Cu" "In1.Cu" "In2.Cu" "In3.Cu" "In4.Cu" "In5.Cu" "In6.Cu"
			"In7.Cu" "In8.Cu" "In9.Cu" "In10.Cu" "In11.Cu" "In12.Cu" "In13.Cu" "In14.Cu"
			"In15.Cu" "In16.Cu"
		)
		(hatch none 0.5)
		(connect_pads
			(clearance 0)
		)
		(min_thickness 0.25)
		(keepout
			(tracks not_allowed)
			(vias allowed)
			(pads allowed)
			(copperpour not_allowed)
			(footprints allowed)
		)
		(placement
			(enabled no)
			(sheetname "")
		)
		(fill
			(thermal_gap 0.5)
			(thermal_bridge_width 0.5)
			(island_removal_mode 0)
		)
		(polygon
			(pts
				(arc
					(start 161.323274 -409.649168)
					(mid 160.942274 -410.030168)
					(end 161.323274 -410.411168)
				)
				(arc
					(start 162.186874 -410.411168)
					(mid 162.567874 -410.030168)
					(end 162.186874 -409.649168)
				)
			)
		)
	)
	(zone
		(layers "F.Cu" "B.Cu" "In1.Cu" "In2.Cu" "In3.Cu" "In4.Cu" "In5.Cu" "In6.Cu"
			"In7.Cu" "In8.Cu" "In9.Cu" "In10.Cu" "In11.Cu" "In12.Cu" "In13.Cu" "In14.Cu"
			"In15.Cu" "In16.Cu"
		)
		(hatch none 0.5)
		(connect_pads
			(clearance 0)
		)
		(min_thickness 0.25)
		(keepout
			(tracks not_allowed)
			(vias allowed)
			(pads allowed)
			(copperpour not_allowed)
			(footprints allowed)
		)
		(placement
			(enabled no)
			(sheetname "")
		)
		(fill
			(thermal_gap 0.5)
			(thermal_bridge_width 0.5)
			(island_removal_mode 0)
		)
		(polygon
			(pts
				(arc
					(start 403.40153 -406.62352)
					(mid 403.02053 -407.00452)
					(end 403.40153 -407.38552)
				)
				(arc
					(start 404.26513 -407.38552)
					(mid 404.64613 -407.00452)
					(end 404.26513 -406.62352)
				)
			)
		)
	)
	(zone
		(layers "F.Cu" "B.Cu" "In1.Cu" "In2.Cu" "In3.Cu" "In4.Cu" "In5.Cu" "In6.Cu"
			"In7.Cu" "In8.Cu" "In9.Cu" "In10.Cu" "In11.Cu" "In12.Cu" "In13.Cu" "In14.Cu"
			"In15.Cu" "In16.Cu"
		)
		(hatch none 0.5)
		(connect_pads
			(clearance 0)
		)
		(min_thickness 0.25)
		(keepout
			(tracks not_allowed)
			(vias allowed)
			(pads allowed)
			(copperpour not_allowed)
			(footprints allowed)
		)
		(placement
			(enabled no)
			(sheetname "")
		)
		(fill
			(thermal_gap 0.5)
			(thermal_bridge_width 0.5)
			(island_removal_mode 0)
		)
		(polygon
			(pts
				(arc
					(start 101.105462 -288.831274)
					(mid 101.037754 -288.759423)
					(end 100.942648 -288.732976)
				)
				(arc
					(start 100.942648 -288.732976)
					(mid 100.812434 -288.786912)
					(end 100.758498 -288.917126)
				)
				(arc
					(start 100.758498 -288.917126)
					(mid 100.763949 -288.961347)
					(end 100.779834 -289.002978)
				)
				(arc
					(start 101.24948 -289.892994)
					(mid 101.317188 -289.964845)
					(end 101.412294 -289.991292)
				)
				(arc
					(start 101.412294 -289.991292)
					(mid 101.542508 -289.937356)
					(end 101.596444 -289.807142)
				)
				(arc
					(start 101.596444 -289.807142)
					(mid 101.590993 -289.762921)
					(end 101.575108 -289.72129)
				)
			)
		)
	)
	(zone
		(layers "F.Cu" "B.Cu" "In1.Cu" "In2.Cu" "In3.Cu" "In4.Cu" "In5.Cu" "In6.Cu"
			"In7.Cu" "In8.Cu" "In9.Cu" "In10.Cu" "In11.Cu" "In12.Cu" "In13.Cu" "In14.Cu"
			"In15.Cu" "In16.Cu"
		)
		(hatch none 0.5)
		(connect_pads
			(clearance 0)
		)
		(min_thickness 0.25)
		(keepout
			(tracks not_allowed)
			(vias allowed)
			(pads allowed)
			(copperpour not_allowed)
			(footprints allowed)
		)
		(placement
			(enabled no)
			(sheetname "")
		)
		(fill
			(thermal_gap 0.5)
			(thermal_bridge_width 0.5)
			(island_removal_mode 0)
		)
		(polygon
			(pts
				(arc
					(start 348.657672 -167.565832)
					(mid 348.806462 -167.925042)
					(end 349.165672 -168.073832)
				)
				(arc
					(start 349.16618 -168.073832)
					(mid 349.297389 -168.056595)
					(end 349.419672 -168.006014)
				)
				(arc
					(start 350.343724 -167.47236)
					(mid 350.529657 -167.286424)
					(end 350.597724 -167.032432)
				)
				(arc
					(start 350.597724 -167.032432)
					(mid 350.448934 -166.673222)
					(end 350.089724 -166.524432)
				)
				(arc
					(start 350.089216 -166.524432)
					(mid 349.958007 -166.541669)
					(end 349.835724 -166.59225)
				)
				(arc
					(start 348.911672 -167.125904)
					(mid 348.725739 -167.31184)
					(end 348.657672 -167.565832)
				)
			)
		)
	)
	(zone
		(layers "F.Cu" "B.Cu" "In1.Cu" "In2.Cu" "In3.Cu" "In4.Cu" "In5.Cu" "In6.Cu"
			"In7.Cu" "In8.Cu" "In9.Cu" "In10.Cu" "In11.Cu" "In12.Cu" "In13.Cu" "In14.Cu"
			"In15.Cu" "In16.Cu"
		)
		(hatch none 0.5)
		(connect_pads
			(clearance 0)
		)
		(min_thickness 0.25)
		(keepout
			(tracks not_allowed)
			(vias allowed)
			(pads allowed)
			(copperpour not_allowed)
			(footprints allowed)
		)
		(placement
			(enabled no)
			(sheetname "")
		)
		(fill
			(thermal_gap 0.5)
			(thermal_bridge_width 0.5)
			(island_removal_mode 0)
		)
		(polygon
			(pts
				(arc
					(start 345.812364 -217.878406)
					(mid 345.154504 -217.878406)
					(end 345.812364 -217.878406)
				)
			)
		)
	)
	(zone
		(layers "F.Cu" "B.Cu" "In1.Cu" "In2.Cu" "In3.Cu" "In4.Cu" "In5.Cu" "In6.Cu"
			"In7.Cu" "In8.Cu" "In9.Cu" "In10.Cu" "In11.Cu" "In12.Cu" "In13.Cu" "In14.Cu"
			"In15.Cu" "In16.Cu"
		)
		(hatch none 0.5)
		(connect_pads
			(clearance 0)
		)
		(min_thickness 0.25)
		(keepout
			(tracks not_allowed)
			(vias allowed)
			(pads allowed)
			(copperpour not_allowed)
			(footprints allowed)
		)
		(placement
			(enabled no)
			(sheetname "")
		)
		(fill
			(thermal_gap 0.5)
			(thermal_bridge_width 0.5)
			(island_removal_mode 0)
		)
		(polygon
			(pts
				(arc
					(start 341.113364 -217.878406)
					(mid 340.455504 -217.878406)
					(end 341.113364 -217.878406)
				)
			)
		)
	)
	(zone
		(layers "F.Cu" "B.Cu" "In1.Cu" "In2.Cu" "In3.Cu" "In4.Cu" "In5.Cu" "In6.Cu"
			"In7.Cu" "In8.Cu" "In9.Cu" "In10.Cu" "In11.Cu" "In12.Cu" "In13.Cu" "In14.Cu"
			"In15.Cu" "In16.Cu"
		)
		(hatch none 0.5)
		(connect_pads
			(clearance 0)
		)
		(min_thickness 0.25)
		(keepout
			(tracks not_allowed)
			(vias allowed)
			(pads allowed)
			(copperpour not_allowed)
			(footprints allowed)
		)
		(placement
			(enabled no)
			(sheetname "")
		)
		(fill
			(thermal_gap 0.5)
			(thermal_bridge_width 0.5)
			(island_removal_mode 0)
		)
		(polygon
			(pts
				(arc
					(start 346.123514 -220.418152)
					(mid 346.143198 -220.370742)
					(end 346.14993 -220.319854)
				)
				(arc
					(start 346.14993 -220.319854)
					(mid 346.092274 -220.18066)
					(end 345.95308 -220.123004)
				)
				(arc
					(start 345.95308 -220.123004)
					(mid 345.854649 -220.14942)
					(end 345.782646 -220.221556)
				)
				(arc
					(start 345.313 -221.035626)
					(mid 345.293316 -221.083036)
					(end 345.286584 -221.133924)
				)
				(arc
					(start 345.286584 -221.133924)
					(mid 345.34424 -221.273118)
					(end 345.483434 -221.330774)
				)
				(arc
					(start 345.483434 -221.330774)
					(mid 345.581865 -221.304358)
					(end 345.653868 -221.232222)
				)
			)
		)
	)
	(zone
		(layers "F.Cu" "B.Cu" "In1.Cu" "In2.Cu" "In3.Cu" "In4.Cu" "In5.Cu" "In6.Cu"
			"In7.Cu" "In8.Cu" "In9.Cu" "In10.Cu" "In11.Cu" "In12.Cu" "In13.Cu" "In14.Cu"
			"In15.Cu" "In16.Cu"
		)
		(hatch none 0.5)
		(connect_pads
			(clearance 0)
		)
		(min_thickness 0.25)
		(keepout
			(tracks not_allowed)
			(vias allowed)
			(pads allowed)
			(copperpour not_allowed)
			(footprints allowed)
		)
		(placement
			(enabled no)
			(sheetname "")
		)
		(fill
			(thermal_gap 0.5)
			(thermal_bridge_width 0.5)
			(island_removal_mode 0)
		)
		(polygon
			(pts
				(arc
					(start 99.751896 -217.878406)
					(mid 99.094036 -217.878406)
					(end 99.751896 -217.878406)
				)
			)
		)
	)
	(zone
		(layers "F.Cu" "B.Cu" "In1.Cu" "In2.Cu" "In3.Cu" "In4.Cu" "In5.Cu" "In6.Cu"
			"In7.Cu" "In8.Cu" "In9.Cu" "In10.Cu" "In11.Cu" "In12.Cu" "In13.Cu" "In14.Cu"
			"In15.Cu" "In16.Cu"
		)
		(hatch none 0.5)
		(connect_pads
			(clearance 0)
		)
		(min_thickness 0.25)
		(keepout
			(tracks not_allowed)
			(vias allowed)
			(pads allowed)
			(copperpour not_allowed)
			(footprints allowed)
		)
		(placement
			(enabled no)
			(sheetname "")
		)
		(fill
			(thermal_gap 0.5)
			(thermal_bridge_width 0.5)
			(island_removal_mode 0)
		)
		(polygon
			(pts
				(arc
					(start 348.741746 -284.847538)
					(mid 348.083886 -284.847538)
					(end 348.741746 -284.847538)
				)
			)
		)
	)
	(zone
		(layers "F.Cu" "B.Cu" "In1.Cu" "In2.Cu" "In3.Cu" "In4.Cu" "In5.Cu" "In6.Cu"
			"In7.Cu" "In8.Cu" "In9.Cu" "In10.Cu" "In11.Cu" "In12.Cu" "In13.Cu" "In14.Cu"
			"In15.Cu" "In16.Cu"
		)
		(hatch none 0.5)
		(connect_pads
			(clearance 0)
		)
		(min_thickness 0.25)
		(keepout
			(tracks not_allowed)
			(vias allowed)
			(pads allowed)
			(copperpour not_allowed)
			(footprints allowed)
		)
		(placement
			(enabled no)
			(sheetname "")
		)
		(fill
			(thermal_gap 0.5)
			(thermal_bridge_width 0.5)
			(island_removal_mode 0)
		)
		(polygon
			(pts
				(arc
					(start 79.958438 -409.649168)
					(mid 79.577438 -410.030168)
					(end 79.958438 -410.411168)
				)
				(arc
					(start 80.822038 -410.411168)
					(mid 81.203038 -410.030168)
					(end 80.822038 -409.649168)
				)
			)
		)
	)
	(zone
		(layers "F.Cu" "B.Cu" "In1.Cu" "In2.Cu" "In3.Cu" "In4.Cu" "In5.Cu" "In6.Cu"
			"In7.Cu" "In8.Cu" "In9.Cu" "In10.Cu" "In11.Cu" "In12.Cu" "In13.Cu" "In14.Cu"
			"In15.Cu" "In16.Cu"
		)
		(hatch none 0.5)
		(connect_pads
			(clearance 0)
		)
		(min_thickness 0.25)
		(keepout
			(tracks not_allowed)
			(vias allowed)
			(pads allowed)
			(copperpour not_allowed)
			(footprints allowed)
		)
		(placement
			(enabled no)
			(sheetname "")
		)
		(fill
			(thermal_gap 0.5)
			(thermal_bridge_width 0.5)
			(island_removal_mode 0)
		)
		(polygon
			(pts
				(arc
					(start 381.634492 -289.807142)
					(mid 380.976632 -289.807142)
					(end 381.634492 -289.807142)
				)
			)
		)
	)
	(zone
		(layers "F.Cu" "B.Cu" "In1.Cu" "In2.Cu" "In3.Cu" "In4.Cu" "In5.Cu" "In6.Cu"
			"In7.Cu" "In8.Cu" "In9.Cu" "In10.Cu" "In11.Cu" "In12.Cu" "In13.Cu" "In14.Cu"
			"In15.Cu" "In16.Cu"
		)
		(hatch none 0.5)
		(connect_pads
			(clearance 0)
		)
		(min_thickness 0.25)
		(keepout
			(tracks not_allowed)
			(vias allowed)
			(pads allowed)
			(copperpour not_allowed)
			(footprints allowed)
		)
		(placement
			(enabled no)
			(sheetname "")
		)
		(fill
			(thermal_gap 0.5)
			(thermal_bridge_width 0.5)
			(island_removal_mode 0)
		)
		(polygon
			(pts
				(arc
					(start 130.295142 -223.575626)
					(mid 129.637282 -223.575626)
					(end 130.295142 -223.575626)
				)
			)
		)
	)
	(zone
		(layers "F.Cu" "B.Cu" "In1.Cu" "In2.Cu" "In3.Cu" "In4.Cu" "In5.Cu" "In6.Cu"
			"In7.Cu" "In8.Cu" "In9.Cu" "In10.Cu" "In11.Cu" "In12.Cu" "In13.Cu" "In14.Cu"
			"In15.Cu" "In16.Cu"
		)
		(hatch none 0.5)
		(connect_pads
			(clearance 0)
		)
		(min_thickness 0.25)
		(keepout
			(tracks not_allowed)
			(vias allowed)
			(pads allowed)
			(copperpour not_allowed)
			(footprints allowed)
		)
		(placement
			(enabled no)
			(sheetname "")
		)
		(fill
			(thermal_gap 0.5)
			(thermal_bridge_width 0.5)
			(island_removal_mode 0)
		)
		(polygon
			(pts
				(arc
					(start 130.137154 -216.966292)
					(mid 130.065165 -216.894133)
					(end 129.96672 -216.86774)
				)
				(arc
					(start 129.96672 -216.86774)
					(mid 129.827526 -216.925396)
					(end 129.76987 -217.06459)
				)
				(arc
					(start 129.76987 -217.06459)
					(mid 129.776627 -217.115471)
					(end 129.796286 -217.162888)
				)
				(arc
					(start 130.265932 -217.976704)
					(mid 130.337921 -218.048863)
					(end 130.436366 -218.075256)
				)
				(arc
					(start 130.436366 -218.075256)
					(mid 130.57556 -218.0176)
					(end 130.633216 -217.878406)
				)
				(arc
					(start 130.633216 -217.878406)
					(mid 130.626459 -217.827525)
					(end 130.6068 -217.780108)
				)
			)
		)
	)
	(zone
		(layers "F.Cu" "B.Cu" "In1.Cu" "In2.Cu" "In3.Cu" "In4.Cu" "In5.Cu" "In6.Cu"
			"In7.Cu" "In8.Cu" "In9.Cu" "In10.Cu" "In11.Cu" "In12.Cu" "In13.Cu" "In14.Cu"
			"In15.Cu" "In16.Cu"
		)
		(hatch none 0.5)
		(connect_pads
			(clearance 0)
		)
		(min_thickness 0.25)
		(keepout
			(tracks not_allowed)
			(vias allowed)
			(pads allowed)
			(copperpour not_allowed)
			(footprints allowed)
		)
		(placement
			(enabled no)
			(sheetname "")
		)
		(fill
			(thermal_gap 0.5)
			(thermal_bridge_width 0.5)
			(island_removal_mode 0)
		)
		(polygon
			(pts
				(arc
					(start 41.83634 -385.194556)
					(mid 41.45534 -385.575556)
					(end 41.83634 -385.956556)
				)
				(arc
					(start 42.69994 -385.956556)
					(mid 43.08094 -385.575556)
					(end 42.69994 -385.194556)
				)
			)
		)
	)
	(zone
		(layers "F.Cu" "B.Cu" "In1.Cu" "In2.Cu" "In3.Cu" "In4.Cu" "In5.Cu" "In6.Cu"
			"In7.Cu" "In8.Cu" "In9.Cu" "In10.Cu" "In11.Cu" "In12.Cu" "In13.Cu" "In14.Cu"
			"In15.Cu" "In16.Cu"
		)
		(hatch none 0.5)
		(connect_pads
			(clearance 0)
		)
		(min_thickness 0.25)
		(keepout
			(tracks not_allowed)
			(vias allowed)
			(pads allowed)
			(copperpour not_allowed)
			(footprints allowed)
		)
		(placement
			(enabled no)
			(sheetname "")
		)
		(fill
			(thermal_gap 0.5)
			(thermal_bridge_width 0.5)
			(island_removal_mode 0)
		)
		(polygon
			(pts
				(arc
					(start 335.958688 -406.62352)
					(mid 335.577688 -407.00452)
					(end 335.958688 -407.38552)
				)
				(arc
					(start 336.822288 -407.38552)
					(mid 337.203288 -407.00452)
					(end 336.822288 -406.62352)
				)
			)
		)
	)
	(zone
		(layers "F.Cu" "B.Cu" "In1.Cu" "In2.Cu" "In3.Cu" "In4.Cu" "In5.Cu" "In6.Cu"
			"In7.Cu" "In8.Cu" "In9.Cu" "In10.Cu" "In11.Cu" "In12.Cu" "In13.Cu" "In14.Cu"
			"In15.Cu" "In16.Cu"
		)
		(hatch none 0.5)
		(connect_pads
			(clearance 0)
		)
		(min_thickness 0.25)
		(keepout
			(tracks not_allowed)
			(vias allowed)
			(pads allowed)
			(copperpour not_allowed)
			(footprints allowed)
		)
		(placement
			(enabled no)
			(sheetname "")
		)
		(fill
			(thermal_gap 0.5)
			(thermal_bridge_width 0.5)
			(island_removal_mode 0)
		)
		(polygon
			(pts
				(arc
					(start 361.31881 -220.319854)
					(mid 360.66095 -220.319854)
					(end 361.31881 -220.319854)
				)
			)
		)
	)
	(zone
		(layers "F.Cu" "B.Cu" "In1.Cu" "In2.Cu" "In3.Cu" "In4.Cu" "In5.Cu" "In6.Cu"
			"In7.Cu" "In8.Cu" "In9.Cu" "In10.Cu" "In11.Cu" "In12.Cu" "In13.Cu" "In14.Cu"
			"In15.Cu" "In16.Cu"
		)
		(hatch none 0.5)
		(connect_pads
			(clearance 0)
		)
		(min_thickness 0.25)
		(keepout
			(tracks not_allowed)
			(vias allowed)
			(pads allowed)
			(copperpour not_allowed)
			(footprints allowed)
		)
		(placement
			(enabled no)
			(sheetname "")
		)
		(fill
			(thermal_gap 0.5)
			(thermal_bridge_width 0.5)
			(island_removal_mode 0)
		)
		(polygon
			(pts
				(arc
					(start 105.231692 -214.720932)
					(mid 105.251376 -214.673522)
					(end 105.258108 -214.622634)
				)
				(arc
					(start 105.258108 -214.622634)
					(mid 105.200452 -214.48344)
					(end 105.061258 -214.425784)
				)
				(arc
					(start 105.061258 -214.425784)
					(mid 104.962827 -214.4522)
					(end 104.890824 -214.524336)
				)
				(arc
					(start 104.421178 -215.338406)
					(mid 104.401494 -215.385816)
					(end 104.394762 -215.436704)
				)
				(arc
					(start 104.394762 -215.436704)
					(mid 104.452418 -215.575898)
					(end 104.591612 -215.633554)
				)
				(arc
					(start 104.591612 -215.633554)
					(mid 104.690043 -215.607138)
					(end 104.762046 -215.535002)
				)
			)
		)
	)
	(zone
		(layers "F.Cu" "B.Cu" "In1.Cu" "In2.Cu" "In3.Cu" "In4.Cu" "In5.Cu" "In6.Cu"
			"In7.Cu" "In8.Cu" "In9.Cu" "In10.Cu" "In11.Cu" "In12.Cu" "In13.Cu" "In14.Cu"
			"In15.Cu" "In16.Cu"
		)
		(hatch none 0.5)
		(connect_pads
			(clearance 0)
		)
		(min_thickness 0.25)
		(keepout
			(tracks not_allowed)
			(vias allowed)
			(pads allowed)
			(copperpour not_allowed)
			(footprints allowed)
		)
		(placement
			(enabled no)
			(sheetname "")
		)
		(fill
			(thermal_gap 0.5)
			(thermal_bridge_width 0.5)
			(island_removal_mode 0)
		)
		(polygon
			(pts
				(arc
					(start 126.176278 -286.475424)
					(mid 125.518418 -286.475424)
					(end 126.176278 -286.475424)
				)
			)
		)
	)
	(zone
		(layers "F.Cu" "B.Cu" "In1.Cu" "In2.Cu" "In3.Cu" "In4.Cu" "In5.Cu" "In6.Cu"
			"In7.Cu" "In8.Cu" "In9.Cu" "In10.Cu" "In11.Cu" "In12.Cu" "In13.Cu" "In14.Cu"
			"In15.Cu" "In16.Cu"
		)
		(hatch none 0.5)
		(connect_pads
			(clearance 0)
		)
		(min_thickness 0.25)
		(keepout
			(tracks not_allowed)
			(vias allowed)
			(pads allowed)
			(copperpour not_allowed)
			(footprints allowed)
		)
		(placement
			(enabled no)
			(sheetname "")
		)
		(fill
			(thermal_gap 0.5)
			(thermal_bridge_width 0.5)
			(island_removal_mode 0)
		)
		(polygon
			(pts
				(arc
					(start 348.473268 -221.035626)
					(mid 348.401279 -220.963467)
					(end 348.302834 -220.937074)
				)
				(arc
					(start 348.302834 -220.937074)
					(mid 348.16364 -220.99473)
					(end 348.105984 -221.133924)
				)
				(arc
					(start 348.105984 -221.133924)
					(mid 348.112741 -221.184805)
					(end 348.1324 -221.232222)
				)
				(arc
					(start 348.602046 -222.046038)
					(mid 348.674035 -222.118197)
					(end 348.77248 -222.14459)
				)
				(arc
					(start 348.77248 -222.14459)
					(mid 348.911674 -222.086934)
					(end 348.96933 -221.94774)
				)
				(arc
					(start 348.96933 -221.94774)
					(mid 348.962573 -221.896859)
					(end 348.942914 -221.849442)
				)
			)
		)
	)
	(zone
		(layers "F.Cu" "B.Cu" "In1.Cu" "In2.Cu" "In3.Cu" "In4.Cu" "In5.Cu" "In6.Cu"
			"In7.Cu" "In8.Cu" "In9.Cu" "In10.Cu" "In11.Cu" "In12.Cu" "In13.Cu" "In14.Cu"
			"In15.Cu" "In16.Cu"
		)
		(hatch none 0.5)
		(connect_pads
			(clearance 0)
		)
		(min_thickness 0.25)
		(keepout
			(tracks not_allowed)
			(vias allowed)
			(pads allowed)
			(copperpour not_allowed)
			(footprints allowed)
		)
		(placement
			(enabled no)
			(sheetname "")
		)
		(fill
			(thermal_gap 0.5)
			(thermal_bridge_width 0.5)
			(island_removal_mode 0)
		)
		(polygon
			(pts
				(arc
					(start 408.18181 -400.477228)
					(mid 407.80081 -400.858228)
					(end 408.18181 -401.239228)
				)
				(arc
					(start 409.04541 -401.239228)
					(mid 409.42641 -400.858228)
					(end 409.04541 -400.477228)
				)
			)
		)
	)
	(zone
		(layers "F.Cu" "B.Cu" "In1.Cu" "In2.Cu" "In3.Cu" "In4.Cu" "In5.Cu" "In6.Cu"
			"In7.Cu" "In8.Cu" "In9.Cu" "In10.Cu" "In11.Cu" "In12.Cu" "In13.Cu" "In14.Cu"
			"In15.Cu" "In16.Cu"
		)
		(hatch none 0.5)
		(connect_pads
			(clearance 0)
		)
		(min_thickness 0.25)
		(keepout
			(tracks not_allowed)
			(vias allowed)
			(pads allowed)
			(copperpour not_allowed)
			(footprints allowed)
		)
		(placement
			(enabled no)
			(sheetname "")
		)
		(fill
			(thermal_gap 0.5)
			(thermal_bridge_width 0.5)
			(island_removal_mode 0)
		)
		(polygon
			(pts
				(arc
					(start 357.55961 -223.575626)
					(mid 356.90175 -223.575626)
					(end 357.55961 -223.575626)
				)
			)
		)
	)
	(zone
		(layers "F.Cu" "B.Cu" "In1.Cu" "In2.Cu" "In3.Cu" "In4.Cu" "In5.Cu" "In6.Cu"
			"In7.Cu" "In8.Cu" "In9.Cu" "In10.Cu" "In11.Cu" "In12.Cu" "In13.Cu" "In14.Cu"
			"In15.Cu" "In16.Cu"
		)
		(hatch none 0.5)
		(connect_pads
			(clearance 0)
		)
		(min_thickness 0.25)
		(keepout
			(tracks not_allowed)
			(vias allowed)
			(pads allowed)
			(copperpour not_allowed)
			(footprints allowed)
		)
		(placement
			(enabled no)
			(sheetname "")
		)
		(fill
			(thermal_gap 0.5)
			(thermal_bridge_width 0.5)
			(island_removal_mode 0)
		)
		(polygon
			(pts
				(arc
					(start 345.090496 -72.680576)
					(mid 345.471496 -72.299576)
					(end 345.090496 -71.918576)
				)
				(arc
					(start 344.226896 -71.918576)
					(mid 343.845896 -72.299576)
					(end 344.226896 -72.680576)
				)
			)
		)
	)
	(zone
		(layers "F.Cu" "B.Cu" "In1.Cu" "In2.Cu" "In3.Cu" "In4.Cu" "In5.Cu" "In6.Cu"
			"In7.Cu" "In8.Cu" "In9.Cu" "In10.Cu" "In11.Cu" "In12.Cu" "In13.Cu" "In14.Cu"
			"In15.Cu" "In16.Cu"
		)
		(hatch none 0.5)
		(connect_pads
			(clearance 0)
		)
		(min_thickness 0.25)
		(keepout
			(tracks not_allowed)
			(vias allowed)
			(pads allowed)
			(copperpour not_allowed)
			(footprints allowed)
		)
		(placement
			(enabled no)
			(sheetname "")
		)
		(fill
			(thermal_gap 0.5)
			(thermal_bridge_width 0.5)
			(island_removal_mode 0)
		)
		(polygon
			(pts
				(arc
					(start 102.4128 -217.780108)
					(mid 102.340811 -217.707949)
					(end 102.242366 -217.681556)
				)
				(arc
					(start 102.242366 -217.681556)
					(mid 102.103172 -217.739212)
					(end 102.045516 -217.878406)
				)
				(arc
					(start 102.045516 -217.878406)
					(mid 102.052273 -217.929287)
					(end 102.071932 -217.976704)
				)
				(arc
					(start 102.541578 -218.79052)
					(mid 102.613567 -218.862679)
					(end 102.712012 -218.889072)
				)
				(arc
					(start 102.712012 -218.889072)
					(mid 102.851206 -218.831416)
					(end 102.908862 -218.692222)
				)
				(arc
					(start 102.908862 -218.692222)
					(mid 102.902105 -218.641341)
					(end 102.882446 -218.593924)
				)
			)
		)
	)
	(zone
		(layers "F.Cu" "B.Cu" "In1.Cu" "In2.Cu" "In3.Cu" "In4.Cu" "In5.Cu" "In6.Cu"
			"In7.Cu" "In8.Cu" "In9.Cu" "In10.Cu" "In11.Cu" "In12.Cu" "In13.Cu" "In14.Cu"
			"In15.Cu" "In16.Cu"
		)
		(hatch none 0.5)
		(connect_pads
			(clearance 0)
		)
		(min_thickness 0.25)
		(keepout
			(tracks not_allowed)
			(vias allowed)
			(pads allowed)
			(copperpour not_allowed)
			(footprints allowed)
		)
		(placement
			(enabled no)
			(sheetname "")
		)
		(fill
			(thermal_gap 0.5)
			(thermal_bridge_width 0.5)
			(island_removal_mode 0)
		)
		(polygon
			(pts
				(arc
					(start 122.776742 -217.064336)
					(mid 122.118882 -217.064336)
					(end 122.776742 -217.064336)
				)
			)
		)
	)
	(zone
		(layers "F.Cu" "B.Cu" "In1.Cu" "In2.Cu" "In3.Cu" "In4.Cu" "In5.Cu" "In6.Cu"
			"In7.Cu" "In8.Cu" "In9.Cu" "In10.Cu" "In11.Cu" "In12.Cu" "In13.Cu" "In14.Cu"
			"In15.Cu" "In16.Cu"
		)
		(hatch none 0.5)
		(connect_pads
			(clearance 0)
		)
		(min_thickness 0.25)
		(keepout
			(tracks not_allowed)
			(vias allowed)
			(pads allowed)
			(copperpour not_allowed)
			(footprints allowed)
		)
		(placement
			(enabled no)
			(sheetname "")
		)
		(fill
			(thermal_gap 0.5)
			(thermal_bridge_width 0.5)
			(island_removal_mode 0)
		)
		(polygon
			(pts
				(arc
					(start 123.246896 -221.133924)
					(mid 122.589036 -221.133924)
					(end 123.246896 -221.133924)
				)
			)
		)
	)
	(zone
		(layers "F.Cu" "B.Cu" "In1.Cu" "In2.Cu" "In3.Cu" "In4.Cu" "In5.Cu" "In6.Cu"
			"In7.Cu" "In8.Cu" "In9.Cu" "In10.Cu" "In11.Cu" "In12.Cu" "In13.Cu" "In14.Cu"
			"In15.Cu" "In16.Cu"
		)
		(hatch none 0.5)
		(connect_pads
			(clearance 0)
		)
		(min_thickness 0.25)
		(keepout
			(tracks not_allowed)
			(vias allowed)
			(pads allowed)
			(copperpour not_allowed)
			(footprints allowed)
		)
		(placement
			(enabled no)
			(sheetname "")
		)
		(fill
			(thermal_gap 0.5)
			(thermal_bridge_width 0.5)
			(island_removal_mode 0)
		)
		(polygon
			(pts
				(arc
					(start 381.994664 -220.319854)
					(mid 381.336804 -220.319854)
					(end 381.994664 -220.319854)
				)
			)
		)
	)
	(zone
		(layers "F.Cu" "B.Cu" "In1.Cu" "In2.Cu" "In3.Cu" "In4.Cu" "In5.Cu" "In6.Cu"
			"In7.Cu" "In8.Cu" "In9.Cu" "In10.Cu" "In11.Cu" "In12.Cu" "In13.Cu" "In14.Cu"
			"In15.Cu" "In16.Cu"
		)
		(hatch none 0.5)
		(connect_pads
			(clearance 0)
		)
		(min_thickness 0.25)
		(keepout
			(tracks not_allowed)
			(vias allowed)
			(pads allowed)
			(copperpour not_allowed)
			(footprints allowed)
		)
		(placement
			(enabled no)
			(sheetname "")
		)
		(fill
			(thermal_gap 0.5)
			(thermal_bridge_width 0.5)
			(island_removal_mode 0)
		)
		(polygon
			(pts
				(arc
					(start 133.396482 -215.436704)
					(mid 134.054342 -215.436704)
					(end 133.396482 -215.436704)
				)
			)
		)
	)
	(zone
		(layers "F.Cu" "B.Cu" "In1.Cu" "In2.Cu" "In3.Cu" "In4.Cu" "In5.Cu" "In6.Cu"
			"In7.Cu" "In8.Cu" "In9.Cu" "In10.Cu" "In11.Cu" "In12.Cu" "In13.Cu" "In14.Cu"
			"In15.Cu" "In16.Cu"
		)
		(hatch none 0.5)
		(connect_pads
			(clearance 0)
		)
		(min_thickness 0.25)
		(keepout
			(tracks not_allowed)
			(vias allowed)
			(pads allowed)
			(copperpour not_allowed)
			(footprints allowed)
		)
		(placement
			(enabled no)
			(sheetname "")
		)
		(fill
			(thermal_gap 0.5)
			(thermal_bridge_width 0.5)
			(island_removal_mode 0)
		)
		(polygon
			(pts
				(arc
					(start 373.176546 -284.847538)
					(mid 372.518686 -284.847538)
					(end 373.176546 -284.847538)
				)
			)
		)
	)
	(zone
		(layers "F.Cu" "B.Cu" "In1.Cu" "In2.Cu" "In3.Cu" "In4.Cu" "In5.Cu" "In6.Cu"
			"In7.Cu" "In8.Cu" "In9.Cu" "In10.Cu" "In11.Cu" "In12.Cu" "In13.Cu" "In14.Cu"
			"In15.Cu" "In16.Cu"
		)
		(hatch none 0.5)
		(connect_pads
			(clearance 0)
		)
		(min_thickness 0.25)
		(keepout
			(tracks not_allowed)
			(vias allowed)
			(pads allowed)
			(copperpour not_allowed)
			(footprints allowed)
		)
		(placement
			(enabled no)
			(sheetname "")
		)
		(fill
			(thermal_gap 0.5)
			(thermal_bridge_width 0.5)
			(island_removal_mode 0)
		)
		(polygon
			(pts
				(arc
					(start 132.644896 -217.878406)
					(mid 131.987036 -217.878406)
					(end 132.644896 -217.878406)
				)
			)
		)
	)
	(zone
		(layers "F.Cu" "B.Cu" "In1.Cu" "In2.Cu" "In3.Cu" "In4.Cu" "In5.Cu" "In6.Cu"
			"In7.Cu" "In8.Cu" "In9.Cu" "In10.Cu" "In11.Cu" "In12.Cu" "In13.Cu" "In14.Cu"
			"In15.Cu" "In16.Cu"
		)
		(hatch none 0.5)
		(connect_pads
			(clearance 0)
		)
		(min_thickness 0.25)
		(keepout
			(tracks not_allowed)
			(vias allowed)
			(pads allowed)
			(copperpour not_allowed)
			(footprints allowed)
		)
		(placement
			(enabled no)
			(sheetname "")
		)
		(fill
			(thermal_gap 0.5)
			(thermal_bridge_width 0.5)
			(island_removal_mode 0)
		)
		(polygon
			(pts
				(arc
					(start 323.705728 -409.649168)
					(mid 323.324728 -410.030168)
					(end 323.705728 -410.411168)
				)
				(arc
					(start 324.569328 -410.411168)
					(mid 324.950328 -410.030168)
					(end 324.569328 -409.649168)
				)
			)
		)
	)
	(zone
		(layers "F.Cu" "B.Cu" "In1.Cu" "In2.Cu" "In3.Cu" "In4.Cu" "In5.Cu" "In6.Cu"
			"In7.Cu" "In8.Cu" "In9.Cu" "In10.Cu" "In11.Cu" "In12.Cu" "In13.Cu" "In14.Cu"
			"In15.Cu" "In16.Cu"
		)
		(hatch none 0.5)
		(connect_pads
			(clearance 0)
		)
		(min_thickness 0.25)
		(keepout
			(tracks not_allowed)
			(vias allowed)
			(pads allowed)
			(copperpour not_allowed)
			(footprints allowed)
		)
		(placement
			(enabled no)
			(sheetname "")
		)
		(fill
			(thermal_gap 0.5)
			(thermal_bridge_width 0.5)
			(island_removal_mode 0)
		)
		(polygon
			(pts
				(arc
					(start 120.349264 -285.661354)
					(mid 121.007124 -285.661354)
					(end 120.349264 -285.661354)
				)
			)
		)
	)
	(zone
		(layers "F.Cu" "B.Cu" "In1.Cu" "In2.Cu" "In3.Cu" "In4.Cu" "In5.Cu" "In6.Cu"
			"In7.Cu" "In8.Cu" "In9.Cu" "In10.Cu" "In11.Cu" "In12.Cu" "In13.Cu" "In14.Cu"
			"In15.Cu" "In16.Cu"
		)
		(hatch none 0.5)
		(connect_pads
			(clearance 0)
		)
		(min_thickness 0.25)
		(keepout
			(tracks not_allowed)
			(vias allowed)
			(pads allowed)
			(copperpour not_allowed)
			(footprints allowed)
		)
		(placement
			(enabled no)
			(sheetname "")
		)
		(fill
			(thermal_gap 0.5)
			(thermal_bridge_width 0.5)
			(island_removal_mode 0)
		)
		(polygon
			(pts
				(arc
					(start 96.932496 -224.389442)
					(mid 96.274636 -224.389442)
					(end 96.932496 -224.389442)
				)
			)
		)
	)
	(zone
		(layers "F.Cu" "B.Cu" "In1.Cu" "In2.Cu" "In3.Cu" "In4.Cu" "In5.Cu" "In6.Cu"
			"In7.Cu" "In8.Cu" "In9.Cu" "In10.Cu" "In11.Cu" "In12.Cu" "In13.Cu" "In14.Cu"
			"In15.Cu" "In16.Cu"
		)
		(hatch none 0.5)
		(connect_pads
			(clearance 0)
		)
		(min_thickness 0.25)
		(keepout
			(tracks not_allowed)
			(vias allowed)
			(pads allowed)
			(copperpour not_allowed)
			(footprints allowed)
		)
		(placement
			(enabled no)
			(sheetname "")
		)
		(fill
			(thermal_gap 0.5)
			(thermal_bridge_width 0.5)
			(island_removal_mode 0)
		)
		(polygon
			(pts
				(arc
					(start 106.440478 -281.59202)
					(mid 105.782618 -281.59202)
					(end 106.440478 -281.59202)
				)
			)
		)
	)
	(zone
		(layers "F.Cu" "B.Cu" "In1.Cu" "In2.Cu" "In3.Cu" "In4.Cu" "In5.Cu" "In6.Cu"
			"In7.Cu" "In8.Cu" "In9.Cu" "In10.Cu" "In11.Cu" "In12.Cu" "In13.Cu" "In14.Cu"
			"In15.Cu" "In16.Cu"
		)
		(hatch none 0.5)
		(connect_pads
			(clearance 0)
		)
		(min_thickness 0.25)
		(keepout
			(tracks not_allowed)
			(vias allowed)
			(pads allowed)
			(copperpour not_allowed)
			(footprints allowed)
		)
		(placement
			(enabled no)
			(sheetname "")
		)
		(fill
			(thermal_gap 0.5)
			(thermal_bridge_width 0.5)
			(island_removal_mode 0)
		)
		(polygon
			(pts
				(arc
					(start 342.162892 -289.807142)
					(mid 341.505032 -289.807142)
					(end 342.162892 -289.807142)
				)
			)
		)
	)
	(zone
		(layers "F.Cu" "B.Cu" "In1.Cu" "In2.Cu" "In3.Cu" "In4.Cu" "In5.Cu" "In6.Cu"
			"In7.Cu" "In8.Cu" "In9.Cu" "In10.Cu" "In11.Cu" "In12.Cu" "In13.Cu" "In14.Cu"
			"In15.Cu" "In16.Cu"
		)
		(hatch none 0.5)
		(connect_pads
			(clearance 0)
		)
		(min_thickness 0.25)
		(keepout
			(tracks not_allowed)
			(vias allowed)
			(pads allowed)
			(copperpour not_allowed)
			(footprints allowed)
		)
		(placement
			(enabled no)
			(sheetname "")
		)
		(fill
			(thermal_gap 0.5)
			(thermal_bridge_width 0.5)
			(island_removal_mode 0)
		)
		(polygon
			(pts
				(arc
					(start 124.108464 -285.661354)
					(mid 124.766324 -285.661354)
					(end 124.108464 -285.661354)
				)
			)
		)
	)
	(zone
		(layers "F.Cu" "B.Cu" "In1.Cu" "In2.Cu" "In3.Cu" "In4.Cu" "In5.Cu" "In6.Cu"
			"In7.Cu" "In8.Cu" "In9.Cu" "In10.Cu" "In11.Cu" "In12.Cu" "In13.Cu" "In14.Cu"
			"In15.Cu" "In16.Cu"
		)
		(hatch none 0.5)
		(connect_pads
			(clearance 0)
		)
		(min_thickness 0.25)
		(keepout
			(tracks not_allowed)
			(vias allowed)
			(pads allowed)
			(copperpour not_allowed)
			(footprints allowed)
		)
		(placement
			(enabled no)
			(sheetname "")
		)
		(fill
			(thermal_gap 0.5)
			(thermal_bridge_width 0.5)
			(island_removal_mode 0)
		)
		(polygon
			(pts
				(arc
					(start 104.372664 -275.8948)
					(mid 105.030524 -275.8948)
					(end 104.372664 -275.8948)
				)
			)
		)
	)
	(zone
		(layers "F.Cu" "B.Cu" "In1.Cu" "In2.Cu" "In3.Cu" "In4.Cu" "In5.Cu" "In6.Cu"
			"In7.Cu" "In8.Cu" "In9.Cu" "In10.Cu" "In11.Cu" "In12.Cu" "In13.Cu" "In14.Cu"
			"In15.Cu" "In16.Cu"
		)
		(hatch none 0.5)
		(connect_pads
			(clearance 0)
		)
		(min_thickness 0.25)
		(keepout
			(tracks not_allowed)
			(vias allowed)
			(pads allowed)
			(copperpour not_allowed)
			(footprints allowed)
		)
		(placement
			(enabled no)
			(sheetname "")
		)
		(fill
			(thermal_gap 0.5)
			(thermal_bridge_width 0.5)
			(island_removal_mode 0)
		)
		(polygon
			(pts
				(arc
					(start 28.02128 -4.581652)
					(mid 27.64028 -4.962652)
					(end 28.02128 -5.343652)
				)
				(arc
					(start 28.88488 -5.343652)
					(mid 29.26588 -4.962652)
					(end 28.88488 -4.581652)
				)
			)
		)
	)
	(zone
		(layers "F.Cu" "B.Cu" "In1.Cu" "In2.Cu" "In3.Cu" "In4.Cu" "In5.Cu" "In6.Cu"
			"In7.Cu" "In8.Cu" "In9.Cu" "In10.Cu" "In11.Cu" "In12.Cu" "In13.Cu" "In14.Cu"
			"In15.Cu" "In16.Cu"
		)
		(hatch none 0.5)
		(connect_pads
			(clearance 0)
		)
		(min_thickness 0.25)
		(keepout
			(tracks not_allowed)
			(vias allowed)
			(pads allowed)
			(copperpour not_allowed)
			(footprints allowed)
		)
		(placement
			(enabled no)
			(sheetname "")
		)
		(fill
			(thermal_gap 0.5)
			(thermal_bridge_width 0.5)
			(island_removal_mode 0)
		)
		(polygon
			(pts
				(arc
					(start 339.021928 -406.62352)
					(mid 338.640928 -407.00452)
					(end 339.021928 -407.38552)
				)
				(arc
					(start 339.885528 -407.38552)
					(mid 340.266528 -407.00452)
					(end 339.885528 -406.62352)
				)
			)
		)
	)
	(zone
		(layers "F.Cu" "B.Cu" "In1.Cu" "In2.Cu" "In3.Cu" "In4.Cu" "In5.Cu" "In6.Cu"
			"In7.Cu" "In8.Cu" "In9.Cu" "In10.Cu" "In11.Cu" "In12.Cu" "In13.Cu" "In14.Cu"
			"In15.Cu" "In16.Cu"
		)
		(hatch none 0.5)
		(connect_pads
			(clearance 0)
		)
		(min_thickness 0.25)
		(keepout
			(tracks not_allowed)
			(vias allowed)
			(pads allowed)
			(copperpour not_allowed)
			(footprints allowed)
		)
		(placement
			(enabled no)
			(sheetname "")
		)
		(fill
			(thermal_gap 0.5)
			(thermal_bridge_width 0.5)
			(island_removal_mode 0)
		)
		(polygon
			(pts
				(arc
					(start 123.716542 -225.203258)
					(mid 123.058682 -225.203258)
					(end 123.716542 -225.203258)
				)
			)
		)
	)
	(zone
		(layers "F.Cu" "B.Cu" "In1.Cu" "In2.Cu" "In3.Cu" "In4.Cu" "In5.Cu" "In6.Cu"
			"In7.Cu" "In8.Cu" "In9.Cu" "In10.Cu" "In11.Cu" "In12.Cu" "In13.Cu" "In14.Cu"
			"In15.Cu" "In16.Cu"
		)
		(hatch none 0.5)
		(connect_pads
			(clearance 0)
		)
		(min_thickness 0.25)
		(keepout
			(tracks not_allowed)
			(vias allowed)
			(pads allowed)
			(copperpour not_allowed)
			(footprints allowed)
		)
		(placement
			(enabled no)
			(sheetname "")
		)
		(fill
			(thermal_gap 0.5)
			(thermal_bridge_width 0.5)
			(island_removal_mode 0)
		)
		(polygon
			(pts
				(arc
					(start 94.8944 -224.291144)
					(mid 94.822411 -224.218985)
					(end 94.723966 -224.192592)
				)
				(arc
					(start 94.723966 -224.192592)
					(mid 94.584772 -224.250248)
					(end 94.527116 -224.389442)
				)
				(arc
					(start 94.527116 -224.389442)
					(mid 94.533873 -224.440323)
					(end 94.553532 -224.48774)
				)
				(arc
					(start 95.023178 -225.301556)
					(mid 95.095167 -225.373715)
					(end 95.193612 -225.400108)
				)
				(arc
					(start 95.193612 -225.400108)
					(mid 95.332806 -225.342452)
					(end 95.390462 -225.203258)
				)
				(arc
					(start 95.390462 -225.203258)
					(mid 95.383705 -225.152377)
					(end 95.364046 -225.10496)
				)
			)
		)
	)
	(zone
		(layers "F.Cu" "B.Cu" "In1.Cu" "In2.Cu" "In3.Cu" "In4.Cu" "In5.Cu" "In6.Cu"
			"In7.Cu" "In8.Cu" "In9.Cu" "In10.Cu" "In11.Cu" "In12.Cu" "In13.Cu" "In14.Cu"
			"In15.Cu" "In16.Cu"
		)
		(hatch none 0.5)
		(connect_pads
			(clearance 0)
		)
		(min_thickness 0.25)
		(keepout
			(tracks not_allowed)
			(vias allowed)
			(pads allowed)
			(copperpour not_allowed)
			(footprints allowed)
		)
		(placement
			(enabled no)
			(sheetname "")
		)
		(fill
			(thermal_gap 0.5)
			(thermal_bridge_width 0.5)
			(island_removal_mode 0)
		)
		(polygon
			(pts
				(arc
					(start 122.61088 -213.646766)
					(mid 122.543172 -213.574915)
					(end 122.448066 -213.548468)
				)
				(arc
					(start 122.448066 -213.548468)
					(mid 122.317852 -213.602404)
					(end 122.263916 -213.732618)
				)
				(arc
					(start 122.263916 -213.732618)
					(mid 122.269367 -213.776839)
					(end 122.285252 -213.81847)
				)
				(arc
					(start 122.754644 -214.708486)
					(mid 122.822352 -214.780337)
					(end 122.917458 -214.806784)
				)
				(arc
					(start 122.917458 -214.806784)
					(mid 123.047672 -214.752848)
					(end 123.101608 -214.622634)
				)
				(arc
					(start 123.101608 -214.622634)
					(mid 123.096157 -214.578413)
					(end 123.080272 -214.536782)
				)
			)
		)
	)
	(zone
		(layers "F.Cu" "B.Cu" "In1.Cu" "In2.Cu" "In3.Cu" "In4.Cu" "In5.Cu" "In6.Cu"
			"In7.Cu" "In8.Cu" "In9.Cu" "In10.Cu" "In11.Cu" "In12.Cu" "In13.Cu" "In14.Cu"
			"In15.Cu" "In16.Cu"
		)
		(hatch none 0.5)
		(connect_pads
			(clearance 0)
		)
		(min_thickness 0.25)
		(keepout
			(tracks not_allowed)
			(vias allowed)
			(pads allowed)
			(copperpour not_allowed)
			(footprints allowed)
		)
		(placement
			(enabled no)
			(sheetname "")
		)
		(fill
			(thermal_gap 0.5)
			(thermal_bridge_width 0.5)
			(island_removal_mode 0)
		)
		(polygon
			(pts
				(arc
					(start 96.462342 -223.575626)
					(mid 95.804482 -223.575626)
					(end 96.462342 -223.575626)
				)
			)
		)
	)
	(zone
		(layers "F.Cu" "B.Cu" "In1.Cu" "In2.Cu" "In3.Cu" "In4.Cu" "In5.Cu" "In6.Cu"
			"In7.Cu" "In8.Cu" "In9.Cu" "In10.Cu" "In11.Cu" "In12.Cu" "In13.Cu" "In14.Cu"
			"In15.Cu" "In16.Cu"
		)
		(hatch none 0.5)
		(connect_pads
			(clearance 0)
		)
		(min_thickness 0.25)
		(keepout
			(tracks not_allowed)
			(vias allowed)
			(pads allowed)
			(copperpour not_allowed)
			(footprints allowed)
		)
		(placement
			(enabled no)
			(sheetname "")
		)
		(fill
			(thermal_gap 0.5)
			(thermal_bridge_width 0.5)
			(island_removal_mode 0)
		)
		(polygon
			(pts
				(arc
					(start 78.612238 -400.477228)
					(mid 78.231238 -400.858228)
					(end 78.612238 -401.239228)
				)
				(arc
					(start 79.475838 -401.239228)
					(mid 79.856838 -400.858228)
					(end 79.475838 -400.477228)
				)
			)
		)
	)
	(zone
		(layers "F.Cu" "B.Cu" "In1.Cu" "In2.Cu" "In3.Cu" "In4.Cu" "In5.Cu" "In6.Cu"
			"In7.Cu" "In8.Cu" "In9.Cu" "In10.Cu" "In11.Cu" "In12.Cu" "In13.Cu" "In14.Cu"
			"In15.Cu" "In16.Cu"
		)
		(hatch none 0.5)
		(connect_pads
			(clearance 0)
		)
		(min_thickness 0.25)
		(keepout
			(tracks not_allowed)
			(vias allowed)
			(pads allowed)
			(copperpour not_allowed)
			(footprints allowed)
		)
		(placement
			(enabled no)
			(sheetname "")
		)
		(fill
			(thermal_gap 0.5)
			(thermal_bridge_width 0.5)
			(island_removal_mode 0)
		)
		(polygon
			(pts
				(arc
					(start 103.932482 -280.679652)
					(mid 103.860493 -280.607493)
					(end 103.762048 -280.5811)
				)
				(arc
					(start 103.762048 -280.5811)
					(mid 103.622854 -280.638756)
					(end 103.565198 -280.77795)
				)
				(arc
					(start 103.565198 -280.77795)
					(mid 103.571955 -280.828831)
					(end 103.591614 -280.876248)
				)
				(arc
					(start 104.061514 -281.690318)
					(mid 104.133503 -281.762477)
					(end 104.231948 -281.78887)
				)
				(arc
					(start 104.231948 -281.78887)
					(mid 104.371142 -281.731214)
					(end 104.428798 -281.59202)
				)
				(arc
					(start 104.428798 -281.59202)
					(mid 104.422041 -281.541139)
					(end 104.402382 -281.493722)
				)
			)
		)
	)
	(zone
		(layers "F.Cu" "B.Cu" "In1.Cu" "In2.Cu" "In3.Cu" "In4.Cu" "In5.Cu" "In6.Cu"
			"In7.Cu" "In8.Cu" "In9.Cu" "In10.Cu" "In11.Cu" "In12.Cu" "In13.Cu" "In14.Cu"
			"In15.Cu" "In16.Cu"
		)
		(hatch none 0.5)
		(connect_pads
			(clearance 0)
		)
		(min_thickness 0.25)
		(keepout
			(tracks not_allowed)
			(vias allowed)
			(pads allowed)
			(copperpour not_allowed)
			(footprints allowed)
		)
		(placement
			(enabled no)
			(sheetname "")
		)
		(fill
			(thermal_gap 0.5)
			(thermal_bridge_width 0.5)
			(island_removal_mode 0)
		)
		(polygon
			(pts
				(arc
					(start 337.775296 -285.563056)
					(mid 337.703307 -285.490897)
					(end 337.604862 -285.464504)
				)
				(arc
					(start 337.604862 -285.464504)
					(mid 337.465668 -285.52216)
					(end 337.408012 -285.661354)
				)
				(arc
					(start 337.408012 -285.661354)
					(mid 337.414769 -285.712235)
					(end 337.434428 -285.759652)
				)
				(arc
					(start 337.904328 -286.573722)
					(mid 337.976317 -286.645881)
					(end 338.074762 -286.672274)
				)
				(arc
					(start 338.074762 -286.672274)
					(mid 338.213956 -286.614618)
					(end 338.271612 -286.475424)
				)
				(arc
					(start 338.271612 -286.475424)
					(mid 338.264855 -286.424543)
					(end 338.245196 -286.377126)
				)
			)
		)
	)
	(zone
		(layers "F.Cu" "B.Cu" "In1.Cu" "In2.Cu" "In3.Cu" "In4.Cu" "In5.Cu" "In6.Cu"
			"In7.Cu" "In8.Cu" "In9.Cu" "In10.Cu" "In11.Cu" "In12.Cu" "In13.Cu" "In14.Cu"
			"In15.Cu" "In16.Cu"
		)
		(hatch none 0.5)
		(connect_pads
			(clearance 0)
		)
		(min_thickness 0.25)
		(keepout
			(tracks not_allowed)
			(vias allowed)
			(pads allowed)
			(copperpour not_allowed)
			(footprints allowed)
		)
		(placement
			(enabled no)
			(sheetname "")
		)
		(fill
			(thermal_gap 0.5)
			(thermal_bridge_width 0.5)
			(island_removal_mode 0)
		)
		(polygon
			(pts
				(arc
					(start 132.118862 -289.003232)
					(mid 132.134786 -288.961481)
					(end 132.140198 -288.917126)
				)
				(arc
					(start 132.140198 -288.917126)
					(mid 132.086262 -288.786912)
					(end 131.956048 -288.732976)
				)
				(arc
					(start 131.956048 -288.732976)
					(mid 131.861028 -288.759384)
					(end 131.793234 -288.83102)
				)
				(arc
					(start 131.32308 -289.721036)
					(mid 131.307156 -289.762787)
					(end 131.301744 -289.807142)
				)
				(arc
					(start 131.301744 -289.807142)
					(mid 131.35568 -289.937356)
					(end 131.485894 -289.991292)
				)
				(arc
					(start 131.485894 -289.991292)
					(mid 131.580914 -289.964884)
					(end 131.648708 -289.893248)
				)
			)
		)
	)
	(zone
		(layers "F.Cu" "B.Cu" "In1.Cu" "In2.Cu" "In3.Cu" "In4.Cu" "In5.Cu" "In6.Cu"
			"In7.Cu" "In8.Cu" "In9.Cu" "In10.Cu" "In11.Cu" "In12.Cu" "In13.Cu" "In14.Cu"
			"In15.Cu" "In16.Cu"
		)
		(hatch none 0.5)
		(connect_pads
			(clearance 0)
		)
		(min_thickness 0.25)
		(keepout
			(tracks not_allowed)
			(vias allowed)
			(pads allowed)
			(copperpour not_allowed)
			(footprints allowed)
		)
		(placement
			(enabled no)
			(sheetname "")
		)
		(fill
			(thermal_gap 0.5)
			(thermal_bridge_width 0.5)
			(island_removal_mode 0)
		)
		(polygon
			(pts
				(arc
					(start 123.0884 -224.291144)
					(mid 123.016411 -224.218985)
					(end 122.917966 -224.192592)
				)
				(arc
					(start 122.917966 -224.192592)
					(mid 122.778772 -224.250248)
					(end 122.721116 -224.389442)
				)
				(arc
					(start 122.721116 -224.389442)
					(mid 122.727873 -224.440323)
					(end 122.747532 -224.48774)
				)
				(arc
					(start 123.217178 -225.301556)
					(mid 123.289167 -225.373715)
					(end 123.387612 -225.400108)
				)
				(arc
					(start 123.387612 -225.400108)
					(mid 123.526806 -225.342452)
					(end 123.584462 -225.203258)
				)
				(arc
					(start 123.584462 -225.203258)
					(mid 123.577705 -225.152377)
					(end 123.558046 -225.10496)
				)
			)
		)
	)
	(zone
		(layers "F.Cu" "B.Cu" "In1.Cu" "In2.Cu" "In3.Cu" "In4.Cu" "In5.Cu" "In6.Cu"
			"In7.Cu" "In8.Cu" "In9.Cu" "In10.Cu" "In11.Cu" "In12.Cu" "In13.Cu" "In14.Cu"
			"In15.Cu" "In16.Cu"
		)
		(hatch none 0.5)
		(connect_pads
			(clearance 0)
		)
		(min_thickness 0.25)
		(keepout
			(tracks not_allowed)
			(vias allowed)
			(pads allowed)
			(copperpour not_allowed)
			(footprints allowed)
		)
		(placement
			(enabled no)
			(sheetname "")
		)
		(fill
			(thermal_gap 0.5)
			(thermal_bridge_width 0.5)
			(island_removal_mode 0)
		)
		(polygon
			(pts
				(arc
					(start 366.799114 -223.67367)
					(mid 366.818798 -223.62626)
					(end 366.82553 -223.575372)
				)
				(arc
					(start 366.82553 -223.575372)
					(mid 366.767874 -223.436178)
					(end 366.62868 -223.378522)
				)
				(arc
					(start 366.62868 -223.378522)
					(mid 366.530249 -223.404938)
					(end 366.458246 -223.477074)
				)
				(arc
					(start 365.9886 -224.291144)
					(mid 365.968916 -224.338554)
					(end 365.962184 -224.389442)
				)
				(arc
					(start 365.962184 -224.389442)
					(mid 366.01984 -224.528636)
					(end 366.159034 -224.586292)
				)
				(arc
					(start 366.159034 -224.586292)
					(mid 366.257465 -224.559876)
					(end 366.329468 -224.48774)
				)
			)
		)
	)
	(zone
		(layers "F.Cu" "B.Cu" "In1.Cu" "In2.Cu" "In3.Cu" "In4.Cu" "In5.Cu" "In6.Cu"
			"In7.Cu" "In8.Cu" "In9.Cu" "In10.Cu" "In11.Cu" "In12.Cu" "In13.Cu" "In14.Cu"
			"In15.Cu" "In16.Cu"
		)
		(hatch none 0.5)
		(connect_pads
			(clearance 0)
		)
		(min_thickness 0.25)
		(keepout
			(tracks not_allowed)
			(vias allowed)
			(pads allowed)
			(copperpour not_allowed)
			(footprints allowed)
		)
		(placement
			(enabled no)
			(sheetname "")
		)
		(fill
			(thermal_gap 0.5)
			(thermal_bridge_width 0.5)
			(island_removal_mode 0)
		)
		(polygon
			(pts
				(arc
					(start 118.859554 -216.966292)
					(mid 118.787565 -216.894133)
					(end 118.68912 -216.86774)
				)
				(arc
					(start 118.68912 -216.86774)
					(mid 118.549926 -216.925396)
					(end 118.49227 -217.06459)
				)
				(arc
					(start 118.49227 -217.06459)
					(mid 118.499027 -217.115471)
					(end 118.518686 -217.162888)
				)
				(arc
					(start 118.988332 -217.976704)
					(mid 119.060321 -218.048863)
					(end 119.158766 -218.075256)
				)
				(arc
					(start 119.158766 -218.075256)
					(mid 119.29796 -218.0176)
					(end 119.355616 -217.878406)
				)
				(arc
					(start 119.355616 -217.878406)
					(mid 119.348859 -217.827525)
					(end 119.3292 -217.780108)
				)
			)
		)
	)
	(zone
		(layers "F.Cu" "B.Cu" "In1.Cu" "In2.Cu" "In3.Cu" "In4.Cu" "In5.Cu" "In6.Cu"
			"In7.Cu" "In8.Cu" "In9.Cu" "In10.Cu" "In11.Cu" "In12.Cu" "In13.Cu" "In14.Cu"
			"In15.Cu" "In16.Cu"
		)
		(hatch none 0.5)
		(connect_pads
			(clearance 0)
		)
		(min_thickness 0.25)
		(keepout
			(tracks not_allowed)
			(vias allowed)
			(pads allowed)
			(copperpour not_allowed)
			(footprints allowed)
		)
		(placement
			(enabled no)
			(sheetname "")
		)
		(fill
			(thermal_gap 0.5)
			(thermal_bridge_width 0.5)
			(island_removal_mode 0)
		)
		(polygon
			(pts
				(arc
					(start 58.199274 -13.245084)
					(mid 58.580274 -12.864084)
					(end 58.199274 -12.483084)
				)
				(arc
					(start 57.335674 -12.483084)
					(mid 56.954674 -12.864084)
					(end 57.335674 -13.245084)
				)
			)
		)
	)
	(zone
		(layers "F.Cu" "B.Cu" "In1.Cu" "In2.Cu" "In3.Cu" "In4.Cu" "In5.Cu" "In6.Cu"
			"In7.Cu" "In8.Cu" "In9.Cu" "In10.Cu" "In11.Cu" "In12.Cu" "In13.Cu" "In14.Cu"
			"In15.Cu" "In16.Cu"
		)
		(hatch none 0.5)
		(connect_pads
			(clearance 0)
		)
		(min_thickness 0.25)
		(keepout
			(tracks not_allowed)
			(vias allowed)
			(pads allowed)
			(copperpour not_allowed)
			(footprints allowed)
		)
		(placement
			(enabled no)
			(sheetname "")
		)
		(fill
			(thermal_gap 0.5)
			(thermal_bridge_width 0.5)
			(island_removal_mode 0)
		)
		(polygon
			(pts
				(arc
					(start 340.400894 -74.905616)
					(mid 340.781894 -74.524616)
					(end 340.400894 -74.143616)
				)
				(arc
					(start 339.537294 -74.143616)
					(mid 339.156294 -74.524616)
					(end 339.537294 -74.905616)
				)
			)
		)
	)
	(zone
		(layers "F.Cu" "B.Cu" "In1.Cu" "In2.Cu" "In3.Cu" "In4.Cu" "In5.Cu" "In6.Cu"
			"In7.Cu" "In8.Cu" "In9.Cu" "In10.Cu" "In11.Cu" "In12.Cu" "In13.Cu" "In14.Cu"
			"In15.Cu" "In16.Cu"
		)
		(hatch none 0.5)
		(connect_pads
			(clearance 0)
		)
		(min_thickness 0.25)
		(keepout
			(tracks not_allowed)
			(vias allowed)
			(pads allowed)
			(copperpour not_allowed)
			(footprints allowed)
		)
		(placement
			(enabled no)
			(sheetname "")
		)
		(fill
			(thermal_gap 0.5)
			(thermal_bridge_width 0.5)
			(island_removal_mode 0)
		)
		(polygon
			(pts
				(arc
					(start 97.713292 -214.720932)
					(mid 97.732976 -214.673522)
					(end 97.739708 -214.622634)
				)
				(arc
					(start 97.739708 -214.622634)
					(mid 97.682052 -214.48344)
					(end 97.542858 -214.425784)
				)
				(arc
					(start 97.542858 -214.425784)
					(mid 97.444427 -214.4522)
					(end 97.372424 -214.524336)
				)
				(arc
					(start 96.902778 -215.338406)
					(mid 96.883094 -215.385816)
					(end 96.876362 -215.436704)
				)
				(arc
					(start 96.876362 -215.436704)
					(mid 96.934018 -215.575898)
					(end 97.073212 -215.633554)
				)
				(arc
					(start 97.073212 -215.633554)
					(mid 97.171643 -215.607138)
					(end 97.243646 -215.535002)
				)
			)
		)
	)
	(zone
		(layers "F.Cu" "B.Cu" "In1.Cu" "In2.Cu" "In3.Cu" "In4.Cu" "In5.Cu" "In6.Cu"
			"In7.Cu" "In8.Cu" "In9.Cu" "In10.Cu" "In11.Cu" "In12.Cu" "In13.Cu" "In14.Cu"
			"In15.Cu" "In16.Cu"
		)
		(hatch none 0.5)
		(connect_pads
			(clearance 0)
		)
		(min_thickness 0.25)
		(keepout
			(tracks not_allowed)
			(vias allowed)
			(pads allowed)
			(copperpour not_allowed)
			(footprints allowed)
		)
		(placement
			(enabled no)
			(sheetname "")
		)
		(fill
			(thermal_gap 0.5)
			(thermal_bridge_width 0.5)
			(island_removal_mode 0)
		)
		(polygon
			(pts
				(arc
					(start 92.211398 -409.649168)
					(mid 91.830398 -410.030168)
					(end 92.211398 -410.411168)
				)
				(arc
					(start 93.074998 -410.411168)
					(mid 93.455998 -410.030168)
					(end 93.074998 -409.649168)
				)
			)
		)
	)
	(zone
		(layers "F.Cu" "B.Cu" "In1.Cu" "In2.Cu" "In3.Cu" "In4.Cu" "In5.Cu" "In6.Cu"
			"In7.Cu" "In8.Cu" "In9.Cu" "In10.Cu" "In11.Cu" "In12.Cu" "In13.Cu" "In14.Cu"
			"In15.Cu" "In16.Cu"
		)
		(hatch none 0.5)
		(connect_pads
			(clearance 0)
		)
		(min_thickness 0.25)
		(keepout
			(tracks not_allowed)
			(vias allowed)
			(pads allowed)
			(copperpour not_allowed)
			(footprints allowed)
		)
		(placement
			(enabled no)
			(sheetname "")
		)
		(fill
			(thermal_gap 0.5)
			(thermal_bridge_width 0.5)
			(island_removal_mode 0)
		)
		(polygon
			(pts
				(arc
					(start 94.974664 -280.778204)
					(mid 95.632524 -280.778204)
					(end 94.974664 -280.778204)
				)
			)
		)
	)
	(zone
		(layers "F.Cu" "B.Cu" "In1.Cu" "In2.Cu" "In3.Cu" "In4.Cu" "In5.Cu" "In6.Cu"
			"In7.Cu" "In8.Cu" "In9.Cu" "In10.Cu" "In11.Cu" "In12.Cu" "In13.Cu" "In14.Cu"
			"In15.Cu" "In16.Cu"
		)
		(hatch none 0.5)
		(connect_pads
			(clearance 0)
		)
		(min_thickness 0.25)
		(keepout
			(tracks not_allowed)
			(vias allowed)
			(pads allowed)
			(copperpour not_allowed)
			(footprints allowed)
		)
		(placement
			(enabled no)
			(sheetname "")
		)
		(fill
			(thermal_gap 0.5)
			(thermal_bridge_width 0.5)
			(island_removal_mode 0)
		)
		(polygon
			(pts
				(arc
					(start 349.10141 -215.436704)
					(mid 348.44355 -215.436704)
					(end 349.10141 -215.436704)
				)
			)
		)
	)
	(zone
		(layers "F.Cu" "B.Cu" "In1.Cu" "In2.Cu" "In3.Cu" "In4.Cu" "In5.Cu" "In6.Cu"
			"In7.Cu" "In8.Cu" "In9.Cu" "In10.Cu" "In11.Cu" "In12.Cu" "In13.Cu" "In14.Cu"
			"In15.Cu" "In16.Cu"
		)
		(hatch none 0.5)
		(connect_pads
			(clearance 0)
		)
		(min_thickness 0.25)
		(keepout
			(tracks not_allowed)
			(vias allowed)
			(pads allowed)
			(copperpour not_allowed)
			(footprints allowed)
		)
		(placement
			(enabled no)
			(sheetname "")
		)
		(fill
			(thermal_gap 0.5)
			(thermal_bridge_width 0.5)
			(island_removal_mode 0)
		)
		(polygon
			(pts
				(arc
					(start 397.124174 -6.332474)
					(mid 396.743174 -6.713474)
					(end 397.124174 -7.094474)
				)
				(arc
					(start 397.987774 -7.094474)
					(mid 398.368774 -6.713474)
					(end 397.987774 -6.332474)
				)
			)
		)
	)
	(zone
		(layers "F.Cu" "B.Cu" "In1.Cu" "In2.Cu" "In3.Cu" "In4.Cu" "In5.Cu" "In6.Cu"
			"In7.Cu" "In8.Cu" "In9.Cu" "In10.Cu" "In11.Cu" "In12.Cu" "In13.Cu" "In14.Cu"
			"In15.Cu" "In16.Cu"
		)
		(hatch none 0.5)
		(connect_pads
			(clearance 0)
		)
		(min_thickness 0.25)
		(keepout
			(tracks not_allowed)
			(vias allowed)
			(pads allowed)
			(copperpour not_allowed)
			(footprints allowed)
		)
		(placement
			(enabled no)
			(sheetname "")
		)
		(fill
			(thermal_gap 0.5)
			(thermal_bridge_width 0.5)
			(island_removal_mode 0)
		)
		(polygon
			(pts
				(arc
					(start 89.365328 -288.201354)
					(mid 89.385012 -288.153944)
					(end 89.391744 -288.103056)
				)
				(arc
					(start 89.391744 -288.103056)
					(mid 89.334088 -287.963862)
					(end 89.194894 -287.906206)
				)
				(arc
					(start 89.194894 -287.906206)
					(mid 89.096463 -287.932622)
					(end 89.02446 -288.004758)
				)
				(arc
					(start 88.554814 -288.818828)
					(mid 88.53513 -288.866238)
					(end 88.528398 -288.917126)
				)
				(arc
					(start 88.528398 -288.917126)
					(mid 88.586054 -289.05632)
					(end 88.725248 -289.113976)
				)
				(arc
					(start 88.725248 -289.113976)
					(mid 88.823679 -289.08756)
					(end 88.895682 -289.015424)
				)
			)
		)
	)
	(zone
		(layers "F.Cu" "B.Cu" "In1.Cu" "In2.Cu" "In3.Cu" "In4.Cu" "In5.Cu" "In6.Cu"
			"In7.Cu" "In8.Cu" "In9.Cu" "In10.Cu" "In11.Cu" "In12.Cu" "In13.Cu" "In14.Cu"
			"In15.Cu" "In16.Cu"
		)
		(hatch none 0.5)
		(connect_pads
			(clearance 0)
		)
		(min_thickness 0.25)
		(keepout
			(tracks not_allowed)
			(vias allowed)
			(pads allowed)
			(copperpour not_allowed)
			(footprints allowed)
		)
		(placement
			(enabled no)
			(sheetname "")
		)
		(fill
			(thermal_gap 0.5)
			(thermal_bridge_width 0.5)
			(island_removal_mode 0)
		)
		(polygon
			(pts
				(arc
					(start 136.817354 -409.649168)
					(mid 136.436354 -410.030168)
					(end 136.817354 -410.411168)
				)
				(arc
					(start 137.680954 -410.411168)
					(mid 138.061954 -410.030168)
					(end 137.680954 -409.649168)
				)
			)
		)
	)
	(zone
		(layers "F.Cu" "B.Cu" "In1.Cu" "In2.Cu" "In3.Cu" "In4.Cu" "In5.Cu" "In6.Cu"
			"In7.Cu" "In8.Cu" "In9.Cu" "In10.Cu" "In11.Cu" "In12.Cu" "In13.Cu" "In14.Cu"
			"In15.Cu" "In16.Cu"
		)
		(hatch none 0.5)
		(connect_pads
			(clearance 0)
		)
		(min_thickness 0.25)
		(keepout
			(tracks not_allowed)
			(vias allowed)
			(pads allowed)
			(copperpour not_allowed)
			(footprints allowed)
		)
		(placement
			(enabled no)
			(sheetname "")
		)
		(fill
			(thermal_gap 0.5)
			(thermal_bridge_width 0.5)
			(island_removal_mode 0)
		)
		(polygon
			(pts
				(arc
					(start 124.498354 -220.22181)
					(mid 124.426365 -220.149651)
					(end 124.32792 -220.123258)
				)
				(arc
					(start 124.32792 -220.123258)
					(mid 124.188726 -220.180914)
					(end 124.13107 -220.320108)
				)
				(arc
					(start 124.13107 -220.320108)
					(mid 124.137827 -220.370989)
					(end 124.157486 -220.418406)
				)
				(arc
					(start 124.627132 -221.232222)
					(mid 124.699121 -221.304381)
					(end 124.797566 -221.330774)
				)
				(arc
					(start 124.797566 -221.330774)
					(mid 124.93676 -221.273118)
					(end 124.994416 -221.133924)
				)
				(arc
					(start 124.994416 -221.133924)
					(mid 124.987659 -221.083043)
					(end 124.968 -221.035626)
				)
			)
		)
	)
	(zone
		(layers "F.Cu" "B.Cu" "In1.Cu" "In2.Cu" "In3.Cu" "In4.Cu" "In5.Cu" "In6.Cu"
			"In7.Cu" "In8.Cu" "In9.Cu" "In10.Cu" "In11.Cu" "In12.Cu" "In13.Cu" "In14.Cu"
			"In15.Cu" "In16.Cu"
		)
		(hatch none 0.5)
		(connect_pads
			(clearance 0)
		)
		(min_thickness 0.25)
		(keepout
			(tracks not_allowed)
			(vias allowed)
			(pads allowed)
			(copperpour not_allowed)
			(footprints allowed)
		)
		(placement
			(enabled no)
			(sheetname "")
		)
		(fill
			(thermal_gap 0.5)
			(thermal_bridge_width 0.5)
			(island_removal_mode 0)
		)
		(polygon
			(pts
				(arc
					(start 373.066564 -217.878406)
					(mid 372.408704 -217.878406)
					(end 373.066564 -217.878406)
				)
			)
		)
	)
	(zone
		(layers "F.Cu" "B.Cu" "In1.Cu" "In2.Cu" "In3.Cu" "In4.Cu" "In5.Cu" "In6.Cu"
			"In7.Cu" "In8.Cu" "In9.Cu" "In10.Cu" "In11.Cu" "In12.Cu" "In13.Cu" "In14.Cu"
			"In15.Cu" "In16.Cu"
		)
		(hatch none 0.5)
		(connect_pads
			(clearance 0)
		)
		(min_thickness 0.25)
		(keepout
			(tracks not_allowed)
			(vias allowed)
			(pads allowed)
			(copperpour not_allowed)
			(footprints allowed)
		)
		(placement
			(enabled no)
			(sheetname "")
		)
		(fill
			(thermal_gap 0.5)
			(thermal_bridge_width 0.5)
			(island_removal_mode 0)
		)
		(polygon
			(pts
				(arc
					(start 345.452446 -288.917126)
					(mid 344.794586 -288.917126)
					(end 345.452446 -288.917126)
				)
			)
		)
	)
	(zone
		(layers "F.Cu" "B.Cu" "In1.Cu" "In2.Cu" "In3.Cu" "In4.Cu" "In5.Cu" "In6.Cu"
			"In7.Cu" "In8.Cu" "In9.Cu" "In10.Cu" "In11.Cu" "In12.Cu" "In13.Cu" "In14.Cu"
			"In15.Cu" "In16.Cu"
		)
		(hatch none 0.5)
		(connect_pads
			(clearance 0)
		)
		(min_thickness 0.25)
		(keepout
			(tracks not_allowed)
			(vias allowed)
			(pads allowed)
			(copperpour not_allowed)
			(footprints allowed)
		)
		(placement
			(enabled no)
			(sheetname "")
		)
		(fill
			(thermal_gap 0.5)
			(thermal_bridge_width 0.5)
			(island_removal_mode 0)
		)
		(polygon
			(pts
				(arc
					(start 346.865448 -400.477228)
					(mid 346.484448 -400.858228)
					(end 346.865448 -401.239228)
				)
				(arc
					(start 347.729048 -401.239228)
					(mid 348.110048 -400.858228)
					(end 347.729048 -400.477228)
				)
			)
		)
	)
	(zone
		(layers "F.Cu" "B.Cu" "In1.Cu" "In2.Cu" "In3.Cu" "In4.Cu" "In5.Cu" "In6.Cu"
			"In7.Cu" "In8.Cu" "In9.Cu" "In10.Cu" "In11.Cu" "In12.Cu" "In13.Cu" "In14.Cu"
			"In15.Cu" "In16.Cu"
		)
		(hatch none 0.5)
		(connect_pads
			(clearance 0)
		)
		(min_thickness 0.25)
		(keepout
			(tracks not_allowed)
			(vias allowed)
			(pads allowed)
			(copperpour not_allowed)
			(footprints allowed)
		)
		(placement
			(enabled no)
			(sheetname "")
		)
		(fill
			(thermal_gap 0.5)
			(thermal_bridge_width 0.5)
			(island_removal_mode 0)
		)
		(polygon
			(pts
				(arc
					(start 372.706392 -285.661354)
					(mid 372.048532 -285.661354)
					(end 372.706392 -285.661354)
				)
			)
		)
	)
	(zone
		(layers "F.Cu" "B.Cu" "In1.Cu" "In2.Cu" "In3.Cu" "In4.Cu" "In5.Cu" "In6.Cu"
			"In7.Cu" "In8.Cu" "In9.Cu" "In10.Cu" "In11.Cu" "In12.Cu" "In13.Cu" "In14.Cu"
			"In15.Cu" "In16.Cu"
		)
		(hatch none 0.5)
		(connect_pads
			(clearance 0)
		)
		(min_thickness 0.25)
		(keepout
			(tracks not_allowed)
			(vias allowed)
			(pads allowed)
			(copperpour not_allowed)
			(footprints allowed)
		)
		(placement
			(enabled no)
			(sheetname "")
		)
		(fill
			(thermal_gap 0.5)
			(thermal_bridge_width 0.5)
			(island_removal_mode 0)
		)
		(polygon
			(pts
				(arc
					(start 72.19442 -13.245084)
					(mid 72.57542 -12.864084)
					(end 72.19442 -12.483084)
				)
				(arc
					(start 71.33082 -12.483084)
					(mid 70.94982 -12.864084)
					(end 71.33082 -13.245084)
				)
			)
		)
	)
	(zone
		(layers "F.Cu" "B.Cu" "In1.Cu" "In2.Cu" "In3.Cu" "In4.Cu" "In5.Cu" "In6.Cu"
			"In7.Cu" "In8.Cu" "In9.Cu" "In10.Cu" "In11.Cu" "In12.Cu" "In13.Cu" "In14.Cu"
			"In15.Cu" "In16.Cu"
		)
		(hatch none 0.5)
		(connect_pads
			(clearance 0)
		)
		(min_thickness 0.25)
		(keepout
			(tracks not_allowed)
			(vias allowed)
			(pads allowed)
			(copperpour not_allowed)
			(footprints allowed)
		)
		(placement
			(enabled no)
			(sheetname "")
		)
		(fill
			(thermal_gap 0.5)
			(thermal_bridge_width 0.5)
			(island_removal_mode 0)
		)
		(polygon
			(pts
				(arc
					(start 117.608096 -217.878406)
					(mid 116.950236 -217.878406)
					(end 117.608096 -217.878406)
				)
			)
		)
	)
	(zone
		(layers "F.Cu" "B.Cu" "In1.Cu" "In2.Cu" "In3.Cu" "In4.Cu" "In5.Cu" "In6.Cu"
			"In7.Cu" "In8.Cu" "In9.Cu" "In10.Cu" "In11.Cu" "In12.Cu" "In13.Cu" "In14.Cu"
			"In15.Cu" "In16.Cu"
		)
		(hatch none 0.5)
		(connect_pads
			(clearance 0)
		)
		(min_thickness 0.25)
		(keepout
			(tracks not_allowed)
			(vias allowed)
			(pads allowed)
			(copperpour not_allowed)
			(footprints allowed)
		)
		(placement
			(enabled no)
			(sheetname "")
		)
		(fill
			(thermal_gap 0.5)
			(thermal_bridge_width 0.5)
			(island_removal_mode 0)
		)
		(polygon
			(pts
				(arc
					(start 411.24505 -403.502876)
					(mid 410.86405 -403.883876)
					(end 411.24505 -404.264876)
				)
				(arc
					(start 412.10865 -404.264876)
					(mid 412.48965 -403.883876)
					(end 412.10865 -403.502876)
				)
			)
		)
	)
	(zone
		(layers "F.Cu" "B.Cu" "In1.Cu" "In2.Cu" "In3.Cu" "In4.Cu" "In5.Cu" "In6.Cu"
			"In7.Cu" "In8.Cu" "In9.Cu" "In10.Cu" "In11.Cu" "In12.Cu" "In13.Cu" "In14.Cu"
			"In15.Cu" "In16.Cu"
		)
		(hatch none 0.5)
		(connect_pads
			(clearance 0)
		)
		(min_thickness 0.25)
		(keepout
			(tracks not_allowed)
			(vias allowed)
			(pads allowed)
			(copperpour not_allowed)
			(footprints allowed)
		)
		(placement
			(enabled no)
			(sheetname "")
		)
		(fill
			(thermal_gap 0.5)
			(thermal_bridge_width 0.5)
			(island_removal_mode 0)
		)
		(polygon
			(pts
				(arc
					(start 101.322124 -414.818068)
					(mid 100.941124 -414.437068)
					(end 100.560124 -414.818068)
				)
				(arc
					(start 100.560124 -415.681668)
					(mid 100.941124 -416.062668)
					(end 101.322124 -415.681668)
				)
			)
		)
	)
	(zone
		(layers "F.Cu" "B.Cu" "In1.Cu" "In2.Cu" "In3.Cu" "In4.Cu" "In5.Cu" "In6.Cu"
			"In7.Cu" "In8.Cu" "In9.Cu" "In10.Cu" "In11.Cu" "In12.Cu" "In13.Cu" "In14.Cu"
			"In15.Cu" "In16.Cu"
		)
		(hatch none 0.5)
		(connect_pads
			(clearance 0)
		)
		(min_thickness 0.25)
		(keepout
			(tracks not_allowed)
			(vias allowed)
			(pads allowed)
			(copperpour not_allowed)
			(footprints allowed)
		)
		(placement
			(enabled no)
			(sheetname "")
		)
		(fill
			(thermal_gap 0.5)
			(thermal_bridge_width 0.5)
			(island_removal_mode 0)
		)
		(polygon
			(pts
				(arc
					(start 129.277364 -289.807142)
					(mid 129.935224 -289.807142)
					(end 129.277364 -289.807142)
				)
			)
		)
	)
	(zone
		(layers "F.Cu" "B.Cu" "In1.Cu" "In2.Cu" "In3.Cu" "In4.Cu" "In5.Cu" "In6.Cu"
			"In7.Cu" "In8.Cu" "In9.Cu" "In10.Cu" "In11.Cu" "In12.Cu" "In13.Cu" "In14.Cu"
			"In15.Cu" "In16.Cu"
		)
		(hatch none 0.5)
		(connect_pads
			(clearance 0)
		)
		(min_thickness 0.25)
		(keepout
			(tracks not_allowed)
			(vias allowed)
			(pads allowed)
			(copperpour not_allowed)
			(footprints allowed)
		)
		(placement
			(enabled no)
			(sheetname "")
		)
		(fill
			(thermal_gap 0.5)
			(thermal_bridge_width 0.5)
			(island_removal_mode 0)
		)
		(polygon
			(pts
				(arc
					(start 257.266694 -109.572552)
					(mid 256.885694 -109.953552)
					(end 257.266694 -110.334552)
				)
				(arc
					(start 258.130294 -110.334552)
					(mid 258.511294 -109.953552)
					(end 258.130294 -109.572552)
				)
			)
		)
	)
	(zone
		(layers "F.Cu" "B.Cu" "In1.Cu" "In2.Cu" "In3.Cu" "In4.Cu" "In5.Cu" "In6.Cu"
			"In7.Cu" "In8.Cu" "In9.Cu" "In10.Cu" "In11.Cu" "In12.Cu" "In13.Cu" "In14.Cu"
			"In15.Cu" "In16.Cu"
		)
		(hatch none 0.5)
		(connect_pads
			(clearance 0)
		)
		(min_thickness 0.25)
		(keepout
			(tracks not_allowed)
			(vias allowed)
			(pads allowed)
			(copperpour not_allowed)
			(footprints allowed)
		)
		(placement
			(enabled no)
			(sheetname "")
		)
		(fill
			(thermal_gap 0.5)
			(thermal_bridge_width 0.5)
			(island_removal_mode 0)
		)
		(polygon
			(pts
				(arc
					(start 94.582742 -223.575626)
					(mid 93.924882 -223.575626)
					(end 94.582742 -223.575626)
				)
			)
		)
	)
	(zone
		(layers "F.Cu" "B.Cu" "In1.Cu" "In2.Cu" "In3.Cu" "In4.Cu" "In5.Cu" "In6.Cu"
			"In7.Cu" "In8.Cu" "In9.Cu" "In10.Cu" "In11.Cu" "In12.Cu" "In13.Cu" "In14.Cu"
			"In15.Cu" "In16.Cu"
		)
		(hatch none 0.5)
		(connect_pads
			(clearance 0)
		)
		(min_thickness 0.25)
		(keepout
			(tracks not_allowed)
			(vias allowed)
			(pads allowed)
			(copperpour not_allowed)
			(footprints allowed)
		)
		(placement
			(enabled no)
			(sheetname "")
		)
		(fill
			(thermal_gap 0.5)
			(thermal_bridge_width 0.5)
			(island_removal_mode 0)
		)
		(polygon
			(pts
				(arc
					(start 125.236478 -288.103056)
					(mid 124.578618 -288.103056)
					(end 125.236478 -288.103056)
				)
			)
		)
	)
	(zone
		(layers "F.Cu" "B.Cu" "In1.Cu" "In2.Cu" "In3.Cu" "In4.Cu" "In5.Cu" "In6.Cu"
			"In7.Cu" "In8.Cu" "In9.Cu" "In10.Cu" "In11.Cu" "In12.Cu" "In13.Cu" "In14.Cu"
			"In15.Cu" "In16.Cu"
		)
		(hatch none 0.5)
		(connect_pads
			(clearance 0)
		)
		(min_thickness 0.25)
		(keepout
			(tracks not_allowed)
			(vias allowed)
			(pads allowed)
			(copperpour not_allowed)
			(footprints allowed)
		)
		(placement
			(enabled no)
			(sheetname "")
		)
		(fill
			(thermal_gap 0.5)
			(thermal_bridge_width 0.5)
			(island_removal_mode 0)
		)
		(polygon
			(pts
				(arc
					(start 349.05315 -280.679652)
					(mid 348.981161 -280.607493)
					(end 348.882716 -280.5811)
				)
				(arc
					(start 348.882716 -280.5811)
					(mid 348.743522 -280.638756)
					(end 348.685866 -280.77795)
				)
				(arc
					(start 348.685866 -280.77795)
					(mid 348.692623 -280.828831)
					(end 348.712282 -280.876248)
				)
				(arc
					(start 349.182182 -281.690318)
					(mid 349.254171 -281.762477)
					(end 349.352616 -281.78887)
				)
				(arc
					(start 349.352616 -281.78887)
					(mid 349.49181 -281.731214)
					(end 349.549466 -281.59202)
				)
				(arc
					(start 349.549466 -281.59202)
					(mid 349.542709 -281.541139)
					(end 349.52305 -281.493722)
				)
			)
		)
	)
	(zone
		(layers "F.Cu" "B.Cu" "In1.Cu" "In2.Cu" "In3.Cu" "In4.Cu" "In5.Cu" "In6.Cu"
			"In7.Cu" "In8.Cu" "In9.Cu" "In10.Cu" "In11.Cu" "In12.Cu" "In13.Cu" "In14.Cu"
			"In15.Cu" "In16.Cu"
		)
		(hatch none 0.5)
		(connect_pads
			(clearance 0)
		)
		(min_thickness 0.25)
		(keepout
			(tracks not_allowed)
			(vias allowed)
			(pads allowed)
			(copperpour not_allowed)
			(footprints allowed)
		)
		(placement
			(enabled no)
			(sheetname "")
		)
		(fill
			(thermal_gap 0.5)
			(thermal_bridge_width 0.5)
			(island_removal_mode 0)
		)
		(polygon
			(pts
				(xy 465.100162 -416.609022) (xy 465.100162 -421.609012) (xy 464.795362 -421.304212) (xy 464.795362 -416.913822)
			)
		)
	)
	(zone
		(layers "F.Cu" "B.Cu" "In1.Cu" "In2.Cu" "In3.Cu" "In4.Cu" "In5.Cu" "In6.Cu"
			"In7.Cu" "In8.Cu" "In9.Cu" "In10.Cu" "In11.Cu" "In12.Cu" "In13.Cu" "In14.Cu"
			"In15.Cu" "In16.Cu"
		)
		(hatch none 0.5)
		(connect_pads
			(clearance 0)
		)
		(min_thickness 0.25)
		(keepout
			(tracks not_allowed)
			(vias allowed)
			(pads allowed)
			(copperpour not_allowed)
			(footprints allowed)
		)
		(placement
			(enabled no)
			(sheetname "")
		)
		(fill
			(thermal_gap 0.5)
			(thermal_bridge_width 0.5)
			(island_removal_mode 0)
		)
		(polygon
			(pts
				(arc
					(start 124.027692 -214.720932)
					(mid 124.047376 -214.673522)
					(end 124.054108 -214.622634)
				)
				(arc
					(start 124.054108 -214.622634)
					(mid 123.996452 -214.48344)
					(end 123.857258 -214.425784)
				)
				(arc
					(start 123.857258 -214.425784)
					(mid 123.758827 -214.4522)
					(end 123.686824 -214.524336)
				)
				(arc
					(start 123.217178 -215.338406)
					(mid 123.197494 -215.385816)
					(end 123.190762 -215.436704)
				)
				(arc
					(start 123.190762 -215.436704)
					(mid 123.248418 -215.575898)
					(end 123.387612 -215.633554)
				)
				(arc
					(start 123.387612 -215.633554)
					(mid 123.486043 -215.607138)
					(end 123.558046 -215.535002)
				)
			)
		)
	)
	(zone
		(layers "F.Cu" "B.Cu" "In1.Cu" "In2.Cu" "In3.Cu" "In4.Cu" "In5.Cu" "In6.Cu"
			"In7.Cu" "In8.Cu" "In9.Cu" "In10.Cu" "In11.Cu" "In12.Cu" "In13.Cu" "In14.Cu"
			"In15.Cu" "In16.Cu"
		)
		(hatch none 0.5)
		(connect_pads
			(clearance 0)
		)
		(min_thickness 0.25)
		(keepout
			(tracks not_allowed)
			(vias allowed)
			(pads allowed)
			(copperpour not_allowed)
			(footprints allowed)
		)
		(placement
			(enabled no)
			(sheetname "")
		)
		(fill
			(thermal_gap 0.5)
			(thermal_bridge_width 0.5)
			(island_removal_mode 0)
		)
		(polygon
			(pts
				(arc
					(start 24.143462 -175.83404)
					(mid 23.378414 -175.83404)
					(end 24.143462 -175.83404)
				)
			)
		)
	)
	(zone
		(layers "F.Cu" "B.Cu" "In1.Cu" "In2.Cu" "In3.Cu" "In4.Cu" "In5.Cu" "In6.Cu"
			"In7.Cu" "In8.Cu" "In9.Cu" "In10.Cu" "In11.Cu" "In12.Cu" "In13.Cu" "In14.Cu"
			"In15.Cu" "In16.Cu"
		)
		(hatch none 0.5)
		(connect_pads
			(clearance 0)
		)
		(min_thickness 0.25)
		(keepout
			(tracks not_allowed)
			(vias allowed)
			(pads allowed)
			(copperpour not_allowed)
			(footprints allowed)
		)
		(placement
			(enabled no)
			(sheetname "")
		)
		(fill
			(thermal_gap 0.5)
			(thermal_bridge_width 0.5)
			(island_removal_mode 0)
		)
		(polygon
			(pts
				(arc
					(start 86.084918 -406.62352)
					(mid 85.703918 -407.00452)
					(end 86.084918 -407.38552)
				)
				(arc
					(start 86.948518 -407.38552)
					(mid 87.329518 -407.00452)
					(end 86.948518 -406.62352)
				)
			)
		)
	)
	(zone
		(layers "F.Cu" "B.Cu" "In1.Cu" "In2.Cu" "In3.Cu" "In4.Cu" "In5.Cu" "In6.Cu"
			"In7.Cu" "In8.Cu" "In9.Cu" "In10.Cu" "In11.Cu" "In12.Cu" "In13.Cu" "In14.Cu"
			"In15.Cu" "In16.Cu"
		)
		(hatch none 0.5)
		(connect_pads
			(clearance 0)
		)
		(min_thickness 0.25)
		(keepout
			(tracks not_allowed)
			(vias allowed)
			(pads allowed)
			(copperpour not_allowed)
			(footprints allowed)
		)
		(placement
			(enabled no)
			(sheetname "")
		)
		(fill
			(thermal_gap 0.5)
			(thermal_bridge_width 0.5)
			(island_removal_mode 0)
		)
		(polygon
			(pts
				(arc
					(start 126.8476 -224.291144)
					(mid 126.775611 -224.218985)
					(end 126.677166 -224.192592)
				)
				(arc
					(start 126.677166 -224.192592)
					(mid 126.537972 -224.250248)
					(end 126.480316 -224.389442)
				)
				(arc
					(start 126.480316 -224.389442)
					(mid 126.487073 -224.440323)
					(end 126.506732 -224.48774)
				)
				(arc
					(start 126.976378 -225.301556)
					(mid 127.048367 -225.373715)
					(end 127.146812 -225.400108)
				)
				(arc
					(start 127.146812 -225.400108)
					(mid 127.286006 -225.342452)
					(end 127.343662 -225.203258)
				)
				(arc
					(start 127.343662 -225.203258)
					(mid 127.336905 -225.152377)
					(end 127.317246 -225.10496)
				)
			)
		)
	)
	(zone
		(layers "F.Cu" "B.Cu" "In1.Cu" "In2.Cu" "In3.Cu" "In4.Cu" "In5.Cu" "In6.Cu"
			"In7.Cu" "In8.Cu" "In9.Cu" "In10.Cu" "In11.Cu" "In12.Cu" "In13.Cu" "In14.Cu"
			"In15.Cu" "In16.Cu"
		)
		(hatch none 0.5)
		(connect_pads
			(clearance 0)
		)
		(min_thickness 0.25)
		(keepout
			(tracks not_allowed)
			(vias allowed)
			(pads allowed)
			(copperpour not_allowed)
			(footprints allowed)
		)
		(placement
			(enabled no)
			(sheetname "")
		)
		(fill
			(thermal_gap 0.5)
			(thermal_bridge_width 0.5)
			(island_removal_mode 0)
		)
		(polygon
			(pts
				(arc
					(start 403.40153 -409.649168)
					(mid 403.02053 -410.030168)
					(end 403.40153 -410.411168)
				)
				(arc
					(start 404.26513 -410.411168)
					(mid 404.64613 -410.030168)
					(end 404.26513 -409.649168)
				)
			)
		)
	)
	(zone
		(layers "F.Cu" "B.Cu" "In1.Cu" "In2.Cu" "In3.Cu" "In4.Cu" "In5.Cu" "In6.Cu"
			"In7.Cu" "In8.Cu" "In9.Cu" "In10.Cu" "In11.Cu" "In12.Cu" "In13.Cu" "In14.Cu"
			"In15.Cu" "In16.Cu"
		)
		(hatch none 0.5)
		(connect_pads
			(clearance 0)
		)
		(min_thickness 0.25)
		(keepout
			(tracks not_allowed)
			(vias allowed)
			(pads allowed)
			(copperpour not_allowed)
			(footprints allowed)
		)
		(placement
			(enabled no)
			(sheetname "")
		)
		(fill
			(thermal_gap 0.5)
			(thermal_bridge_width 0.5)
			(island_removal_mode 0)
		)
		(polygon
			(pts
				(arc
					(start 102.4128 -221.035626)
					(mid 102.340811 -220.963467)
					(end 102.242366 -220.937074)
				)
				(arc
					(start 102.242366 -220.937074)
					(mid 102.103172 -220.99473)
					(end 102.045516 -221.133924)
				)
				(arc
					(start 102.045516 -221.133924)
					(mid 102.052273 -221.184805)
					(end 102.071932 -221.232222)
				)
				(arc
					(start 102.541578 -222.046038)
					(mid 102.613567 -222.118197)
					(end 102.712012 -222.14459)
				)
				(arc
					(start 102.712012 -222.14459)
					(mid 102.851206 -222.086934)
					(end 102.908862 -221.94774)
				)
				(arc
					(start 102.908862 -221.94774)
					(mid 102.902105 -221.896859)
					(end 102.882446 -221.849442)
				)
			)
		)
	)
	(zone
		(layers "F.Cu" "B.Cu" "In1.Cu" "In2.Cu" "In3.Cu" "In4.Cu" "In5.Cu" "In6.Cu"
			"In7.Cu" "In8.Cu" "In9.Cu" "In10.Cu" "In11.Cu" "In12.Cu" "In13.Cu" "In14.Cu"
			"In15.Cu" "In16.Cu"
		)
		(hatch none 0.5)
		(connect_pads
			(clearance 0)
		)
		(min_thickness 0.25)
		(keepout
			(tracks not_allowed)
			(vias allowed)
			(pads allowed)
			(copperpour not_allowed)
			(footprints allowed)
		)
		(placement
			(enabled no)
			(sheetname "")
		)
		(fill
			(thermal_gap 0.5)
			(thermal_bridge_width 0.5)
			(island_removal_mode 0)
		)
		(polygon
			(pts
				(arc
					(start 389.80237 -403.502876)
					(mid 389.42137 -403.883876)
					(end 389.80237 -404.264876)
				)
				(arc
					(start 390.66597 -404.264876)
					(mid 391.04697 -403.883876)
					(end 390.66597 -403.502876)
				)
			)
		)
	)
	(zone
		(layers "F.Cu" "B.Cu" "In1.Cu" "In2.Cu" "In3.Cu" "In4.Cu" "In5.Cu" "In6.Cu"
			"In7.Cu" "In8.Cu" "In9.Cu" "In10.Cu" "In11.Cu" "In12.Cu" "In13.Cu" "In14.Cu"
			"In15.Cu" "In16.Cu"
		)
		(hatch none 0.5)
		(connect_pads
			(clearance 0)
		)
		(min_thickness 0.25)
		(keepout
			(tracks not_allowed)
			(vias allowed)
			(pads allowed)
			(copperpour not_allowed)
			(footprints allowed)
		)
		(placement
			(enabled no)
			(sheetname "")
		)
		(fill
			(thermal_gap 0.5)
			(thermal_bridge_width 0.5)
			(island_removal_mode 0)
		)
		(polygon
			(pts
				(arc
					(start 114.629946 -217.97645)
					(mid 114.64963 -217.92904)
					(end 114.656362 -217.878152)
				)
				(arc
					(start 114.656362 -217.878152)
					(mid 114.598706 -217.738958)
					(end 114.459512 -217.681302)
				)
				(arc
					(start 114.459512 -217.681302)
					(mid 114.361081 -217.707718)
					(end 114.289078 -217.779854)
				)
				(arc
					(start 113.819432 -218.593924)
					(mid 113.799748 -218.641334)
					(end 113.793016 -218.692222)
				)
				(arc
					(start 113.793016 -218.692222)
					(mid 113.850672 -218.831416)
					(end 113.989866 -218.889072)
				)
				(arc
					(start 113.989866 -218.889072)
					(mid 114.088297 -218.862656)
					(end 114.1603 -218.79052)
				)
			)
		)
	)
	(zone
		(layers "F.Cu" "B.Cu" "In1.Cu" "In2.Cu" "In3.Cu" "In4.Cu" "In5.Cu" "In6.Cu"
			"In7.Cu" "In8.Cu" "In9.Cu" "In10.Cu" "In11.Cu" "In12.Cu" "In13.Cu" "In14.Cu"
			"In15.Cu" "In16.Cu"
		)
		(hatch none 0.5)
		(connect_pads
			(clearance 0)
		)
		(min_thickness 0.25)
		(keepout
			(tracks not_allowed)
			(vias allowed)
			(pads allowed)
			(copperpour not_allowed)
			(footprints allowed)
		)
		(placement
			(enabled no)
			(sheetname "")
		)
		(fill
			(thermal_gap 0.5)
			(thermal_bridge_width 0.5)
			(island_removal_mode 0)
		)
		(polygon
			(pts
				(arc
					(start 363.89564 -55.503572)
					(mid 363.51464 -55.884572)
					(end 363.89564 -56.265572)
				)
				(arc
					(start 364.75924 -56.265572)
					(mid 365.14024 -55.884572)
					(end 364.75924 -55.503572)
				)
			)
		)
	)
	(zone
		(layers "F.Cu" "B.Cu" "In1.Cu" "In2.Cu" "In3.Cu" "In4.Cu" "In5.Cu" "In6.Cu"
			"In7.Cu" "In8.Cu" "In9.Cu" "In10.Cu" "In11.Cu" "In12.Cu" "In13.Cu" "In14.Cu"
			"In15.Cu" "In16.Cu"
		)
		(hatch none 0.5)
		(connect_pads
			(clearance 0)
		)
		(min_thickness 0.25)
		(keepout
			(tracks not_allowed)
			(vias allowed)
			(pads allowed)
			(copperpour not_allowed)
			(footprints allowed)
		)
		(placement
			(enabled no)
			(sheetname "")
		)
		(fill
			(thermal_gap 0.5)
			(thermal_bridge_width 0.5)
			(island_removal_mode 0)
		)
		(polygon
			(pts
				(arc
					(start 93.253814 -282.307538)
					(mid 93.23413 -282.354948)
					(end 93.227398 -282.405836)
				)
				(arc
					(start 93.227398 -282.405836)
					(mid 93.285054 -282.54503)
					(end 93.424248 -282.602686)
				)
				(arc
					(start 93.424248 -282.602686)
					(mid 93.522679 -282.57627)
					(end 93.594682 -282.504134)
				)
				(arc
					(start 94.064582 -281.690064)
					(mid 94.084266 -281.642654)
					(end 94.090998 -281.591766)
				)
				(arc
					(start 94.090998 -281.591766)
					(mid 94.033342 -281.452572)
					(end 93.894148 -281.394916)
				)
				(arc
					(start 93.894148 -281.394916)
					(mid 93.795717 -281.421332)
					(end 93.723714 -281.493468)
				)
			)
		)
	)
	(zone
		(layers "F.Cu" "B.Cu" "In1.Cu" "In2.Cu" "In3.Cu" "In4.Cu" "In5.Cu" "In6.Cu"
			"In7.Cu" "In8.Cu" "In9.Cu" "In10.Cu" "In11.Cu" "In12.Cu" "In13.Cu" "In14.Cu"
			"In15.Cu" "In16.Cu"
		)
		(hatch none 0.5)
		(connect_pads
			(clearance 0)
		)
		(min_thickness 0.25)
		(keepout
			(tracks not_allowed)
			(vias allowed)
			(pads allowed)
			(copperpour not_allowed)
			(footprints allowed)
		)
		(placement
			(enabled no)
			(sheetname "")
		)
		(fill
			(thermal_gap 0.5)
			(thermal_bridge_width 0.5)
			(island_removal_mode 0)
		)
		(polygon
			(pts
				(arc
					(start 378.657104 -288.005012)
					(mid 378.585115 -287.932853)
					(end 378.48667 -287.90646)
				)
				(arc
					(start 378.48667 -287.90646)
					(mid 378.347476 -287.964116)
					(end 378.28982 -288.10331)
				)
				(arc
					(start 378.28982 -288.10331)
					(mid 378.296577 -288.154191)
					(end 378.316236 -288.201608)
				)
				(arc
					(start 378.785882 -289.015424)
					(mid 378.857871 -289.087583)
					(end 378.956316 -289.113976)
				)
				(arc
					(start 378.956316 -289.113976)
					(mid 379.09551 -289.05632)
					(end 379.153166 -288.917126)
				)
				(arc
					(start 379.153166 -288.917126)
					(mid 379.146409 -288.866245)
					(end 379.12675 -288.818828)
				)
			)
		)
	)
	(zone
		(layers "F.Cu" "B.Cu" "In1.Cu" "In2.Cu" "In3.Cu" "In4.Cu" "In5.Cu" "In6.Cu"
			"In7.Cu" "In8.Cu" "In9.Cu" "In10.Cu" "In11.Cu" "In12.Cu" "In13.Cu" "In14.Cu"
			"In15.Cu" "In16.Cu"
		)
		(hatch none 0.5)
		(connect_pads
			(clearance 0)
		)
		(min_thickness 0.25)
		(keepout
			(tracks not_allowed)
			(vias allowed)
			(pads allowed)
			(copperpour not_allowed)
			(footprints allowed)
		)
		(placement
			(enabled no)
			(sheetname "")
		)
		(fill
			(thermal_gap 0.5)
			(thermal_bridge_width 0.5)
			(island_removal_mode 0)
		)
		(polygon
			(pts
				(arc
					(start 128.837436 -288.005012)
					(mid 128.765447 -287.932853)
					(end 128.667002 -287.90646)
				)
				(arc
					(start 128.667002 -287.90646)
					(mid 128.527808 -287.964116)
					(end 128.470152 -288.10331)
				)
				(arc
					(start 128.470152 -288.10331)
					(mid 128.476909 -288.154191)
					(end 128.496568 -288.201608)
				)
				(arc
					(start 128.966214 -289.015424)
					(mid 129.038203 -289.087583)
					(end 129.136648 -289.113976)
				)
				(arc
					(start 129.136648 -289.113976)
					(mid 129.275842 -289.05632)
					(end 129.333498 -288.917126)
				)
				(arc
					(start 129.333498 -288.917126)
					(mid 129.326741 -288.866245)
					(end 129.307082 -288.818828)
				)
			)
		)
	)
	(zone
		(layers "F.Cu" "B.Cu" "In1.Cu" "In2.Cu" "In3.Cu" "In4.Cu" "In5.Cu" "In6.Cu"
			"In7.Cu" "In8.Cu" "In9.Cu" "In10.Cu" "In11.Cu" "In12.Cu" "In13.Cu" "In14.Cu"
			"In15.Cu" "In16.Cu"
		)
		(hatch none 0.5)
		(connect_pads
			(clearance 0)
		)
		(min_thickness 0.25)
		(keepout
			(tracks not_allowed)
			(vias allowed)
			(pads allowed)
			(copperpour not_allowed)
			(footprints allowed)
		)
		(placement
			(enabled no)
			(sheetname "")
		)
		(fill
			(thermal_gap 0.5)
			(thermal_bridge_width 0.5)
			(island_removal_mode 0)
		)
		(polygon
			(pts
				(arc
					(start 344.243914 -217.162634)
					(mid 344.263598 -217.115224)
					(end 344.27033 -217.064336)
				)
				(arc
					(start 344.27033 -217.064336)
					(mid 344.212674 -216.925142)
					(end 344.07348 -216.867486)
				)
				(arc
					(start 344.07348 -216.867486)
					(mid 343.975049 -216.893902)
					(end 343.903046 -216.966038)
				)
				(arc
					(start 343.4334 -217.780108)
					(mid 343.413716 -217.827518)
					(end 343.406984 -217.878406)
				)
				(arc
					(start 343.406984 -217.878406)
					(mid 343.46464 -218.0176)
					(end 343.603834 -218.075256)
				)
				(arc
					(start 343.603834 -218.075256)
					(mid 343.702265 -218.04884)
					(end 343.774268 -217.976704)
				)
			)
		)
	)
	(zone
		(layers "F.Cu" "B.Cu" "In1.Cu" "In2.Cu" "In3.Cu" "In4.Cu" "In5.Cu" "In6.Cu"
			"In7.Cu" "In8.Cu" "In9.Cu" "In10.Cu" "In11.Cu" "In12.Cu" "In13.Cu" "In14.Cu"
			"In15.Cu" "In16.Cu"
		)
		(hatch none 0.5)
		(connect_pads
			(clearance 0)
		)
		(min_thickness 0.25)
		(keepout
			(tracks not_allowed)
			(vias allowed)
			(pads allowed)
			(copperpour not_allowed)
			(footprints allowed)
		)
		(placement
			(enabled no)
			(sheetname "")
		)
		(fill
			(thermal_gap 0.5)
			(thermal_bridge_width 0.5)
			(island_removal_mode 0)
		)
		(polygon
			(pts
				(arc
					(start 354.270564 -224.389442)
					(mid 353.612704 -224.389442)
					(end 354.270564 -224.389442)
				)
			)
		)
	)
	(zone
		(layers "F.Cu" "B.Cu" "In1.Cu" "In2.Cu" "In3.Cu" "In4.Cu" "In5.Cu" "In6.Cu"
			"In7.Cu" "In8.Cu" "In9.Cu" "In10.Cu" "In11.Cu" "In12.Cu" "In13.Cu" "In14.Cu"
			"In15.Cu" "In16.Cu"
		)
		(hatch none 0.5)
		(connect_pads
			(clearance 0)
		)
		(min_thickness 0.25)
		(keepout
			(tracks not_allowed)
			(vias allowed)
			(pads allowed)
			(copperpour not_allowed)
			(footprints allowed)
		)
		(placement
			(enabled no)
			(sheetname "")
		)
		(fill
			(thermal_gap 0.5)
			(thermal_bridge_width 0.5)
			(island_removal_mode 0)
		)
		(polygon
			(pts
				(arc
					(start 93.928438 -403.502876)
					(mid 93.547438 -403.883876)
					(end 93.928438 -404.264876)
				)
				(arc
					(start 94.792038 -404.264876)
					(mid 95.173038 -403.883876)
					(end 94.792038 -403.502876)
				)
			)
		)
	)
	(zone
		(layers "F.Cu" "B.Cu" "In1.Cu" "In2.Cu" "In3.Cu" "In4.Cu" "In5.Cu" "In6.Cu"
			"In7.Cu" "In8.Cu" "In9.Cu" "In10.Cu" "In11.Cu" "In12.Cu" "In13.Cu" "In14.Cu"
			"In15.Cu" "In16.Cu"
		)
		(hatch none 0.5)
		(connect_pads
			(clearance 0)
		)
		(min_thickness 0.25)
		(keepout
			(tracks not_allowed)
			(vias allowed)
			(pads allowed)
			(copperpour not_allowed)
			(footprints allowed)
		)
		(placement
			(enabled no)
			(sheetname "")
		)
		(fill
			(thermal_gap 0.5)
			(thermal_bridge_width 0.5)
			(island_removal_mode 0)
		)
		(polygon
			(pts
				(xy 467.499954 -421.609012) (xy 467.499954 -416.609022) (xy 467.804754 -416.913822) (xy 467.804754 -421.304212)
			)
		)
	)
	(zone
		(layers "F.Cu" "B.Cu" "In1.Cu" "In2.Cu" "In3.Cu" "In4.Cu" "In5.Cu" "In6.Cu"
			"In7.Cu" "In8.Cu" "In9.Cu" "In10.Cu" "In11.Cu" "In12.Cu" "In13.Cu" "In14.Cu"
			"In15.Cu" "In16.Cu"
		)
		(hatch none 0.5)
		(connect_pads
			(clearance 0)
		)
		(min_thickness 0.25)
		(keepout
			(tracks not_allowed)
			(vias allowed)
			(pads allowed)
			(copperpour not_allowed)
			(footprints allowed)
		)
		(placement
			(enabled no)
			(sheetname "")
		)
		(fill
			(thermal_gap 0.5)
			(thermal_bridge_width 0.5)
			(island_removal_mode 0)
		)
		(polygon
			(pts
				(arc
					(start 362.258864 -218.692222)
					(mid 361.601004 -218.692222)
					(end 362.258864 -218.692222)
				)
			)
		)
	)
	(zone
		(layers "F.Cu" "B.Cu" "In1.Cu" "In2.Cu" "In3.Cu" "In4.Cu" "In5.Cu" "In6.Cu"
			"In7.Cu" "In8.Cu" "In9.Cu" "In10.Cu" "In11.Cu" "In12.Cu" "In13.Cu" "In14.Cu"
			"In15.Cu" "In16.Cu"
		)
		(hatch none 0.5)
		(connect_pads
			(clearance 0)
		)
		(min_thickness 0.25)
		(keepout
			(tracks not_allowed)
			(vias allowed)
			(pads allowed)
			(copperpour not_allowed)
			(footprints allowed)
		)
		(placement
			(enabled no)
			(sheetname "")
		)
		(fill
			(thermal_gap 0.5)
			(thermal_bridge_width 0.5)
			(island_removal_mode 0)
		)
		(polygon
			(pts
				(arc
					(start 103.980742 -223.575626)
					(mid 103.322882 -223.575626)
					(end 103.980742 -223.575626)
				)
			)
		)
	)
	(zone
		(layers "F.Cu" "B.Cu" "In1.Cu" "In2.Cu" "In3.Cu" "In4.Cu" "In5.Cu" "In6.Cu"
			"In7.Cu" "In8.Cu" "In9.Cu" "In10.Cu" "In11.Cu" "In12.Cu" "In13.Cu" "In14.Cu"
			"In15.Cu" "In16.Cu"
		)
		(hatch none 0.5)
		(connect_pads
			(clearance 0)
		)
		(min_thickness 0.25)
		(keepout
			(tracks not_allowed)
			(vias allowed)
			(pads allowed)
			(copperpour not_allowed)
			(footprints allowed)
		)
		(placement
			(enabled no)
			(sheetname "")
		)
		(fill
			(thermal_gap 0.5)
			(thermal_bridge_width 0.5)
			(island_removal_mode 0)
		)
		(polygon
			(pts
				(arc
					(start 98.623882 -215.436704)
					(mid 99.281742 -215.436704)
					(end 98.623882 -215.436704)
				)
			)
		)
	)
	(zone
		(layers "F.Cu" "B.Cu" "In1.Cu" "In2.Cu" "In3.Cu" "In4.Cu" "In5.Cu" "In6.Cu"
			"In7.Cu" "In8.Cu" "In9.Cu" "In10.Cu" "In11.Cu" "In12.Cu" "In13.Cu" "In14.Cu"
			"In15.Cu" "In16.Cu"
		)
		(hatch none 0.5)
		(connect_pads
			(clearance 0)
		)
		(min_thickness 0.25)
		(keepout
			(tracks not_allowed)
			(vias allowed)
			(pads allowed)
			(copperpour not_allowed)
			(footprints allowed)
		)
		(placement
			(enabled no)
			(sheetname "")
		)
		(fill
			(thermal_gap 0.5)
			(thermal_bridge_width 0.5)
			(island_removal_mode 0)
		)
		(polygon
			(pts
				(arc
					(start 374.946164 -224.389442)
					(mid 374.288304 -224.389442)
					(end 374.946164 -224.389442)
				)
			)
		)
	)
	(zone
		(layers "F.Cu" "B.Cu" "In1.Cu" "In2.Cu" "In3.Cu" "In4.Cu" "In5.Cu" "In6.Cu"
			"In7.Cu" "In8.Cu" "In9.Cu" "In10.Cu" "In11.Cu" "In12.Cu" "In13.Cu" "In14.Cu"
			"In15.Cu" "In16.Cu"
		)
		(hatch none 0.5)
		(connect_pads
			(clearance 0)
		)
		(min_thickness 0.25)
		(keepout
			(tracks not_allowed)
			(vias allowed)
			(pads allowed)
			(copperpour not_allowed)
			(footprints allowed)
		)
		(placement
			(enabled no)
			(sheetname "")
		)
		(fill
			(thermal_gap 0.5)
			(thermal_bridge_width 0.5)
			(island_removal_mode 0)
		)
		(polygon
			(pts
				(arc
					(start 369.417346 -284.847538)
					(mid 368.759486 -284.847538)
					(end 369.417346 -284.847538)
				)
			)
		)
	)
	(zone
		(layers "F.Cu" "B.Cu" "In1.Cu" "In2.Cu" "In3.Cu" "In4.Cu" "In5.Cu" "In6.Cu"
			"In7.Cu" "In8.Cu" "In9.Cu" "In10.Cu" "In11.Cu" "In12.Cu" "In13.Cu" "In14.Cu"
			"In15.Cu" "In16.Cu"
		)
		(hatch none 0.5)
		(connect_pads
			(clearance 0)
		)
		(min_thickness 0.25)
		(keepout
			(tracks not_allowed)
			(vias allowed)
			(pads allowed)
			(copperpour not_allowed)
			(footprints allowed)
		)
		(placement
			(enabled no)
			(sheetname "")
		)
		(fill
			(thermal_gap 0.5)
			(thermal_bridge_width 0.5)
			(island_removal_mode 0)
		)
		(polygon
			(pts
				(arc
					(start 371.028468 -224.291144)
					(mid 370.956479 -224.218985)
					(end 370.858034 -224.192592)
				)
				(arc
					(start 370.858034 -224.192592)
					(mid 370.71884 -224.250248)
					(end 370.661184 -224.389442)
				)
				(arc
					(start 370.661184 -224.389442)
					(mid 370.667941 -224.440323)
					(end 370.6876 -224.48774)
				)
				(arc
					(start 371.157246 -225.301556)
					(mid 371.229235 -225.373715)
					(end 371.32768 -225.400108)
				)
				(arc
					(start 371.32768 -225.400108)
					(mid 371.466874 -225.342452)
					(end 371.52453 -225.203258)
				)
				(arc
					(start 371.52453 -225.203258)
					(mid 371.517773 -225.152377)
					(end 371.498114 -225.10496)
				)
			)
		)
	)
	(zone
		(layers "F.Cu" "B.Cu" "In1.Cu" "In2.Cu" "In3.Cu" "In4.Cu" "In5.Cu" "In6.Cu"
			"In7.Cu" "In8.Cu" "In9.Cu" "In10.Cu" "In11.Cu" "In12.Cu" "In13.Cu" "In14.Cu"
			"In15.Cu" "In16.Cu"
		)
		(hatch none 0.5)
		(connect_pads
			(clearance 0)
		)
		(min_thickness 0.25)
		(keepout
			(tracks not_allowed)
			(vias allowed)
			(pads allowed)
			(copperpour not_allowed)
			(footprints allowed)
		)
		(placement
			(enabled no)
			(sheetname "")
		)
		(fill
			(thermal_gap 0.5)
			(thermal_bridge_width 0.5)
			(island_removal_mode 0)
		)
		(polygon
			(pts
				(arc
					(start 98.812096 -221.133924)
					(mid 98.154236 -221.133924)
					(end 98.812096 -221.133924)
				)
			)
		)
	)
	(zone
		(layers "F.Cu" "B.Cu" "In1.Cu" "In2.Cu" "In3.Cu" "In4.Cu" "In5.Cu" "In6.Cu"
			"In7.Cu" "In8.Cu" "In9.Cu" "In10.Cu" "In11.Cu" "In12.Cu" "In13.Cu" "In14.Cu"
			"In15.Cu" "In16.Cu"
		)
		(hatch none 0.5)
		(connect_pads
			(clearance 0)
		)
		(min_thickness 0.25)
		(keepout
			(tracks not_allowed)
			(vias allowed)
			(pads allowed)
			(copperpour not_allowed)
			(footprints allowed)
		)
		(placement
			(enabled no)
			(sheetname "")
		)
		(fill
			(thermal_gap 0.5)
			(thermal_bridge_width 0.5)
			(island_removal_mode 0)
		)
		(polygon
			(pts
				(arc
					(start 374.946164 -217.878406)
					(mid 374.288304 -217.878406)
					(end 374.946164 -217.878406)
				)
			)
		)
	)
	(zone
		(layers "F.Cu" "B.Cu" "In1.Cu" "In2.Cu" "In3.Cu" "In4.Cu" "In5.Cu" "In6.Cu"
			"In7.Cu" "In8.Cu" "In9.Cu" "In10.Cu" "In11.Cu" "In12.Cu" "In13.Cu" "In14.Cu"
			"In15.Cu" "In16.Cu"
		)
		(hatch none 0.5)
		(connect_pads
			(clearance 0)
		)
		(min_thickness 0.25)
		(keepout
			(tracks not_allowed)
			(vias allowed)
			(pads allowed)
			(copperpour not_allowed)
			(footprints allowed)
		)
		(placement
			(enabled no)
			(sheetname "")
		)
		(fill
			(thermal_gap 0.5)
			(thermal_bridge_width 0.5)
			(island_removal_mode 0)
		)
		(polygon
			(pts
				(arc
					(start 370.558822 -216.966292)
					(mid 370.486833 -216.894133)
					(end 370.388388 -216.86774)
				)
				(arc
					(start 370.388388 -216.86774)
					(mid 370.249194 -216.925396)
					(end 370.191538 -217.06459)
				)
				(arc
					(start 370.191538 -217.06459)
					(mid 370.198295 -217.115471)
					(end 370.217954 -217.162888)
				)
				(arc
					(start 370.6876 -217.976704)
					(mid 370.759589 -218.048863)
					(end 370.858034 -218.075256)
				)
				(arc
					(start 370.858034 -218.075256)
					(mid 370.997228 -218.0176)
					(end 371.054884 -217.878406)
				)
				(arc
					(start 371.054884 -217.878406)
					(mid 371.048127 -217.827525)
					(end 371.028468 -217.780108)
				)
			)
		)
	)
	(zone
		(layers "F.Cu" "B.Cu" "In1.Cu" "In2.Cu" "In3.Cu" "In4.Cu" "In5.Cu" "In6.Cu"
			"In7.Cu" "In8.Cu" "In9.Cu" "In10.Cu" "In11.Cu" "In12.Cu" "In13.Cu" "In14.Cu"
			"In15.Cu" "In16.Cu"
		)
		(hatch none 0.5)
		(connect_pads
			(clearance 0)
		)
		(min_thickness 0.25)
		(keepout
			(tracks not_allowed)
			(vias allowed)
			(pads allowed)
			(copperpour not_allowed)
			(footprints allowed)
		)
		(placement
			(enabled no)
			(sheetname "")
		)
		(fill
			(thermal_gap 0.5)
			(thermal_bridge_width 0.5)
			(island_removal_mode 0)
		)
		(polygon
			(pts
				(arc
					(start 104.842818 -279.964134)
					(mid 105.500678 -279.964134)
					(end 104.842818 -279.964134)
				)
			)
		)
	)
	(zone
		(layers "F.Cu" "B.Cu" "In1.Cu" "In2.Cu" "In3.Cu" "In4.Cu" "In5.Cu" "In6.Cu"
			"In7.Cu" "In8.Cu" "In9.Cu" "In10.Cu" "In11.Cu" "In12.Cu" "In13.Cu" "In14.Cu"
			"In15.Cu" "In16.Cu"
		)
		(hatch none 0.5)
		(connect_pads
			(clearance 0)
		)
		(min_thickness 0.25)
		(keepout
			(tracks not_allowed)
			(vias allowed)
			(pads allowed)
			(copperpour not_allowed)
			(footprints allowed)
		)
		(placement
			(enabled no)
			(sheetname "")
		)
		(fill
			(thermal_gap 0.5)
			(thermal_bridge_width 0.5)
			(island_removal_mode 0)
		)
		(polygon
			(pts
				(arc
					(start 340.738968 -400.477228)
					(mid 340.357968 -400.858228)
					(end 340.738968 -401.239228)
				)
				(arc
					(start 341.602568 -401.239228)
					(mid 341.983568 -400.858228)
					(end 341.602568 -400.477228)
				)
			)
		)
	)
	(zone
		(layers "F.Cu" "B.Cu" "In1.Cu" "In2.Cu" "In3.Cu" "In4.Cu" "In5.Cu" "In6.Cu"
			"In7.Cu" "In8.Cu" "In9.Cu" "In10.Cu" "In11.Cu" "In12.Cu" "In13.Cu" "In14.Cu"
			"In15.Cu" "In16.Cu"
		)
		(hatch none 0.5)
		(connect_pads
			(clearance 0)
		)
		(min_thickness 0.25)
		(keepout
			(tracks not_allowed)
			(vias allowed)
			(pads allowed)
			(copperpour not_allowed)
			(footprints allowed)
		)
		(placement
			(enabled no)
			(sheetname "")
		)
		(fill
			(thermal_gap 0.5)
			(thermal_bridge_width 0.5)
			(island_removal_mode 0)
		)
		(polygon
			(pts
				(arc
					(start 383.514346 -288.103056)
					(mid 382.856486 -288.103056)
					(end 383.514346 -288.103056)
				)
			)
		)
	)
	(zone
		(layers "F.Cu" "B.Cu" "In1.Cu" "In2.Cu" "In3.Cu" "In4.Cu" "In5.Cu" "In6.Cu"
			"In7.Cu" "In8.Cu" "In9.Cu" "In10.Cu" "In11.Cu" "In12.Cu" "In13.Cu" "In14.Cu"
			"In15.Cu" "In16.Cu"
		)
		(hatch none 0.5)
		(connect_pads
			(clearance 0)
		)
		(min_thickness 0.25)
		(keepout
			(tracks not_allowed)
			(vias allowed)
			(pads allowed)
			(copperpour not_allowed)
			(footprints allowed)
		)
		(placement
			(enabled no)
			(sheetname "")
		)
		(fill
			(thermal_gap 0.5)
			(thermal_bridge_width 0.5)
			(island_removal_mode 0)
		)
		(polygon
			(pts
				(arc
					(start 345.812364 -221.133924)
					(mid 345.154504 -221.133924)
					(end 345.812364 -221.133924)
				)
			)
		)
	)
	(zone
		(layers "F.Cu" "B.Cu" "In1.Cu" "In2.Cu" "In3.Cu" "In4.Cu" "In5.Cu" "In6.Cu"
			"In7.Cu" "In8.Cu" "In9.Cu" "In10.Cu" "In11.Cu" "In12.Cu" "In13.Cu" "In14.Cu"
			"In15.Cu" "In16.Cu"
		)
		(hatch none 0.5)
		(connect_pads
			(clearance 0)
		)
		(min_thickness 0.25)
		(keepout
			(tracks not_allowed)
			(vias allowed)
			(pads allowed)
			(copperpour not_allowed)
			(footprints allowed)
		)
		(placement
			(enabled no)
			(sheetname "")
		)
		(fill
			(thermal_gap 0.5)
			(thermal_bridge_width 0.5)
			(island_removal_mode 0)
		)
		(polygon
			(pts
				(arc
					(start 96.883728 -279.865836)
					(mid 96.811739 -279.793677)
					(end 96.713294 -279.767284)
				)
				(arc
					(start 96.713294 -279.767284)
					(mid 96.5741 -279.82494)
					(end 96.516444 -279.964134)
				)
				(arc
					(start 96.516444 -279.964134)
					(mid 96.523201 -280.015015)
					(end 96.54286 -280.062432)
				)
				(arc
					(start 97.01276 -280.876502)
					(mid 97.084749 -280.948661)
					(end 97.183194 -280.975054)
				)
				(arc
					(start 97.183194 -280.975054)
					(mid 97.322388 -280.917398)
					(end 97.380044 -280.778204)
				)
				(arc
					(start 97.380044 -280.778204)
					(mid 97.373287 -280.727323)
					(end 97.353628 -280.679906)
				)
			)
		)
	)
	(zone
		(layers "F.Cu" "B.Cu" "In1.Cu" "In2.Cu" "In3.Cu" "In4.Cu" "In5.Cu" "In6.Cu"
			"In7.Cu" "In8.Cu" "In9.Cu" "In10.Cu" "In11.Cu" "In12.Cu" "In13.Cu" "In14.Cu"
			"In15.Cu" "In16.Cu"
		)
		(hatch none 0.5)
		(connect_pads
			(clearance 0)
		)
		(min_thickness 0.25)
		(keepout
			(tracks not_allowed)
			(vias allowed)
			(pads allowed)
			(copperpour not_allowed)
			(footprints allowed)
		)
		(placement
			(enabled no)
			(sheetname "")
		)
		(fill
			(thermal_gap 0.5)
			(thermal_bridge_width 0.5)
			(island_removal_mode 0)
		)
		(polygon
			(pts
				(arc
					(start 109.901482 -215.436704)
					(mid 110.559342 -215.436704)
					(end 109.901482 -215.436704)
				)
			)
		)
	)
	(zone
		(layers "F.Cu" "B.Cu" "In1.Cu" "In2.Cu" "In3.Cu" "In4.Cu" "In5.Cu" "In6.Cu"
			"In7.Cu" "In8.Cu" "In9.Cu" "In10.Cu" "In11.Cu" "In12.Cu" "In13.Cu" "In14.Cu"
			"In15.Cu" "In16.Cu"
		)
		(hatch none 0.5)
		(connect_pads
			(clearance 0)
		)
		(min_thickness 0.25)
		(keepout
			(tracks not_allowed)
			(vias allowed)
			(pads allowed)
			(copperpour not_allowed)
			(footprints allowed)
		)
		(placement
			(enabled no)
			(sheetname "")
		)
		(fill
			(thermal_gap 0.5)
			(thermal_bridge_width 0.5)
			(island_removal_mode 0)
		)
		(polygon
			(pts
				(arc
					(start 133.425692 -214.720932)
					(mid 133.445376 -214.673522)
					(end 133.452108 -214.622634)
				)
				(arc
					(start 133.452108 -214.622634)
					(mid 133.394452 -214.48344)
					(end 133.255258 -214.425784)
				)
				(arc
					(start 133.255258 -214.425784)
					(mid 133.156827 -214.4522)
					(end 133.084824 -214.524336)
				)
				(arc
					(start 132.615178 -215.338406)
					(mid 132.595494 -215.385816)
					(end 132.588762 -215.436704)
				)
				(arc
					(start 132.588762 -215.436704)
					(mid 132.646418 -215.575898)
					(end 132.785612 -215.633554)
				)
				(arc
					(start 132.785612 -215.633554)
					(mid 132.884043 -215.607138)
					(end 132.956046 -215.535002)
				)
			)
		)
	)
	(zone
		(layers "F.Cu" "B.Cu" "In1.Cu" "In2.Cu" "In3.Cu" "In4.Cu" "In5.Cu" "In6.Cu"
			"In7.Cu" "In8.Cu" "In9.Cu" "In10.Cu" "In11.Cu" "In12.Cu" "In13.Cu" "In14.Cu"
			"In15.Cu" "In16.Cu"
		)
		(hatch none 0.5)
		(connect_pads
			(clearance 0)
		)
		(min_thickness 0.25)
		(keepout
			(tracks not_allowed)
			(vias allowed)
			(pads allowed)
			(copperpour not_allowed)
			(footprints allowed)
		)
		(placement
			(enabled no)
			(sheetname "")
		)
		(fill
			(thermal_gap 0.5)
			(thermal_bridge_width 0.5)
			(island_removal_mode 0)
		)
		(polygon
			(pts
				(arc
					(start 113.220246 -223.67367)
					(mid 113.23993 -223.62626)
					(end 113.246662 -223.575372)
				)
				(arc
					(start 113.246662 -223.575372)
					(mid 113.189006 -223.436178)
					(end 113.049812 -223.378522)
				)
				(arc
					(start 113.049812 -223.378522)
					(mid 112.951381 -223.404938)
					(end 112.879378 -223.477074)
				)
				(arc
					(start 112.409732 -224.291144)
					(mid 112.390048 -224.338554)
					(end 112.383316 -224.389442)
				)
				(arc
					(start 112.383316 -224.389442)
					(mid 112.440972 -224.528636)
					(end 112.580166 -224.586292)
				)
				(arc
					(start 112.580166 -224.586292)
					(mid 112.678597 -224.559876)
					(end 112.7506 -224.48774)
				)
			)
		)
	)
	(zone
		(layers "F.Cu" "B.Cu" "In1.Cu" "In2.Cu" "In3.Cu" "In4.Cu" "In5.Cu" "In6.Cu"
			"In7.Cu" "In8.Cu" "In9.Cu" "In10.Cu" "In11.Cu" "In12.Cu" "In13.Cu" "In14.Cu"
			"In15.Cu" "In16.Cu"
		)
		(hatch none 0.5)
		(connect_pads
			(clearance 0)
		)
		(min_thickness 0.25)
		(keepout
			(tracks not_allowed)
			(vias allowed)
			(pads allowed)
			(copperpour not_allowed)
			(footprints allowed)
		)
		(placement
			(enabled no)
			(sheetname "")
		)
		(fill
			(thermal_gap 0.5)
			(thermal_bridge_width 0.5)
			(island_removal_mode 0)
		)
		(polygon
			(pts
				(arc
					(start 125.596142 -225.203258)
					(mid 124.938282 -225.203258)
					(end 125.596142 -225.203258)
				)
			)
		)
	)
	(zone
		(layers "F.Cu" "B.Cu" "In1.Cu" "In2.Cu" "In3.Cu" "In4.Cu" "In5.Cu" "In6.Cu"
			"In7.Cu" "In8.Cu" "In9.Cu" "In10.Cu" "In11.Cu" "In12.Cu" "In13.Cu" "In14.Cu"
			"In15.Cu" "In16.Cu"
		)
		(hatch none 0.5)
		(connect_pads
			(clearance 0)
		)
		(min_thickness 0.25)
		(keepout
			(tracks not_allowed)
			(vias allowed)
			(pads allowed)
			(copperpour not_allowed)
			(footprints allowed)
		)
		(placement
			(enabled no)
			(sheetname "")
		)
		(fill
			(thermal_gap 0.5)
			(thermal_bridge_width 0.5)
			(island_removal_mode 0)
		)
		(polygon
			(pts
				(arc
					(start 377.60656 -217.97645)
					(mid 377.626244 -217.92904)
					(end 377.632976 -217.878152)
				)
				(arc
					(start 377.632976 -217.878152)
					(mid 377.57532 -217.738958)
					(end 377.436126 -217.681302)
				)
				(arc
					(start 377.436126 -217.681302)
					(mid 377.337695 -217.707718)
					(end 377.265692 -217.779854)
				)
				(arc
					(start 376.796046 -218.593924)
					(mid 376.776362 -218.641334)
					(end 376.76963 -218.692222)
				)
				(arc
					(start 376.76963 -218.692222)
					(mid 376.827286 -218.831416)
					(end 376.96648 -218.889072)
				)
				(arc
					(start 376.96648 -218.889072)
					(mid 377.064911 -218.862656)
					(end 377.136914 -218.79052)
				)
			)
		)
	)
	(zone
		(layers "F.Cu" "B.Cu" "In1.Cu" "In2.Cu" "In3.Cu" "In4.Cu" "In5.Cu" "In6.Cu"
			"In7.Cu" "In8.Cu" "In9.Cu" "In10.Cu" "In11.Cu" "In12.Cu" "In13.Cu" "In14.Cu"
			"In15.Cu" "In16.Cu"
		)
		(hatch none 0.5)
		(connect_pads
			(clearance 0)
		)
		(min_thickness 0.25)
		(keepout
			(tracks not_allowed)
			(vias allowed)
			(pads allowed)
			(copperpour not_allowed)
			(footprints allowed)
		)
		(placement
			(enabled no)
			(sheetname "")
		)
		(fill
			(thermal_gap 0.5)
			(thermal_bridge_width 0.5)
			(island_removal_mode 0)
		)
		(polygon
			(pts
				(arc
					(start 381.93853 -289.003232)
					(mid 381.954454 -288.961481)
					(end 381.959866 -288.917126)
				)
				(arc
					(start 381.959866 -288.917126)
					(mid 381.90593 -288.786912)
					(end 381.775716 -288.732976)
				)
				(arc
					(start 381.775716 -288.732976)
					(mid 381.680696 -288.759384)
					(end 381.612902 -288.83102)
				)
				(arc
					(start 381.142748 -289.721036)
					(mid 381.126824 -289.762787)
					(end 381.121412 -289.807142)
				)
				(arc
					(start 381.121412 -289.807142)
					(mid 381.175348 -289.937356)
					(end 381.305562 -289.991292)
				)
				(arc
					(start 381.305562 -289.991292)
					(mid 381.400582 -289.964884)
					(end 381.468376 -289.893248)
				)
			)
		)
	)
	(zone
		(layers "F.Cu" "B.Cu" "In1.Cu" "In2.Cu" "In3.Cu" "In4.Cu" "In5.Cu" "In6.Cu"
			"In7.Cu" "In8.Cu" "In9.Cu" "In10.Cu" "In11.Cu" "In12.Cu" "In13.Cu" "In14.Cu"
			"In15.Cu" "In16.Cu"
		)
		(hatch none 0.5)
		(connect_pads
			(clearance 0)
		)
		(min_thickness 0.25)
		(keepout
			(tracks not_allowed)
			(vias allowed)
			(pads allowed)
			(copperpour not_allowed)
			(footprints allowed)
		)
		(placement
			(enabled no)
			(sheetname "")
		)
		(fill
			(thermal_gap 0.5)
			(thermal_bridge_width 0.5)
			(island_removal_mode 0)
		)
		(polygon
			(pts
				(arc
					(start 70.1421 -420.760398)
					(mid 70.164418 -420.81428)
					(end 70.2183 -420.836598)
				)
				(arc
					(start 71.1581 -420.836598)
					(mid 71.211982 -420.81428)
					(end 71.2343 -420.760398)
				)
				(arc
					(start 71.2343 -418.218874)
					(mid 71.211982 -418.164992)
					(end 71.1581 -418.142674)
				)
				(arc
					(start 70.2183 -418.142674)
					(mid 70.164418 -418.164992)
					(end 70.1421 -418.218874)
				)
			)
		)
	)
	(zone
		(layers "F.Cu" "B.Cu" "In1.Cu" "In2.Cu" "In3.Cu" "In4.Cu" "In5.Cu" "In6.Cu"
			"In7.Cu" "In8.Cu" "In9.Cu" "In10.Cu" "In11.Cu" "In12.Cu" "In13.Cu" "In14.Cu"
			"In15.Cu" "In16.Cu"
		)
		(hatch none 0.5)
		(connect_pads
			(clearance 0)
		)
		(min_thickness 0.25)
		(keepout
			(tracks not_allowed)
			(vias allowed)
			(pads allowed)
			(copperpour not_allowed)
			(footprints allowed)
		)
		(placement
			(enabled no)
			(sheetname "")
		)
		(fill
			(thermal_gap 0.5)
			(thermal_bridge_width 0.5)
			(island_removal_mode 0)
		)
		(polygon
			(pts
				(arc
					(start 345.148408 -406.62352)
					(mid 344.767408 -407.00452)
					(end 345.148408 -407.38552)
				)
				(arc
					(start 346.012008 -407.38552)
					(mid 346.393008 -407.00452)
					(end 346.012008 -406.62352)
				)
			)
		)
	)
	(zone
		(layers "F.Cu" "B.Cu" "In1.Cu" "In2.Cu" "In3.Cu" "In4.Cu" "In5.Cu" "In6.Cu"
			"In7.Cu" "In8.Cu" "In9.Cu" "In10.Cu" "In11.Cu" "In12.Cu" "In13.Cu" "In14.Cu"
			"In15.Cu" "In16.Cu"
		)
		(hatch none 0.5)
		(connect_pads
			(clearance 0)
		)
		(min_thickness 0.25)
		(keepout
			(tracks not_allowed)
			(vias allowed)
			(pads allowed)
			(copperpour not_allowed)
			(footprints allowed)
		)
		(placement
			(enabled no)
			(sheetname "")
		)
		(fill
			(thermal_gap 0.5)
			(thermal_bridge_width 0.5)
			(island_removal_mode 0)
		)
		(polygon
			(pts
				(arc
					(start 349.211392 -285.661354)
					(mid 348.553532 -285.661354)
					(end 349.211392 -285.661354)
				)
			)
		)
	)
	(zone
		(layers "F.Cu" "B.Cu" "In1.Cu" "In2.Cu" "In3.Cu" "In4.Cu" "In5.Cu" "In6.Cu"
			"In7.Cu" "In8.Cu" "In9.Cu" "In10.Cu" "In11.Cu" "In12.Cu" "In13.Cu" "In14.Cu"
			"In15.Cu" "In16.Cu"
		)
		(hatch none 0.5)
		(connect_pads
			(clearance 0)
		)
		(min_thickness 0.25)
		(keepout
			(tracks not_allowed)
			(vias allowed)
			(pads allowed)
			(copperpour not_allowed)
			(footprints allowed)
		)
		(placement
			(enabled no)
			(sheetname "")
		)
		(fill
			(thermal_gap 0.5)
			(thermal_bridge_width 0.5)
			(island_removal_mode 0)
		)
		(polygon
			(pts
				(arc
					(start 118.077742 -225.203258)
					(mid 117.419882 -225.203258)
					(end 118.077742 -225.203258)
				)
			)
		)
	)
	(zone
		(layers "F.Cu" "B.Cu" "In1.Cu" "In2.Cu" "In3.Cu" "In4.Cu" "In5.Cu" "In6.Cu"
			"In7.Cu" "In8.Cu" "In9.Cu" "In10.Cu" "In11.Cu" "In12.Cu" "In13.Cu" "In14.Cu"
			"In15.Cu" "In16.Cu"
		)
		(hatch none 0.5)
		(connect_pads
			(clearance 0)
		)
		(min_thickness 0.25)
		(keepout
			(tracks not_allowed)
			(vias allowed)
			(pads allowed)
			(copperpour not_allowed)
			(footprints allowed)
		)
		(placement
			(enabled no)
			(sheetname "")
		)
		(fill
			(thermal_gap 0.5)
			(thermal_bridge_width 0.5)
			(island_removal_mode 0)
		)
		(polygon
			(pts
				(arc
					(start 88.865964 -279.964134)
					(mid 89.523824 -279.964134)
					(end 88.865964 -279.964134)
				)
			)
		)
	)
	(zone
		(layers "F.Cu" "B.Cu" "In1.Cu" "In2.Cu" "In3.Cu" "In4.Cu" "In5.Cu" "In6.Cu"
			"In7.Cu" "In8.Cu" "In9.Cu" "In10.Cu" "In11.Cu" "In12.Cu" "In13.Cu" "In14.Cu"
			"In15.Cu" "In16.Cu"
		)
		(hatch none 0.5)
		(connect_pads
			(clearance 0)
		)
		(min_thickness 0.25)
		(keepout
			(tracks not_allowed)
			(vias allowed)
			(pads allowed)
			(copperpour not_allowed)
			(footprints allowed)
		)
		(placement
			(enabled no)
			(sheetname "")
		)
		(fill
			(thermal_gap 0.5)
			(thermal_bridge_width 0.5)
			(island_removal_mode 0)
		)
		(polygon
			(pts
				(arc
					(start 349.882714 -223.67367)
					(mid 349.902398 -223.62626)
					(end 349.90913 -223.575372)
				)
				(arc
					(start 349.90913 -223.575372)
					(mid 349.851474 -223.436178)
					(end 349.71228 -223.378522)
				)
				(arc
					(start 349.71228 -223.378522)
					(mid 349.613849 -223.404938)
					(end 349.541846 -223.477074)
				)
				(arc
					(start 349.0722 -224.291144)
					(mid 349.052516 -224.338554)
					(end 349.045784 -224.389442)
				)
				(arc
					(start 349.045784 -224.389442)
					(mid 349.10344 -224.528636)
					(end 349.242634 -224.586292)
				)
				(arc
					(start 349.242634 -224.586292)
					(mid 349.341065 -224.559876)
					(end 349.413068 -224.48774)
				)
			)
		)
	)
	(zone
		(layers "F.Cu" "B.Cu" "In1.Cu" "In2.Cu" "In3.Cu" "In4.Cu" "In5.Cu" "In6.Cu"
			"In7.Cu" "In8.Cu" "In9.Cu" "In10.Cu" "In11.Cu" "In12.Cu" "In13.Cu" "In14.Cu"
			"In15.Cu" "In16.Cu"
		)
		(hatch none 0.5)
		(connect_pads
			(clearance 0)
		)
		(min_thickness 0.25)
		(keepout
			(tracks not_allowed)
			(vias allowed)
			(pads allowed)
			(copperpour not_allowed)
			(footprints allowed)
		)
		(placement
			(enabled no)
			(sheetname "")
		)
		(fill
			(thermal_gap 0.5)
			(thermal_bridge_width 0.5)
			(island_removal_mode 0)
		)
		(polygon
			(pts
				(arc
					(start 356.400862 -277.325582)
					(mid 356.204012 -277.522432)
					(end 356.400862 -277.719282)
				)
				(arc
					(start 357.340662 -277.719282)
					(mid 357.537512 -277.522432)
					(end 357.340662 -277.325582)
				)
			)
		)
	)
	(zone
		(layers "F.Cu" "B.Cu" "In1.Cu" "In2.Cu" "In3.Cu" "In4.Cu" "In5.Cu" "In6.Cu"
			"In7.Cu" "In8.Cu" "In9.Cu" "In10.Cu" "In11.Cu" "In12.Cu" "In13.Cu" "In14.Cu"
			"In15.Cu" "In16.Cu"
		)
		(hatch none 0.5)
		(connect_pads
			(clearance 0)
		)
		(min_thickness 0.25)
		(keepout
			(tracks not_allowed)
			(vias allowed)
			(pads allowed)
			(copperpour not_allowed)
			(footprints allowed)
		)
		(placement
			(enabled no)
			(sheetname "")
		)
		(fill
			(thermal_gap 0.5)
			(thermal_bridge_width 0.5)
			(island_removal_mode 0)
		)
		(polygon
			(pts
				(arc
					(start 342.133428 -285.563056)
					(mid 342.113744 -285.610466)
					(end 342.107012 -285.661354)
				)
				(arc
					(start 342.107012 -285.661354)
					(mid 342.164668 -285.800548)
					(end 342.303862 -285.858204)
				)
				(arc
					(start 342.303862 -285.858204)
					(mid 342.402293 -285.831788)
					(end 342.474296 -285.759652)
				)
				(arc
					(start 342.944196 -284.945582)
					(mid 342.96388 -284.898172)
					(end 342.970612 -284.847284)
				)
				(arc
					(start 342.970612 -284.847284)
					(mid 342.912956 -284.70809)
					(end 342.773762 -284.650434)
				)
				(arc
					(start 342.773762 -284.650434)
					(mid 342.675331 -284.67685)
					(end 342.603328 -284.748986)
				)
			)
		)
	)
	(zone
		(layers "F.Cu" "B.Cu" "In1.Cu" "In2.Cu" "In3.Cu" "In4.Cu" "In5.Cu" "In6.Cu"
			"In7.Cu" "In8.Cu" "In9.Cu" "In10.Cu" "In11.Cu" "In12.Cu" "In13.Cu" "In14.Cu"
			"In15.Cu" "In16.Cu"
		)
		(hatch none 0.5)
		(connect_pads
			(clearance 0)
		)
		(min_thickness 0.25)
		(keepout
			(tracks not_allowed)
			(vias allowed)
			(pads allowed)
			(copperpour not_allowed)
			(footprints allowed)
		)
		(placement
			(enabled no)
			(sheetname "")
		)
		(fill
			(thermal_gap 0.5)
			(thermal_bridge_width 0.5)
			(island_removal_mode 0)
		)
		(polygon
			(pts
				(arc
					(start 114.600482 -220.319854)
					(mid 115.258342 -220.319854)
					(end 114.600482 -220.319854)
				)
			)
		)
	)
	(zone
		(layers "F.Cu" "B.Cu" "In1.Cu" "In2.Cu" "In3.Cu" "In4.Cu" "In5.Cu" "In6.Cu"
			"In7.Cu" "In8.Cu" "In9.Cu" "In10.Cu" "In11.Cu" "In12.Cu" "In13.Cu" "In14.Cu"
			"In15.Cu" "In16.Cu"
		)
		(hatch none 0.5)
		(connect_pads
			(clearance 0)
		)
		(min_thickness 0.25)
		(keepout
			(tracks not_allowed)
			(vias allowed)
			(pads allowed)
			(copperpour not_allowed)
			(footprints allowed)
		)
		(placement
			(enabled no)
			(sheetname "")
		)
		(fill
			(thermal_gap 0.5)
			(thermal_bridge_width 0.5)
			(island_removal_mode 0)
		)
		(polygon
			(pts
				(arc
					(start 116.979446 -223.67367)
					(mid 116.99913 -223.62626)
					(end 117.005862 -223.575372)
				)
				(arc
					(start 117.005862 -223.575372)
					(mid 116.948206 -223.436178)
					(end 116.809012 -223.378522)
				)
				(arc
					(start 116.809012 -223.378522)
					(mid 116.710581 -223.404938)
					(end 116.638578 -223.477074)
				)
				(arc
					(start 116.168932 -224.291144)
					(mid 116.149248 -224.338554)
					(end 116.142516 -224.389442)
				)
				(arc
					(start 116.142516 -224.389442)
					(mid 116.200172 -224.528636)
					(end 116.339366 -224.586292)
				)
				(arc
					(start 116.339366 -224.586292)
					(mid 116.437797 -224.559876)
					(end 116.5098 -224.48774)
				)
			)
		)
	)
	(zone
		(layers "F.Cu" "B.Cu" "In1.Cu" "In2.Cu" "In3.Cu" "In4.Cu" "In5.Cu" "In6.Cu"
			"In7.Cu" "In8.Cu" "In9.Cu" "In10.Cu" "In11.Cu" "In12.Cu" "In13.Cu" "In14.Cu"
			"In15.Cu" "In16.Cu"
		)
		(hatch none 0.5)
		(connect_pads
			(clearance 0)
		)
		(min_thickness 0.25)
		(keepout
			(tracks not_allowed)
			(vias allowed)
			(pads allowed)
			(copperpour not_allowed)
			(footprints allowed)
		)
		(placement
			(enabled no)
			(sheetname "")
		)
		(fill
			(thermal_gap 0.5)
			(thermal_bridge_width 0.5)
			(island_removal_mode 0)
		)
		(polygon
			(pts
				(arc
					(start 371.186964 -224.389442)
					(mid 370.529104 -224.389442)
					(end 371.186964 -224.389442)
				)
			)
		)
	)
	(zone
		(layers "F.Cu" "B.Cu" "In1.Cu" "In2.Cu" "In3.Cu" "In4.Cu" "In5.Cu" "In6.Cu"
			"In7.Cu" "In8.Cu" "In9.Cu" "In10.Cu" "In11.Cu" "In12.Cu" "In13.Cu" "In14.Cu"
			"In15.Cu" "In16.Cu"
		)
		(hatch none 0.5)
		(connect_pads
			(clearance 0)
		)
		(min_thickness 0.25)
		(keepout
			(tracks not_allowed)
			(vias allowed)
			(pads allowed)
			(copperpour not_allowed)
			(footprints allowed)
		)
		(placement
			(enabled no)
			(sheetname "")
		)
		(fill
			(thermal_gap 0.5)
			(thermal_bridge_width 0.5)
			(island_removal_mode 0)
		)
		(polygon
			(pts
				(arc
					(start 130.137154 -220.22181)
					(mid 130.065165 -220.149651)
					(end 129.96672 -220.123258)
				)
				(arc
					(start 129.96672 -220.123258)
					(mid 129.827526 -220.180914)
					(end 129.76987 -220.320108)
				)
				(arc
					(start 129.76987 -220.320108)
					(mid 129.776627 -220.370989)
					(end 129.796286 -220.418406)
				)
				(arc
					(start 130.265932 -221.232222)
					(mid 130.337921 -221.304381)
					(end 130.436366 -221.330774)
				)
				(arc
					(start 130.436366 -221.330774)
					(mid 130.57556 -221.273118)
					(end 130.633216 -221.133924)
				)
				(arc
					(start 130.633216 -221.133924)
					(mid 130.626459 -221.083043)
					(end 130.6068 -221.035626)
				)
			)
		)
	)
	(zone
		(layers "F.Cu" "B.Cu" "In1.Cu" "In2.Cu" "In3.Cu" "In4.Cu" "In5.Cu" "In6.Cu"
			"In7.Cu" "In8.Cu" "In9.Cu" "In10.Cu" "In11.Cu" "In12.Cu" "In13.Cu" "In14.Cu"
			"In15.Cu" "In16.Cu"
		)
		(hatch none 0.5)
		(connect_pads
			(clearance 0)
		)
		(min_thickness 0.25)
		(keepout
			(tracks not_allowed)
			(vias allowed)
			(pads allowed)
			(copperpour not_allowed)
			(footprints allowed)
		)
		(placement
			(enabled no)
			(sheetname "")
		)
		(fill
			(thermal_gap 0.5)
			(thermal_bridge_width 0.5)
			(island_removal_mode 0)
		)
		(polygon
			(pts
				(arc
					(start 355.514148 -213.646766)
					(mid 355.44644 -213.574915)
					(end 355.351334 -213.548468)
				)
				(arc
					(start 355.351334 -213.548468)
					(mid 355.22112 -213.602404)
					(end 355.167184 -213.732618)
				)
				(arc
					(start 355.167184 -213.732618)
					(mid 355.172635 -213.776839)
					(end 355.18852 -213.81847)
				)
				(arc
					(start 355.657912 -214.708486)
					(mid 355.72562 -214.780337)
					(end 355.820726 -214.806784)
				)
				(arc
					(start 355.820726 -214.806784)
					(mid 355.95094 -214.752848)
					(end 356.004876 -214.622634)
				)
				(arc
					(start 356.004876 -214.622634)
					(mid 355.999425 -214.578413)
					(end 355.98354 -214.536782)
				)
			)
		)
	)
	(zone
		(layers "F.Cu" "B.Cu" "In1.Cu" "In2.Cu" "In3.Cu" "In4.Cu" "In5.Cu" "In6.Cu"
			"In7.Cu" "In8.Cu" "In9.Cu" "In10.Cu" "In11.Cu" "In12.Cu" "In13.Cu" "In14.Cu"
			"In15.Cu" "In16.Cu"
		)
		(hatch none 0.5)
		(connect_pads
			(clearance 0)
		)
		(min_thickness 0.25)
		(keepout
			(tracks not_allowed)
			(vias allowed)
			(pads allowed)
			(copperpour not_allowed)
			(footprints allowed)
		)
		(placement
			(enabled no)
			(sheetname "")
		)
		(fill
			(thermal_gap 0.5)
			(thermal_bridge_width 0.5)
			(island_removal_mode 0)
		)
		(polygon
			(pts
				(arc
					(start 341.223346 -288.103056)
					(mid 340.565486 -288.103056)
					(end 341.223346 -288.103056)
				)
			)
		)
	)
	(zone
		(layers "F.Cu" "B.Cu" "In1.Cu" "In2.Cu" "In3.Cu" "In4.Cu" "In5.Cu" "In6.Cu"
			"In7.Cu" "In8.Cu" "In9.Cu" "In10.Cu" "In11.Cu" "In12.Cu" "In13.Cu" "In14.Cu"
			"In15.Cu" "In16.Cu"
		)
		(hatch none 0.5)
		(connect_pads
			(clearance 0)
		)
		(min_thickness 0.25)
		(keepout
			(tracks not_allowed)
			(vias allowed)
			(pads allowed)
			(copperpour not_allowed)
			(footprints allowed)
		)
		(placement
			(enabled no)
			(sheetname "")
		)
		(fill
			(thermal_gap 0.5)
			(thermal_bridge_width 0.5)
			(island_removal_mode 0)
		)
		(polygon
			(pts
				(arc
					(start 388.78764 -25.060148)
					(mid 388.40664 -25.441148)
					(end 388.78764 -25.822148)
				)
				(arc
					(start 389.65124 -25.822148)
					(mid 390.03224 -25.441148)
					(end 389.65124 -25.060148)
				)
			)
		)
	)
	(zone
		(layers "F.Cu" "B.Cu" "In1.Cu" "In2.Cu" "In3.Cu" "In4.Cu" "In8.Cu" "In9.Cu"
			"In10.Cu" "In11.Cu" "In12.Cu" "In13.Cu" "In14.Cu" "In15.Cu" "In16.Cu"
		)
		(hatch none 0.5)
		(connect_pads
			(clearance 0)
		)
		(min_thickness 0.25)
		(keepout
			(tracks not_allowed)
			(vias allowed)
			(pads allowed)
			(copperpour not_allowed)
			(footprints allowed)
		)
		(placement
			(enabled no)
			(sheetname "")
		)
		(fill yes
			(thermal_gap 0.5)
			(thermal_bridge_width 0.5)
			(island_removal_mode 0)
		)
		(polygon
			(pts
				(arc
					(start 92.985082 -225.203258)
					(mid 93.314012 -225.532188)
					(end 93.642942 -225.203258)
				)
				(arc
					(start 93.642942 -225.203258)
					(mid 93.559872 -224.984746)
					(end 93.35262 -224.876614)
				)
				(arc
					(start 93.146626 -224.51949)
					(mid 93.166548 -224.456075)
					(end 93.173296 -224.38995)
				)
				(arc
					(start 93.173296 -224.389442)
					(mid 92.844366 -224.060512)
					(end 92.515436 -224.389442)
				)
				(arc
					(start 92.515436 -224.389442)
					(mid 92.598506 -224.607954)
					(end 92.805758 -224.716086)
				)
				(arc
					(start 93.011752 -225.07321)
					(mid 92.991779 -225.136874)
					(end 92.985082 -225.203258)
				)
			)
		)
	)
	(zone
		(layers "F.Cu" "B.Cu" "In1.Cu" "In2.Cu" "In3.Cu" "In4.Cu" "In8.Cu" "In9.Cu"
			"In10.Cu" "In11.Cu" "In12.Cu" "In13.Cu" "In14.Cu" "In15.Cu" "In16.Cu"
		)
		(hatch none 0.5)
		(connect_pads
			(clearance 0)
		)
		(min_thickness 0.25)
		(keepout
			(tracks not_allowed)
			(vias allowed)
			(pads allowed)
			(copperpour not_allowed)
			(footprints allowed)
		)
		(placement
			(enabled no)
			(sheetname "")
		)
		(fill yes
			(thermal_gap 0.5)
			(thermal_bridge_width 0.5)
			(island_removal_mode 0)
		)
		(polygon
			(pts
				(arc
					(start 339.04555 -225.203258)
					(mid 339.37448 -225.532188)
					(end 339.70341 -225.203258)
				)
				(arc
					(start 339.70341 -225.203258)
					(mid 339.62034 -224.984746)
					(end 339.413088 -224.876614)
				)
				(arc
					(start 339.207094 -224.51949)
					(mid 339.227016 -224.456075)
					(end 339.233764 -224.38995)
				)
				(arc
					(start 339.233764 -224.389442)
					(mid 338.904834 -224.060512)
					(end 338.575904 -224.389442)
				)
				(arc
					(start 338.575904 -224.389442)
					(mid 338.658974 -224.607954)
					(end 338.866226 -224.716086)
				)
				(arc
					(start 339.07222 -225.07321)
					(mid 339.052247 -225.136874)
					(end 339.04555 -225.203258)
				)
			)
		)
	)
	(zone
		(layers "F.Cu" "B.Cu" "In1.Cu" "In2.Cu" "In3.Cu" "In4.Cu" "In8.Cu" "In9.Cu"
			"In10.Cu" "In11.Cu" "In12.Cu" "In13.Cu" "In14.Cu" "In15.Cu" "In16.Cu"
		)
		(hatch none 0.5)
		(connect_pads
			(clearance 0)
		)
		(min_thickness 0.25)
		(keepout
			(tracks not_allowed)
			(vias allowed)
			(pads allowed)
			(copperpour not_allowed)
			(footprints allowed)
		)
		(placement
			(enabled no)
			(sheetname "")
		)
		(fill yes
			(thermal_gap 0.5)
			(thermal_bridge_width 0.5)
			(island_removal_mode 0)
		)
		(polygon
			(pts
				(arc
					(start 91.105482 -225.203258)
					(mid 91.434412 -225.532188)
					(end 91.763342 -225.203258)
				)
				(arc
					(start 91.763342 -225.203258)
					(mid 91.680272 -224.984746)
					(end 91.47302 -224.876614)
				)
				(arc
					(start 91.267026 -224.51949)
					(mid 91.286948 -224.456075)
					(end 91.293696 -224.38995)
				)
				(arc
					(start 91.293696 -224.389442)
					(mid 90.964766 -224.060512)
					(end 90.635836 -224.389442)
				)
				(arc
					(start 90.635836 -224.389442)
					(mid 90.718906 -224.607954)
					(end 90.926158 -224.716086)
				)
				(arc
					(start 91.132152 -225.07321)
					(mid 91.112179 -225.136874)
					(end 91.105482 -225.203258)
				)
			)
		)
	)
	(zone
		(layers "F.Cu" "B.Cu" "In1.Cu" "In2.Cu" "In3.Cu" "In4.Cu" "In8.Cu" "In9.Cu"
			"In10.Cu" "In11.Cu" "In12.Cu" "In13.Cu" "In14.Cu" "In15.Cu" "In16.Cu"
		)
		(hatch none 0.5)
		(connect_pads
			(clearance 0)
		)
		(min_thickness 0.25)
		(keepout
			(tracks not_allowed)
			(vias allowed)
			(pads allowed)
			(copperpour not_allowed)
			(footprints allowed)
		)
		(placement
			(enabled no)
			(sheetname "")
		)
		(fill yes
			(thermal_gap 0.5)
			(thermal_bridge_width 0.5)
			(island_removal_mode 0)
		)
		(polygon
			(pts
				(arc
					(start 89.696036 -224.389442)
					(mid 90.024966 -224.718372)
					(end 90.353896 -224.389442)
				)
				(arc
					(start 90.353896 -224.389442)
					(mid 90.347181 -224.323061)
					(end 90.327226 -224.259394)
				)
				(arc
					(start 90.53322 -223.90227)
					(mid 90.740463 -223.79413)
					(end 90.823542 -223.575626)
				)
				(arc
					(start 90.823542 -223.575626)
					(mid 90.494612 -223.246696)
					(end 90.165682 -223.575626)
				)
				(arc
					(start 90.165682 -223.575626)
					(mid 90.172418 -223.641879)
					(end 90.192352 -223.70542)
				)
				(arc
					(start 89.986358 -224.062798)
					(mid 89.779115 -224.170938)
					(end 89.696036 -224.389442)
				)
			)
		)
	)
	(zone
		(layers "F.Cu" "B.Cu" "In1.Cu" "In2.Cu" "In3.Cu" "In4.Cu" "In8.Cu" "In9.Cu"
			"In10.Cu" "In11.Cu" "In12.Cu" "In13.Cu" "In14.Cu" "In15.Cu" "In16.Cu"
		)
		(hatch none 0.5)
		(connect_pads
			(clearance 0)
		)
		(min_thickness 0.25)
		(keepout
			(tracks not_allowed)
			(vias allowed)
			(pads allowed)
			(copperpour not_allowed)
			(footprints allowed)
		)
		(placement
			(enabled no)
			(sheetname "")
		)
		(fill yes
			(thermal_gap 0.5)
			(thermal_bridge_width 0.5)
			(island_removal_mode 0)
		)
		(polygon
			(pts
				(arc
					(start 340.92515 -225.203258)
					(mid 341.25408 -225.532188)
					(end 341.58301 -225.203258)
				)
				(arc
					(start 341.58301 -225.203258)
					(mid 341.49994 -224.984746)
					(end 341.292688 -224.876614)
				)
				(arc
					(start 341.086694 -224.51949)
					(mid 341.106616 -224.456075)
					(end 341.113364 -224.38995)
				)
				(arc
					(start 341.113364 -224.389442)
					(mid 340.784434 -224.060512)
					(end 340.455504 -224.389442)
				)
				(arc
					(start 340.455504 -224.389442)
					(mid 340.538574 -224.607954)
					(end 340.745826 -224.716086)
				)
				(arc
					(start 340.95182 -225.07321)
					(mid 340.931847 -225.136874)
					(end 340.92515 -225.203258)
				)
			)
		)
	)
	(zone
		(layers "F.Cu" "B.Cu" "In1.Cu" "In2.Cu" "In3.Cu" "In4.Cu" "In8.Cu" "In9.Cu"
			"In10.Cu" "In11.Cu" "In12.Cu" "In13.Cu" "In14.Cu" "In15.Cu" "In16.Cu"
		)
		(hatch none 0.5)
		(connect_pads
			(clearance 0)
		)
		(min_thickness 0.25)
		(keepout
			(tracks not_allowed)
			(vias allowed)
			(pads allowed)
			(copperpour not_allowed)
			(footprints allowed)
		)
		(placement
			(enabled no)
			(sheetname "")
		)
		(fill yes
			(thermal_gap 0.5)
			(thermal_bridge_width 0.5)
			(island_removal_mode 0)
		)
		(polygon
			(pts
				(arc
					(start 337.636104 -224.389442)
					(mid 337.965034 -224.718372)
					(end 338.293964 -224.389442)
				)
				(arc
					(start 338.293964 -224.389442)
					(mid 338.287249 -224.323061)
					(end 338.267294 -224.259394)
				)
				(arc
					(start 338.473288 -223.90227)
					(mid 338.680531 -223.79413)
					(end 338.76361 -223.575626)
				)
				(arc
					(start 338.76361 -223.575626)
					(mid 338.43468 -223.246696)
					(end 338.10575 -223.575626)
				)
				(arc
					(start 338.10575 -223.575626)
					(mid 338.112486 -223.641879)
					(end 338.13242 -223.70542)
				)
				(arc
					(start 337.926426 -224.062798)
					(mid 337.719183 -224.170938)
					(end 337.636104 -224.389442)
				)
			)
		)
	)
	(zone
		(layers "F.Cu" "B.Cu" "In1.Cu" "In2.Cu" "In6.Cu" "In7.Cu" "In8.Cu" "In9.Cu"
			"In10.Cu" "In11.Cu" "In12.Cu" "In13.Cu" "In14.Cu" "In15.Cu" "In16.Cu"
		)
		(hatch none 0.5)
		(connect_pads
			(clearance 0)
		)
		(min_thickness 0.25)
		(keepout
			(tracks not_allowed)
			(vias allowed)
			(pads allowed)
			(copperpour not_allowed)
			(footprints allowed)
		)
		(placement
			(enabled no)
			(sheetname "")
		)
		(fill yes
			(thermal_gap 0.5)
			(thermal_bridge_width 0.5)
			(island_removal_mode 0)
		)
		(polygon
			(pts
				(arc
					(start 87.456264 -285.661354)
					(mid 87.785194 -285.990284)
					(end 88.114124 -285.661354)
				)
				(arc
					(start 88.114124 -285.661354)
					(mid 88.107388 -285.595101)
					(end 88.087454 -285.53156)
				)
				(arc
					(start 88.293702 -285.174182)
					(mid 88.500945 -285.066042)
					(end 88.584024 -284.847538)
				)
				(arc
					(start 88.584024 -284.847538)
					(mid 88.255094 -284.518608)
					(end 87.926164 -284.847538)
				)
				(arc
					(start 87.926164 -284.847538)
					(mid 87.9329 -284.913791)
					(end 87.952834 -284.977332)
				)
				(arc
					(start 87.746586 -285.33471)
					(mid 87.539343 -285.44285)
					(end 87.456264 -285.661354)
				)
			)
		)
	)
	(zone
		(layers "F.Cu" "B.Cu" "In1.Cu" "In2.Cu" "In6.Cu" "In7.Cu" "In8.Cu" "In9.Cu"
			"In10.Cu" "In11.Cu" "In12.Cu" "In13.Cu" "In14.Cu" "In15.Cu" "In16.Cu"
		)
		(hatch none 0.5)
		(connect_pads
			(clearance 0)
		)
		(min_thickness 0.25)
		(keepout
			(tracks not_allowed)
			(vias allowed)
			(pads allowed)
			(copperpour not_allowed)
			(footprints allowed)
		)
		(placement
			(enabled no)
			(sheetname "")
		)
		(fill yes
			(thermal_gap 0.5)
			(thermal_bridge_width 0.5)
			(island_removal_mode 0)
		)
		(polygon
			(pts
				(arc
					(start 92.625164 -281.59202)
					(mid 92.954094 -281.92095)
					(end 93.283024 -281.59202)
				)
				(arc
					(start 93.283024 -281.59202)
					(mid 93.199954 -281.373508)
					(end 92.992702 -281.265376)
				)
				(arc
					(start 92.786454 -280.908252)
					(mid 92.806541 -280.8446)
					(end 92.813378 -280.778204)
				)
				(arc
					(start 92.813378 -280.778204)
					(mid 92.484448 -280.449274)
					(end 92.155518 -280.778204)
				)
				(arc
					(start 92.155518 -280.778204)
					(mid 92.238504 -280.996622)
					(end 92.445586 -281.104848)
				)
				(arc
					(start 92.651834 -281.462226)
					(mid 92.631901 -281.525767)
					(end 92.625164 -281.59202)
				)
			)
		)
	)
	(zone
		(layers "F.Cu" "B.Cu" "In1.Cu" "In2.Cu" "In6.Cu" "In7.Cu" "In8.Cu" "In9.Cu"
			"In10.Cu" "In11.Cu" "In12.Cu" "In13.Cu" "In14.Cu" "In15.Cu" "In16.Cu"
		)
		(hatch none 0.5)
		(connect_pads
			(clearance 0)
		)
		(min_thickness 0.25)
		(keepout
			(tracks not_allowed)
			(vias allowed)
			(pads allowed)
			(copperpour not_allowed)
			(footprints allowed)
		)
		(placement
			(enabled no)
			(sheetname "")
		)
		(fill yes
			(thermal_gap 0.5)
			(thermal_bridge_width 0.5)
			(island_removal_mode 0)
		)
		(polygon
			(pts
				(arc
					(start 382.27635 -221.94774)
					(mid 382.60528 -222.27667)
					(end 382.93421 -221.94774)
				)
				(arc
					(start 382.93421 -221.947232)
					(mid 382.927444 -221.881111)
					(end 382.90754 -221.817692)
				)
				(arc
					(start 383.113534 -221.460568)
					(mid 383.321073 -221.352577)
					(end 383.404364 -221.133924)
				)
				(arc
					(start 383.404364 -221.133924)
					(mid 383.075434 -220.804994)
					(end 382.746504 -221.133924)
				)
				(arc
					(start 382.746504 -221.133924)
					(mid 382.753139 -221.199912)
					(end 382.77292 -221.26321)
				)
				(arc
					(start 382.566672 -221.621096)
					(mid 382.359429 -221.729236)
					(end 382.27635 -221.94774)
				)
			)
		)
	)
	(zone
		(layers "F.Cu" "B.Cu" "In1.Cu" "In2.Cu" "In6.Cu" "In7.Cu" "In8.Cu" "In9.Cu"
			"In10.Cu" "In11.Cu" "In12.Cu" "In13.Cu" "In14.Cu" "In15.Cu" "In16.Cu"
		)
		(hatch none 0.5)
		(connect_pads
			(clearance 0)
		)
		(min_thickness 0.25)
		(keepout
			(tracks not_allowed)
			(vias allowed)
			(pads allowed)
			(copperpour not_allowed)
			(footprints allowed)
		)
		(placement
			(enabled no)
			(sheetname "")
		)
		(fill yes
			(thermal_gap 0.5)
			(thermal_bridge_width 0.5)
			(island_removal_mode 0)
		)
		(polygon
			(pts
				(arc
					(start 378.987304 -224.389442)
					(mid 379.316234 -224.718372)
					(end 379.645164 -224.389442)
				)
				(arc
					(start 379.645164 -224.388934)
					(mid 379.638398 -224.322813)
					(end 379.618494 -224.259394)
				)
				(arc
					(start 379.824488 -223.90227)
					(mid 380.031731 -223.79413)
					(end 380.11481 -223.575626)
				)
				(arc
					(start 380.11481 -223.575626)
					(mid 379.78588 -223.246696)
					(end 379.45695 -223.575626)
				)
				(arc
					(start 379.45695 -223.575626)
					(mid 379.463686 -223.641879)
					(end 379.48362 -223.70542)
				)
				(arc
					(start 379.277626 -224.062798)
					(mid 379.070383 -224.170938)
					(end 378.987304 -224.389442)
				)
			)
		)
	)
	(zone
		(layers "F.Cu" "B.Cu" "In1.Cu" "In2.Cu" "In6.Cu" "In7.Cu" "In8.Cu" "In9.Cu"
			"In10.Cu" "In11.Cu" "In12.Cu" "In13.Cu" "In14.Cu" "In15.Cu" "In16.Cu"
		)
		(hatch none 0.5)
		(connect_pads
			(clearance 0)
		)
		(min_thickness 0.25)
		(keepout
			(tracks not_allowed)
			(vias allowed)
			(pads allowed)
			(copperpour not_allowed)
			(footprints allowed)
		)
		(placement
			(enabled no)
			(sheetname "")
		)
		(fill yes
			(thermal_gap 0.5)
			(thermal_bridge_width 0.5)
			(island_removal_mode 0)
		)
		(polygon
			(pts
				(arc
					(start 382.276604 -225.203258)
					(mid 382.605534 -225.532188)
					(end 382.934464 -225.203258)
				)
				(arc
					(start 382.934464 -225.203258)
					(mid 382.851394 -224.984746)
					(end 382.644142 -224.876614)
				)
				(arc
					(start 382.437894 -224.519236)
					(mid 382.457827 -224.455695)
					(end 382.464564 -224.389442)
				)
				(arc
					(start 382.464564 -224.389442)
					(mid 382.135634 -224.060512)
					(end 381.806704 -224.389442)
				)
				(arc
					(start 381.806704 -224.389442)
					(mid 381.889857 -224.608048)
					(end 382.09728 -224.716086)
				)
				(arc
					(start 382.303274 -225.07321)
					(mid 382.283301 -225.136874)
					(end 382.276604 -225.203258)
				)
			)
		)
	)
	(zone
		(layers "F.Cu" "B.Cu" "In1.Cu" "In2.Cu" "In6.Cu" "In7.Cu" "In8.Cu" "In9.Cu"
			"In10.Cu" "In11.Cu" "In12.Cu" "In13.Cu" "In14.Cu" "In15.Cu" "In16.Cu"
		)
		(hatch none 0.5)
		(connect_pads
			(clearance 0)
		)
		(min_thickness 0.25)
		(keepout
			(tracks not_allowed)
			(vias allowed)
			(pads allowed)
			(copperpour not_allowed)
			(footprints allowed)
		)
		(placement
			(enabled no)
			(sheetname "")
		)
		(fill yes
			(thermal_gap 0.5)
			(thermal_bridge_width 0.5)
			(island_removal_mode 0)
		)
		(polygon
			(pts
				(arc
					(start 132.926836 -224.389442)
					(mid 133.255766 -224.718372)
					(end 133.584696 -224.389442)
				)
				(arc
					(start 133.584696 -224.388934)
					(mid 133.57793 -224.322813)
					(end 133.558026 -224.259394)
				)
				(arc
					(start 133.76402 -223.90227)
					(mid 133.971411 -223.794205)
					(end 134.054596 -223.575626)
				)
				(arc
					(start 134.054596 -223.575626)
					(mid 133.725666 -223.246696)
					(end 133.396736 -223.575626)
				)
				(arc
					(start 133.396736 -223.575626)
					(mid 133.403502 -223.641747)
					(end 133.423406 -223.705166)
				)
				(arc
					(start 133.217158 -224.062798)
					(mid 133.009915 -224.170938)
					(end 132.926836 -224.389442)
				)
			)
		)
	)
	(zone
		(layers "F.Cu" "B.Cu" "In1.Cu" "In2.Cu" "In6.Cu" "In7.Cu" "In8.Cu" "In9.Cu"
			"In10.Cu" "In11.Cu" "In12.Cu" "In13.Cu" "In14.Cu" "In15.Cu" "In16.Cu"
		)
		(hatch none 0.5)
		(connect_pads
			(clearance 0)
		)
		(min_thickness 0.25)
		(keepout
			(tracks not_allowed)
			(vias allowed)
			(pads allowed)
			(copperpour not_allowed)
			(footprints allowed)
		)
		(placement
			(enabled no)
			(sheetname "")
		)
		(fill yes
			(thermal_gap 0.5)
			(thermal_bridge_width 0.5)
			(island_removal_mode 0)
		)
		(polygon
			(pts
				(arc
					(start 337.341718 -282.602686)
					(mid 337.457787 -282.699897)
					(end 337.605116 -282.734766)
				)
				(arc
					(start 337.605116 -282.734766)
					(mid 337.934046 -282.405836)
					(end 337.605116 -282.076906)
				)
				(arc
					(start 337.605116 -282.076906)
					(mid 337.457787 -282.111776)
					(end 337.341718 -282.208986)
				)
				(arc
					(start 336.928714 -282.208986)
					(mid 336.812645 -282.111775)
					(end 336.665316 -282.076906)
				)
				(arc
					(start 336.665316 -282.076906)
					(mid 336.336386 -282.405836)
					(end 336.665316 -282.734766)
				)
				(arc
					(start 336.665316 -282.734766)
					(mid 336.812645 -282.699896)
					(end 336.928714 -282.602686)
				)
			)
		)
	)
	(zone
		(layers "F.Cu" "B.Cu" "In1.Cu" "In2.Cu" "In6.Cu" "In7.Cu" "In8.Cu" "In9.Cu"
			"In10.Cu" "In11.Cu" "In12.Cu" "In13.Cu" "In14.Cu" "In15.Cu" "In16.Cu"
		)
		(hatch none 0.5)
		(connect_pads
			(clearance 0)
		)
		(min_thickness 0.25)
		(keepout
			(tracks not_allowed)
			(vias allowed)
			(pads allowed)
			(copperpour not_allowed)
			(footprints allowed)
		)
		(placement
			(enabled no)
			(sheetname "")
		)
		(fill yes
			(thermal_gap 0.5)
			(thermal_bridge_width 0.5)
			(island_removal_mode 0)
		)
		(polygon
			(pts
				(arc
					(start 335.396332 -285.661354)
					(mid 335.725262 -285.990284)
					(end 336.054192 -285.661354)
				)
				(arc
					(start 336.054192 -285.661354)
					(mid 336.047456 -285.595101)
					(end 336.027522 -285.53156)
				)
				(arc
					(start 336.23377 -285.174182)
					(mid 336.441013 -285.066042)
					(end 336.524092 -284.847538)
				)
				(arc
					(start 336.524092 -284.847538)
					(mid 336.195162 -284.518608)
					(end 335.866232 -284.847538)
				)
				(arc
					(start 335.866232 -284.847538)
					(mid 335.872968 -284.913791)
					(end 335.892902 -284.977332)
				)
				(arc
					(start 335.686654 -285.33471)
					(mid 335.479411 -285.44285)
					(end 335.396332 -285.661354)
				)
			)
		)
	)
	(zone
		(layers "F.Cu" "B.Cu" "In1.Cu" "In2.Cu" "In6.Cu" "In7.Cu" "In8.Cu" "In9.Cu"
			"In10.Cu" "In11.Cu" "In12.Cu" "In13.Cu" "In14.Cu" "In15.Cu" "In16.Cu"
		)
		(hatch none 0.5)
		(connect_pads
			(clearance 0)
		)
		(min_thickness 0.25)
		(keepout
			(tracks not_allowed)
			(vias allowed)
			(pads allowed)
			(copperpour not_allowed)
			(footprints allowed)
		)
		(placement
			(enabled no)
			(sheetname "")
		)
		(fill yes
			(thermal_gap 0.5)
			(thermal_bridge_width 0.5)
			(island_removal_mode 0)
		)
		(polygon
			(pts
				(arc
					(start 86.112096 -285.044388)
					(mid 86.228165 -285.141599)
					(end 86.375494 -285.176468)
				)
				(arc
					(start 86.375494 -285.176468)
					(mid 86.704424 -284.847538)
					(end 86.375494 -284.518608)
				)
				(arc
					(start 86.375494 -284.518608)
					(mid 86.228165 -284.553478)
					(end 86.112096 -284.650688)
				)
				(arc
					(start 85.699092 -284.650688)
					(mid 85.583023 -284.553477)
					(end 85.435694 -284.518608)
				)
				(arc
					(start 85.435694 -284.518608)
					(mid 85.106764 -284.847538)
					(end 85.435694 -285.176468)
				)
				(arc
					(start 85.435694 -285.176468)
					(mid 85.583023 -285.141598)
					(end 85.699092 -285.044388)
				)
			)
		)
	)
	(zone
		(layers "F.Cu" "B.Cu" "In1.Cu" "In2.Cu" "In6.Cu" "In7.Cu" "In8.Cu" "In9.Cu"
			"In10.Cu" "In11.Cu" "In12.Cu" "In13.Cu" "In14.Cu" "In15.Cu" "In16.Cu"
		)
		(hatch none 0.5)
		(connect_pads
			(clearance 0)
		)
		(min_thickness 0.25)
		(keepout
			(tracks not_allowed)
			(vias allowed)
			(pads allowed)
			(copperpour not_allowed)
			(footprints allowed)
		)
		(placement
			(enabled no)
			(sheetname "")
		)
		(fill yes
			(thermal_gap 0.5)
			(thermal_bridge_width 0.5)
			(island_removal_mode 0)
		)
		(polygon
			(pts
				(arc
					(start 87.991696 -286.672274)
					(mid 88.107765 -286.769485)
					(end 88.255094 -286.804354)
				)
				(arc
					(start 88.255094 -286.804354)
					(mid 88.584024 -286.475424)
					(end 88.255094 -286.146494)
				)
				(arc
					(start 88.255094 -286.146494)
					(mid 88.107765 -286.181364)
					(end 87.991696 -286.278574)
				)
				(arc
					(start 87.578692 -286.278574)
					(mid 87.462623 -286.181363)
					(end 87.315294 -286.146494)
				)
				(arc
					(start 87.315294 -286.146494)
					(mid 86.986364 -286.475424)
					(end 87.315294 -286.804354)
				)
				(arc
					(start 87.315294 -286.804354)
					(mid 87.462623 -286.769484)
					(end 87.578692 -286.672274)
				)
			)
		)
	)
	(zone
		(layers "F.Cu" "B.Cu" "In1.Cu" "In2.Cu" "In6.Cu" "In7.Cu" "In8.Cu" "In9.Cu"
			"In10.Cu" "In11.Cu" "In12.Cu" "In13.Cu" "In14.Cu" "In15.Cu" "In16.Cu"
		)
		(hatch none 0.5)
		(connect_pads
			(clearance 0)
		)
		(min_thickness 0.25)
		(keepout
			(tracks not_allowed)
			(vias allowed)
			(pads allowed)
			(copperpour not_allowed)
			(footprints allowed)
		)
		(placement
			(enabled no)
			(sheetname "")
		)
		(fill yes
			(thermal_gap 0.5)
			(thermal_bridge_width 0.5)
			(island_removal_mode 0)
		)
		(polygon
			(pts
				(arc
					(start 89.40165 -282.602686)
					(mid 89.517719 -282.699897)
					(end 89.665048 -282.734766)
				)
				(arc
					(start 89.665048 -282.734766)
					(mid 89.993978 -282.405836)
					(end 89.665048 -282.076906)
				)
				(arc
					(start 89.665048 -282.076906)
					(mid 89.517719 -282.111776)
					(end 89.40165 -282.208986)
				)
				(arc
					(start 88.988646 -282.208986)
					(mid 88.872577 -282.111775)
					(end 88.725248 -282.076906)
				)
				(arc
					(start 88.725248 -282.076906)
					(mid 88.396318 -282.405836)
					(end 88.725248 -282.734766)
				)
				(arc
					(start 88.725248 -282.734766)
					(mid 88.872577 -282.699896)
					(end 88.988646 -282.602686)
				)
			)
		)
	)
	(zone
		(layers "F.Cu" "B.Cu" "In1.Cu" "In2.Cu" "In6.Cu" "In7.Cu" "In8.Cu" "In9.Cu"
			"In10.Cu" "In11.Cu" "In12.Cu" "In13.Cu" "In14.Cu" "In15.Cu" "In16.Cu"
		)
		(hatch none 0.5)
		(connect_pads
			(clearance 0)
		)
		(min_thickness 0.25)
		(keepout
			(tracks not_allowed)
			(vias allowed)
			(pads allowed)
			(copperpour not_allowed)
			(footprints allowed)
		)
		(placement
			(enabled no)
			(sheetname "")
		)
		(fill yes
			(thermal_gap 0.5)
			(thermal_bridge_width 0.5)
			(island_removal_mode 0)
		)
		(polygon
			(pts
				(arc
					(start 380.39675 -221.94774)
					(mid 380.72568 -222.27667)
					(end 381.05461 -221.94774)
				)
				(arc
					(start 381.05461 -221.947232)
					(mid 381.047844 -221.881111)
					(end 381.02794 -221.817692)
				)
				(arc
					(start 381.233934 -221.460568)
					(mid 381.441473 -221.352577)
					(end 381.524764 -221.133924)
				)
				(arc
					(start 381.524764 -221.133924)
					(mid 381.195834 -220.804994)
					(end 380.866904 -221.133924)
				)
				(arc
					(start 380.866904 -221.133924)
					(mid 380.873539 -221.199912)
					(end 380.89332 -221.26321)
				)
				(arc
					(start 380.687072 -221.621096)
					(mid 380.479829 -221.729236)
					(end 380.39675 -221.94774)
				)
			)
		)
	)
	(zone
		(layers "F.Cu" "B.Cu" "In1.Cu" "In2.Cu" "In6.Cu" "In7.Cu" "In8.Cu" "In9.Cu"
			"In10.Cu" "In11.Cu" "In12.Cu" "In13.Cu" "In14.Cu" "In15.Cu" "In16.Cu"
		)
		(hatch none 0.5)
		(connect_pads
			(clearance 0)
		)
		(min_thickness 0.25)
		(keepout
			(tracks not_allowed)
			(vias allowed)
			(pads allowed)
			(copperpour not_allowed)
			(footprints allowed)
		)
		(placement
			(enabled no)
			(sheetname "")
		)
		(fill yes
			(thermal_gap 0.5)
			(thermal_bridge_width 0.5)
			(island_removal_mode 0)
		)
		(polygon
			(pts
				(arc
					(start 134.336536 -225.203258)
					(mid 134.665466 -225.532188)
					(end 134.994396 -225.203258)
				)
				(arc
					(start 134.994396 -225.203258)
					(mid 134.911326 -224.984746)
					(end 134.704074 -224.876614)
				)
				(arc
					(start 134.497826 -224.519236)
					(mid 134.517759 -224.455695)
					(end 134.524496 -224.389442)
				)
				(arc
					(start 134.524496 -224.389442)
					(mid 134.195566 -224.060512)
					(end 133.866636 -224.389442)
				)
				(arc
					(start 133.866636 -224.389442)
					(mid 133.949789 -224.608048)
					(end 134.157212 -224.716086)
				)
				(arc
					(start 134.363206 -225.07321)
					(mid 134.343233 -225.136874)
					(end 134.336536 -225.203258)
				)
			)
		)
	)
	(zone
		(layers "F.Cu" "B.Cu" "In1.Cu" "In2.Cu" "In6.Cu" "In7.Cu" "In8.Cu" "In9.Cu"
			"In10.Cu" "In11.Cu" "In12.Cu" "In13.Cu" "In14.Cu" "In15.Cu" "In16.Cu"
		)
		(hatch none 0.5)
		(connect_pads
			(clearance 0)
		)
		(min_thickness 0.25)
		(keepout
			(tracks not_allowed)
			(vias allowed)
			(pads allowed)
			(copperpour not_allowed)
			(footprints allowed)
		)
		(placement
			(enabled no)
			(sheetname "")
		)
		(fill yes
			(thermal_gap 0.5)
			(thermal_bridge_width 0.5)
			(island_removal_mode 0)
		)
		(polygon
			(pts
				(arc
					(start 338.685632 -283.219906)
					(mid 339.014562 -283.548836)
					(end 339.343492 -283.219906)
				)
				(arc
					(start 339.343492 -283.219398)
					(mid 339.336726 -283.153277)
					(end 339.316822 -283.089858)
				)
				(arc
					(start 339.52307 -282.73248)
					(mid 339.730461 -282.624415)
					(end 339.813646 -282.405836)
				)
				(arc
					(start 339.813646 -282.405836)
					(mid 339.484716 -282.076906)
					(end 339.155786 -282.405836)
				)
				(arc
					(start 339.155786 -282.405836)
					(mid 339.162522 -282.472089)
					(end 339.182456 -282.53563)
				)
				(arc
					(start 338.975954 -282.893262)
					(mid 338.768711 -283.001402)
					(end 338.685632 -283.219906)
				)
			)
		)
	)
	(zone
		(layers "F.Cu" "B.Cu" "In1.Cu" "In2.Cu" "In6.Cu" "In7.Cu" "In8.Cu" "In9.Cu"
			"In10.Cu" "In11.Cu" "In12.Cu" "In13.Cu" "In14.Cu" "In15.Cu" "In16.Cu"
		)
		(hatch none 0.5)
		(connect_pads
			(clearance 0)
		)
		(min_thickness 0.25)
		(keepout
			(tracks not_allowed)
			(vias allowed)
			(pads allowed)
			(copperpour not_allowed)
			(footprints allowed)
		)
		(placement
			(enabled no)
			(sheetname "")
		)
		(fill yes
			(thermal_gap 0.5)
			(thermal_bridge_width 0.5)
			(island_removal_mode 0)
		)
		(polygon
			(pts
				(arc
					(start 335.931764 -286.672274)
					(mid 336.047833 -286.769485)
					(end 336.195162 -286.804354)
				)
				(arc
					(start 336.195162 -286.804354)
					(mid 336.524092 -286.475424)
					(end 336.195162 -286.146494)
				)
				(arc
					(start 336.195162 -286.146494)
					(mid 336.047833 -286.181364)
					(end 335.931764 -286.278574)
				)
				(arc
					(start 335.51876 -286.278574)
					(mid 335.402691 -286.181363)
					(end 335.255362 -286.146494)
				)
				(arc
					(start 335.255362 -286.146494)
					(mid 334.926432 -286.475424)
					(end 335.255362 -286.804354)
				)
				(arc
					(start 335.255362 -286.804354)
					(mid 335.402691 -286.769484)
					(end 335.51876 -286.672274)
				)
			)
		)
	)
	(zone
		(layers "F.Cu" "B.Cu" "In1.Cu" "In2.Cu" "In6.Cu" "In7.Cu" "In8.Cu" "In9.Cu"
			"In10.Cu" "In11.Cu" "In12.Cu" "In13.Cu" "In14.Cu" "In15.Cu" "In16.Cu"
		)
		(hatch none 0.5)
		(connect_pads
			(clearance 0)
		)
		(min_thickness 0.25)
		(keepout
			(tracks not_allowed)
			(vias allowed)
			(pads allowed)
			(copperpour not_allowed)
			(footprints allowed)
		)
		(placement
			(enabled no)
			(sheetname "")
		)
		(fill yes
			(thermal_gap 0.5)
			(thermal_bridge_width 0.5)
			(island_removal_mode 0)
		)
		(polygon
			(pts
				(arc
					(start 88.866218 -281.59202)
					(mid 89.195148 -281.92095)
					(end 89.524078 -281.59202)
				)
				(arc
					(start 89.524078 -281.591512)
					(mid 89.517312 -281.525391)
					(end 89.497408 -281.461972)
				)
				(arc
					(start 89.703656 -281.104848)
					(mid 89.910751 -280.996634)
					(end 89.993724 -280.778204)
				)
				(arc
					(start 89.993724 -280.778204)
					(mid 89.664794 -280.449274)
					(end 89.335864 -280.778204)
				)
				(arc
					(start 89.335864 -280.778204)
					(mid 89.342688 -280.844603)
					(end 89.362788 -280.908252)
				)
				(arc
					(start 89.15654 -281.265376)
					(mid 88.949297 -281.373516)
					(end 88.866218 -281.59202)
				)
			)
		)
	)
	(zone
		(layers "F.Cu" "B.Cu" "In1.Cu" "In2.Cu" "In6.Cu" "In7.Cu" "In8.Cu" "In9.Cu"
			"In10.Cu" "In11.Cu" "In12.Cu" "In13.Cu" "In14.Cu" "In15.Cu" "In16.Cu"
		)
		(hatch none 0.5)
		(connect_pads
			(clearance 0)
		)
		(min_thickness 0.25)
		(keepout
			(tracks not_allowed)
			(vias allowed)
			(pads allowed)
			(copperpour not_allowed)
			(footprints allowed)
		)
		(placement
			(enabled no)
			(sheetname "")
		)
		(fill yes
			(thermal_gap 0.5)
			(thermal_bridge_width 0.5)
			(island_removal_mode 0)
		)
		(polygon
			(pts
				(arc
					(start 134.336282 -221.94774)
					(mid 134.665212 -222.27667)
					(end 134.994142 -221.94774)
				)
				(arc
					(start 134.994142 -221.947232)
					(mid 134.987376 -221.881111)
					(end 134.967472 -221.817692)
				)
				(arc
					(start 135.173466 -221.460568)
					(mid 135.381005 -221.352577)
					(end 135.464296 -221.133924)
				)
				(arc
					(start 135.464296 -221.133924)
					(mid 135.135366 -220.804994)
					(end 134.806436 -221.133924)
				)
				(arc
					(start 134.806436 -221.133924)
					(mid 134.813071 -221.199912)
					(end 134.832852 -221.26321)
				)
				(arc
					(start 134.626604 -221.621096)
					(mid 134.419361 -221.729236)
					(end 134.336282 -221.94774)
				)
			)
		)
	)
	(zone
		(layers "F.Cu" "B.Cu" "In1.Cu" "In2.Cu" "In6.Cu" "In7.Cu" "In8.Cu" "In9.Cu"
			"In10.Cu" "In11.Cu" "In12.Cu" "In13.Cu" "In14.Cu" "In15.Cu" "In16.Cu"
		)
		(hatch none 0.5)
		(connect_pads
			(clearance 0)
		)
		(min_thickness 0.25)
		(keepout
			(tracks not_allowed)
			(vias allowed)
			(pads allowed)
			(copperpour not_allowed)
			(footprints allowed)
		)
		(placement
			(enabled no)
			(sheetname "")
		)
		(fill yes
			(thermal_gap 0.5)
			(thermal_bridge_width 0.5)
			(island_removal_mode 0)
		)
		(polygon
			(pts
				(arc
					(start 132.456682 -221.94774)
					(mid 132.785612 -222.27667)
					(end 133.114542 -221.94774)
				)
				(arc
					(start 133.114542 -221.947232)
					(mid 133.107776 -221.881111)
					(end 133.087872 -221.817692)
				)
				(arc
					(start 133.293866 -221.460568)
					(mid 133.501405 -221.352577)
					(end 133.584696 -221.133924)
				)
				(arc
					(start 133.584696 -221.133924)
					(mid 133.255766 -220.804994)
					(end 132.926836 -221.133924)
				)
				(arc
					(start 132.926836 -221.133924)
					(mid 132.933471 -221.199912)
					(end 132.953252 -221.26321)
				)
				(arc
					(start 132.747004 -221.621096)
					(mid 132.539761 -221.729236)
					(end 132.456682 -221.94774)
				)
			)
		)
	)
	(zone
		(layers "F.Cu" "B.Cu" "In1.Cu" "In2.Cu" "In6.Cu" "In7.Cu" "In8.Cu" "In9.Cu"
			"In10.Cu" "In11.Cu" "In12.Cu" "In13.Cu" "In14.Cu" "In15.Cu" "In16.Cu"
		)
		(hatch none 0.5)
		(connect_pads
			(clearance 0)
		)
		(min_thickness 0.25)
		(keepout
			(tracks not_allowed)
			(vias allowed)
			(pads allowed)
			(copperpour not_allowed)
			(footprints allowed)
		)
		(placement
			(enabled no)
			(sheetname "")
		)
		(fill yes
			(thermal_gap 0.5)
			(thermal_bridge_width 0.5)
			(island_removal_mode 0)
		)
		(polygon
			(pts
				(arc
					(start 380.866904 -224.389442)
					(mid 381.195834 -224.718372)
					(end 381.524764 -224.389442)
				)
				(arc
					(start 381.524764 -224.388934)
					(mid 381.517998 -224.322813)
					(end 381.498094 -224.259394)
				)
				(arc
					(start 381.704088 -223.90227)
					(mid 381.911479 -223.794205)
					(end 381.994664 -223.575626)
				)
				(arc
					(start 381.994664 -223.575626)
					(mid 381.665734 -223.246696)
					(end 381.336804 -223.575626)
				)
				(arc
					(start 381.336804 -223.575626)
					(mid 381.34357 -223.641747)
					(end 381.363474 -223.705166)
				)
				(arc
					(start 381.157226 -224.062798)
					(mid 380.949983 -224.170938)
					(end 380.866904 -224.389442)
				)
			)
		)
	)
	(zone
		(layers "F.Cu" "B.Cu" "In1.Cu" "In2.Cu" "In6.Cu" "In7.Cu" "In8.Cu" "In9.Cu"
			"In10.Cu" "In11.Cu" "In12.Cu" "In13.Cu" "In14.Cu" "In15.Cu" "In16.Cu"
		)
		(hatch none 0.5)
		(connect_pads
			(clearance 0)
		)
		(min_thickness 0.25)
		(keepout
			(tracks not_allowed)
			(vias allowed)
			(pads allowed)
			(copperpour not_allowed)
			(footprints allowed)
		)
		(placement
			(enabled no)
			(sheetname "")
		)
		(fill yes
			(thermal_gap 0.5)
			(thermal_bridge_width 0.5)
			(island_removal_mode 0)
		)
		(polygon
			(pts
				(arc
					(start 336.806286 -281.59202)
					(mid 337.135216 -281.92095)
					(end 337.464146 -281.59202)
				)
				(arc
					(start 337.464146 -281.591512)
					(mid 337.45738 -281.525391)
					(end 337.437476 -281.461972)
				)
				(arc
					(start 337.643724 -281.104848)
					(mid 337.850819 -280.996634)
					(end 337.933792 -280.778204)
				)
				(arc
					(start 337.933792 -280.778204)
					(mid 337.604862 -280.449274)
					(end 337.275932 -280.778204)
				)
				(arc
					(start 337.275932 -280.778204)
					(mid 337.282756 -280.844603)
					(end 337.302856 -280.908252)
				)
				(arc
					(start 337.096608 -281.265376)
					(mid 336.889365 -281.373516)
					(end 336.806286 -281.59202)
				)
			)
		)
	)
	(zone
		(layers "F.Cu" "B.Cu" "In1.Cu" "In2.Cu" "In6.Cu" "In7.Cu" "In8.Cu" "In9.Cu"
			"In10.Cu" "In11.Cu" "In12.Cu" "In13.Cu" "In14.Cu" "In15.Cu" "In16.Cu"
		)
		(hatch none 0.5)
		(connect_pads
			(clearance 0)
		)
		(min_thickness 0.25)
		(keepout
			(tracks not_allowed)
			(vias allowed)
			(pads allowed)
			(copperpour not_allowed)
			(footprints allowed)
		)
		(placement
			(enabled no)
			(sheetname "")
		)
		(fill yes
			(thermal_gap 0.5)
			(thermal_bridge_width 0.5)
			(island_removal_mode 0)
		)
		(polygon
			(pts
				(arc
					(start 90.745564 -283.219906)
					(mid 91.074494 -283.548836)
					(end 91.403424 -283.219906)
				)
				(arc
					(start 91.403424 -283.219398)
					(mid 91.396658 -283.153277)
					(end 91.376754 -283.089858)
				)
				(arc
					(start 91.583002 -282.73248)
					(mid 91.790393 -282.624415)
					(end 91.873578 -282.405836)
				)
				(arc
					(start 91.873578 -282.405836)
					(mid 91.544648 -282.076906)
					(end 91.215718 -282.405836)
				)
				(arc
					(start 91.215718 -282.405836)
					(mid 91.222454 -282.472089)
					(end 91.242388 -282.53563)
				)
				(arc
					(start 91.035886 -282.893262)
					(mid 90.828643 -283.001402)
					(end 90.745564 -283.219906)
				)
			)
		)
	)
	(zone
		(layers "F.Cu" "B.Cu" "In1.Cu" "In2.Cu" "In6.Cu" "In7.Cu" "In8.Cu" "In9.Cu"
			"In10.Cu" "In11.Cu" "In12.Cu" "In13.Cu" "In14.Cu" "In15.Cu" "In16.Cu"
		)
		(hatch none 0.5)
		(connect_pads
			(clearance 0)
		)
		(min_thickness 0.25)
		(keepout
			(tracks not_allowed)
			(vias allowed)
			(pads allowed)
			(copperpour not_allowed)
			(footprints allowed)
		)
		(placement
			(enabled no)
			(sheetname "")
		)
		(fill yes
			(thermal_gap 0.5)
			(thermal_bridge_width 0.5)
			(island_removal_mode 0)
		)
		(polygon
			(pts
				(arc
					(start 131.047236 -224.389442)
					(mid 131.376166 -224.718372)
					(end 131.705096 -224.389442)
				)
				(arc
					(start 131.705096 -224.388934)
					(mid 131.69833 -224.322813)
					(end 131.678426 -224.259394)
				)
				(arc
					(start 131.88442 -223.90227)
					(mid 132.091663 -223.79413)
					(end 132.174742 -223.575626)
				)
				(arc
					(start 132.174742 -223.575626)
					(mid 131.845812 -223.246696)
					(end 131.516882 -223.575626)
				)
				(arc
					(start 131.516882 -223.575626)
					(mid 131.523618 -223.641879)
					(end 131.543552 -223.70542)
				)
				(arc
					(start 131.337558 -224.062798)
					(mid 131.130315 -224.170938)
					(end 131.047236 -224.389442)
				)
			)
		)
	)
	(zone
		(layers "F.Cu" "B.Cu" "In1.Cu" "In2.Cu" "In6.Cu" "In7.Cu" "In8.Cu" "In9.Cu"
			"In10.Cu" "In11.Cu" "In12.Cu" "In13.Cu" "In14.Cu" "In15.Cu" "In16.Cu"
		)
		(hatch none 0.5)
		(connect_pads
			(clearance 0)
		)
		(min_thickness 0.25)
		(keepout
			(tracks not_allowed)
			(vias allowed)
			(pads allowed)
			(copperpour not_allowed)
			(footprints allowed)
		)
		(placement
			(enabled no)
			(sheetname "")
		)
		(fill yes
			(thermal_gap 0.5)
			(thermal_bridge_width 0.5)
			(island_removal_mode 0)
		)
		(polygon
			(pts
				(arc
					(start 340.565232 -281.59202)
					(mid 340.894162 -281.92095)
					(end 341.223092 -281.59202)
				)
				(arc
					(start 341.223092 -281.59202)
					(mid 341.140022 -281.373508)
					(end 340.93277 -281.265376)
				)
				(arc
					(start 340.726522 -280.908252)
					(mid 340.746609 -280.8446)
					(end 340.753446 -280.778204)
				)
				(arc
					(start 340.753446 -280.778204)
					(mid 340.424516 -280.449274)
					(end 340.095586 -280.778204)
				)
				(arc
					(start 340.095586 -280.778204)
					(mid 340.178572 -280.996622)
					(end 340.385654 -281.104848)
				)
				(arc
					(start 340.591902 -281.462226)
					(mid 340.571969 -281.525767)
					(end 340.565232 -281.59202)
				)
			)
		)
	)
	(zone
		(layers "F.Cu" "B.Cu" "In1.Cu" "In2.Cu" "In6.Cu" "In7.Cu" "In8.Cu" "In9.Cu"
			"In10.Cu" "In11.Cu" "In12.Cu" "In13.Cu" "In14.Cu" "In15.Cu" "In16.Cu"
		)
		(hatch none 0.5)
		(connect_pads
			(clearance 0)
		)
		(min_thickness 0.25)
		(keepout
			(tracks not_allowed)
			(vias allowed)
			(pads allowed)
			(copperpour not_allowed)
			(footprints allowed)
		)
		(placement
			(enabled no)
			(sheetname "")
		)
		(fill yes
			(thermal_gap 0.5)
			(thermal_bridge_width 0.5)
			(island_removal_mode 0)
		)
		(polygon
			(pts
				(arc
					(start 334.052164 -285.044388)
					(mid 334.168233 -285.141599)
					(end 334.315562 -285.176468)
				)
				(arc
					(start 334.315562 -285.176468)
					(mid 334.644492 -284.847538)
					(end 334.315562 -284.518608)
				)
				(arc
					(start 334.315562 -284.518608)
					(mid 334.168233 -284.553478)
					(end 334.052164 -284.650688)
				)
				(arc
					(start 333.63916 -284.650688)
					(mid 333.523091 -284.553477)
					(end 333.375762 -284.518608)
				)
				(arc
					(start 333.375762 -284.518608)
					(mid 333.046832 -284.847538)
					(end 333.375762 -285.176468)
				)
				(arc
					(start 333.375762 -285.176468)
					(mid 333.523091 -285.141598)
					(end 333.63916 -285.044388)
				)
			)
		)
	)
	(zone
		(layers "F.Cu" "B.Cu" "In2.Cu" "In3.Cu" "In4.Cu" "In8.Cu" "In9.Cu" "In10.Cu"
			"In11.Cu" "In12.Cu" "In13.Cu" "In14.Cu" "In15.Cu" "In16.Cu"
		)
		(hatch none 0.5)
		(connect_pads
			(clearance 0)
		)
		(min_thickness 0.25)
		(keepout
			(tracks not_allowed)
			(vias allowed)
			(pads allowed)
			(copperpour not_allowed)
			(footprints allowed)
		)
		(placement
			(enabled no)
			(sheetname "")
		)
		(fill yes
			(thermal_gap 0.5)
			(thermal_bridge_width 0.5)
			(island_removal_mode 0)
		)
		(polygon
			(pts
				(arc
					(start 91.575636 -224.389442)
					(mid 91.904566 -224.718372)
					(end 92.233496 -224.389442)
				)
				(arc
					(start 92.233496 -224.388934)
					(mid 92.22673 -224.322813)
					(end 92.206826 -224.259394)
				)
				(arc
					(start 92.41282 -223.90227)
					(mid 92.620063 -223.79413)
					(end 92.703142 -223.575626)
				)
				(arc
					(start 92.703142 -223.575626)
					(mid 92.374212 -223.246696)
					(end 92.045282 -223.575626)
				)
				(arc
					(start 92.045282 -223.575626)
					(mid 92.052018 -223.641879)
					(end 92.071952 -223.70542)
				)
				(arc
					(start 91.865958 -224.062798)
					(mid 91.658715 -224.170938)
					(end 91.575636 -224.389442)
				)
			)
		)
	)
	(zone
		(layers "F.Cu" "B.Cu" "In2.Cu" "In3.Cu" "In4.Cu" "In8.Cu" "In9.Cu" "In10.Cu"
			"In11.Cu" "In12.Cu" "In13.Cu" "In14.Cu" "In15.Cu" "In16.Cu"
		)
		(hatch none 0.5)
		(connect_pads
			(clearance 0)
		)
		(min_thickness 0.25)
		(keepout
			(tracks not_allowed)
			(vias allowed)
			(pads allowed)
			(copperpour not_allowed)
			(footprints allowed)
		)
		(placement
			(enabled no)
			(sheetname "")
		)
		(fill yes
			(thermal_gap 0.5)
			(thermal_bridge_width 0.5)
			(island_removal_mode 0)
		)
		(polygon
			(pts
				(arc
					(start 339.515704 -224.389442)
					(mid 339.844634 -224.718372)
					(end 340.173564 -224.389442)
				)
				(arc
					(start 340.173564 -224.388934)
					(mid 340.166798 -224.322813)
					(end 340.146894 -224.259394)
				)
				(arc
					(start 340.352888 -223.90227)
					(mid 340.560131 -223.79413)
					(end 340.64321 -223.575626)
				)
				(arc
					(start 340.64321 -223.575626)
					(mid 340.31428 -223.246696)
					(end 339.98535 -223.575626)
				)
				(arc
					(start 339.98535 -223.575626)
					(mid 339.992086 -223.641879)
					(end 340.01202 -223.70542)
				)
				(arc
					(start 339.806026 -224.062798)
					(mid 339.598783 -224.170938)
					(end 339.515704 -224.389442)
				)
			)
		)
	)
	(zone
		(layers "F.Cu" "B.Cu" "In2.Cu" "In4.Cu" "In6.Cu" "In8.Cu" "In9.Cu" "In11.Cu"
			"In13.Cu" "In15.Cu"
		)
		(hatch none 0.5)
		(connect_pads
			(clearance 0)
		)
		(min_thickness 0.25)
		(keepout
			(tracks not_allowed)
			(vias allowed)
			(pads allowed)
			(copperpour not_allowed)
			(footprints allowed)
		)
		(placement
			(enabled no)
			(sheetname "")
		)
		(fill yes
			(thermal_gap 0.5)
			(thermal_bridge_width 0.5)
			(island_removal_mode 0)
		)
		(polygon
			(pts
				(arc
					(start 273.68754 -383.7051)
					(mid 271.90954 -383.7051)
					(end 273.68754 -383.7051)
				)
			)
		)
	)
	(zone
		(layers "F.Cu" "B.Cu" "In2.Cu" "In4.Cu" "In6.Cu" "In8.Cu" "In9.Cu" "In11.Cu"
			"In13.Cu" "In15.Cu"
		)
		(hatch none 0.5)
		(connect_pads
			(clearance 0)
		)
		(min_thickness 0.25)
		(keepout
			(tracks not_allowed)
			(vias allowed)
			(pads allowed)
			(copperpour not_allowed)
			(footprints allowed)
		)
		(placement
			(enabled no)
			(sheetname "")
		)
		(fill yes
			(thermal_gap 0.5)
			(thermal_bridge_width 0.5)
			(island_removal_mode 0)
		)
		(polygon
			(pts
				(arc
					(start 271.770348 -386.102352)
					(mid 269.992348 -386.102352)
					(end 271.770348 -386.102352)
				)
			)
		)
	)
	(zone
		(layers "F.Cu" "B.Cu" "In6.Cu" "In7.Cu" "In8.Cu" "In9.Cu" "In10.Cu" "In11.Cu"
			"In12.Cu" "In13.Cu" "In14.Cu" "In15.Cu" "In16.Cu"
		)
		(hatch none 0.5)
		(connect_pads
			(clearance 0)
		)
		(min_thickness 0.25)
		(keepout
			(tracks not_allowed)
			(vias allowed)
			(pads allowed)
			(copperpour not_allowed)
			(footprints allowed)
		)
		(placement
			(enabled no)
			(sheetname "")
		)
		(fill yes
			(thermal_gap 0.5)
			(thermal_bridge_width 0.5)
			(island_removal_mode 0)
		)
		(polygon
			(pts
				(arc
					(start 86.516718 -282.405836)
					(mid 86.845648 -282.734766)
					(end 87.174578 -282.405836)
				)
				(arc
					(start 87.174578 -282.405836)
					(mid 87.167842 -282.339583)
					(end 87.147908 -282.276042)
				)
				(arc
					(start 87.354156 -281.918664)
					(mid 87.561399 -281.810524)
					(end 87.644478 -281.59202)
				)
				(arc
					(start 87.644478 -281.59202)
					(mid 87.315548 -281.26309)
					(end 86.986618 -281.59202)
				)
				(arc
					(start 86.986618 -281.59202)
					(mid 86.993354 -281.658273)
					(end 87.013288 -281.721814)
				)
				(arc
					(start 86.80704 -282.079192)
					(mid 86.599797 -282.187332)
					(end 86.516718 -282.405836)
				)
			)
		)
	)
	(zone
		(layers "F.Cu" "B.Cu" "In6.Cu" "In7.Cu" "In8.Cu" "In9.Cu" "In10.Cu" "In11.Cu"
			"In12.Cu" "In13.Cu" "In14.Cu" "In15.Cu" "In16.Cu"
		)
		(hatch none 0.5)
		(connect_pads
			(clearance 0)
		)
		(min_thickness 0.25)
		(keepout
			(tracks not_allowed)
			(vias allowed)
			(pads allowed)
			(copperpour not_allowed)
			(footprints allowed)
		)
		(placement
			(enabled no)
			(sheetname "")
		)
		(fill yes
			(thermal_gap 0.5)
			(thermal_bridge_width 0.5)
			(island_removal_mode 0)
		)
		(polygon
			(pts
				(arc
					(start 87.521796 -280.975054)
					(mid 87.637865 -281.072265)
					(end 87.785194 -281.107134)
				)
				(arc
					(start 87.785194 -281.107134)
					(mid 88.114124 -280.778204)
					(end 87.785194 -280.449274)
				)
				(arc
					(start 87.785194 -280.449274)
					(mid 87.637865 -280.484144)
					(end 87.521796 -280.581354)
				)
				(arc
					(start 87.108792 -280.581354)
					(mid 86.992723 -280.484143)
					(end 86.845394 -280.449274)
				)
				(arc
					(start 86.845394 -280.449274)
					(mid 86.516464 -280.778204)
					(end 86.845394 -281.107134)
				)
				(arc
					(start 86.845394 -281.107134)
					(mid 86.992723 -281.072264)
					(end 87.108792 -280.975054)
				)
			)
		)
	)
	(zone
		(layers "F.Cu" "B.Cu" "In6.Cu" "In7.Cu" "In8.Cu" "In9.Cu" "In10.Cu" "In11.Cu"
			"In12.Cu" "In13.Cu" "In14.Cu" "In15.Cu" "In16.Cu"
		)
		(hatch none 0.5)
		(connect_pads
			(clearance 0)
		)
		(min_thickness 0.25)
		(keepout
			(tracks not_allowed)
			(vias allowed)
			(pads allowed)
			(copperpour not_allowed)
			(footprints allowed)
		)
		(placement
			(enabled no)
			(sheetname "")
		)
		(fill yes
			(thermal_gap 0.5)
			(thermal_bridge_width 0.5)
			(island_removal_mode 0)
		)
		(polygon
			(pts
				(arc
					(start 334.456786 -282.405836)
					(mid 334.785716 -282.734766)
					(end 335.114646 -282.405836)
				)
				(arc
					(start 335.114646 -282.405836)
					(mid 335.10791 -282.339583)
					(end 335.087976 -282.276042)
				)
				(arc
					(start 335.294224 -281.918664)
					(mid 335.501467 -281.810524)
					(end 335.584546 -281.59202)
				)
				(arc
					(start 335.584546 -281.59202)
					(mid 335.255616 -281.26309)
					(end 334.926686 -281.59202)
				)
				(arc
					(start 334.926686 -281.59202)
					(mid 334.933422 -281.658273)
					(end 334.953356 -281.721814)
				)
				(arc
					(start 334.747108 -282.079192)
					(mid 334.539865 -282.187332)
					(end 334.456786 -282.405836)
				)
			)
		)
	)
	(zone
		(layers "F.Cu" "B.Cu" "In6.Cu" "In7.Cu" "In8.Cu" "In9.Cu" "In10.Cu" "In11.Cu"
			"In12.Cu" "In13.Cu" "In14.Cu" "In15.Cu" "In16.Cu"
		)
		(hatch none 0.5)
		(connect_pads
			(clearance 0)
		)
		(min_thickness 0.25)
		(keepout
			(tracks not_allowed)
			(vias allowed)
			(pads allowed)
			(copperpour not_allowed)
			(footprints allowed)
		)
		(placement
			(enabled no)
			(sheetname "")
		)
		(fill yes
			(thermal_gap 0.5)
			(thermal_bridge_width 0.5)
			(island_removal_mode 0)
		)
		(polygon
			(pts
				(arc
					(start 335.461864 -280.975054)
					(mid 335.577933 -281.072265)
					(end 335.725262 -281.107134)
				)
				(arc
					(start 335.725262 -281.107134)
					(mid 336.054192 -280.778204)
					(end 335.725262 -280.449274)
				)
				(arc
					(start 335.725262 -280.449274)
					(mid 335.577933 -280.484144)
					(end 335.461864 -280.581354)
				)
				(arc
					(start 335.04886 -280.581354)
					(mid 334.932791 -280.484143)
					(end 334.785462 -280.449274)
				)
				(arc
					(start 334.785462 -280.449274)
					(mid 334.456532 -280.778204)
					(end 334.785462 -281.107134)
				)
				(arc
					(start 334.785462 -281.107134)
					(mid 334.932791 -281.072264)
					(end 335.04886 -280.975054)
				)
			)
		)
	)
	(zone
		(layers "F.Cu" "In1.Cu" "In2.Cu" "In3.Cu" "In4.Cu" "In5.Cu" "In6.Cu" "In7.Cu"
			"In8.Cu" "In9.Cu" "In10.Cu" "In11.Cu" "In13.Cu" "In15.Cu" "In16.Cu"
		)
		(hatch none 0.5)
		(connect_pads
			(clearance 0)
		)
		(min_thickness 0.25)
		(keepout
			(tracks not_allowed)
			(vias allowed)
			(pads allowed)
			(copperpour not_allowed)
			(footprints allowed)
		)
		(placement
			(enabled no)
			(sheetname "")
		)
		(fill yes
			(thermal_gap 0.5)
			(thermal_bridge_width 0.5)
			(island_removal_mode 0)
		)
		(polygon
			(pts
				(arc
					(start 341.142066 -439.760614)
					(mid 341.164384 -439.814496)
					(end 341.218266 -439.836814)
				)
				(arc
					(start 342.158066 -439.836814)
					(mid 342.211948 -439.814496)
					(end 342.234266 -439.760614)
				)
				(arc
					(start 342.234266 -437.21909)
					(mid 342.211948 -437.165208)
					(end 342.158066 -437.14289)
				)
				(arc
					(start 341.218266 -437.14289)
					(mid 341.164384 -437.165208)
					(end 341.142066 -437.21909)
				)
			)
		)
	)
	(zone
		(layers "F.Cu" "In1.Cu" "In2.Cu" "In3.Cu" "In4.Cu" "In5.Cu" "In6.Cu" "In7.Cu"
			"In8.Cu" "In9.Cu" "In10.Cu" "In11.Cu" "In13.Cu" "In15.Cu" "In16.Cu"
		)
		(hatch none 0.5)
		(connect_pads
			(clearance 0)
		)
		(min_thickness 0.25)
		(keepout
			(tracks not_allowed)
			(vias allowed)
			(pads allowed)
			(copperpour not_allowed)
			(footprints allowed)
		)
		(placement
			(enabled no)
			(sheetname "")
		)
		(fill yes
			(thermal_gap 0.5)
			(thermal_bridge_width 0.5)
			(island_removal_mode 0)
		)
		(polygon
			(pts
				(arc
					(start 58.142124 -438.760616)
					(mid 58.164442 -438.814498)
					(end 58.218324 -438.836816)
				)
				(arc
					(start 59.158124 -438.836816)
					(mid 59.212006 -438.814498)
					(end 59.234324 -438.760616)
				)
				(arc
					(start 59.234324 -436.219092)
					(mid 59.212006 -436.16521)
					(end 59.158124 -436.142892)
				)
				(arc
					(start 58.218324 -436.142892)
					(mid 58.164442 -436.16521)
					(end 58.142124 -436.219092)
				)
			)
		)
	)
	(zone
		(layers "F.Cu" "In1.Cu" "In2.Cu" "In3.Cu" "In4.Cu" "In5.Cu" "In6.Cu" "In7.Cu"
			"In8.Cu" "In9.Cu" "In10.Cu" "In11.Cu" "In13.Cu" "In15.Cu" "In16.Cu"
		)
		(hatch none 0.5)
		(connect_pads
			(clearance 0)
		)
		(min_thickness 0.25)
		(keepout
			(tracks not_allowed)
			(vias allowed)
			(pads allowed)
			(copperpour not_allowed)
			(footprints allowed)
		)
		(placement
			(enabled no)
			(sheetname "")
		)
		(fill yes
			(thermal_gap 0.5)
			(thermal_bridge_width 0.5)
			(island_removal_mode 0)
		)
		(polygon
			(pts
				(arc
					(start 87.142066 -438.760616)
					(mid 87.164384 -438.814498)
					(end 87.218266 -438.836816)
				)
				(arc
					(start 88.158066 -438.836816)
					(mid 88.211948 -438.814498)
					(end 88.234266 -438.760616)
				)
				(arc
					(start 88.234266 -436.219092)
					(mid 88.211948 -436.16521)
					(end 88.158066 -436.142892)
				)
				(arc
					(start 87.218266 -436.142892)
					(mid 87.164384 -436.16521)
					(end 87.142066 -436.219092)
				)
			)
		)
	)
	(zone
		(layers "F.Cu" "In1.Cu" "In2.Cu" "In3.Cu" "In4.Cu" "In5.Cu" "In6.Cu" "In7.Cu"
			"In8.Cu" "In9.Cu" "In10.Cu" "In11.Cu" "In13.Cu" "In15.Cu" "In16.Cu"
		)
		(hatch none 0.5)
		(connect_pads
			(clearance 0)
		)
		(min_thickness 0.25)
		(keepout
			(tracks not_allowed)
			(vias allowed)
			(pads allowed)
			(copperpour not_allowed)
			(footprints allowed)
		)
		(placement
			(enabled no)
			(sheetname "")
		)
		(fill yes
			(thermal_gap 0.5)
			(thermal_bridge_width 0.5)
			(island_removal_mode 0)
		)
		(polygon
			(pts
				(arc
					(start 324.1421 -439.760614)
					(mid 324.164418 -439.814496)
					(end 324.2183 -439.836814)
				)
				(arc
					(start 325.1581 -439.836814)
					(mid 325.211982 -439.814496)
					(end 325.2343 -439.760614)
				)
				(arc
					(start 325.2343 -437.21909)
					(mid 325.211982 -437.165208)
					(end 325.1581 -437.14289)
				)
				(arc
					(start 324.2183 -437.14289)
					(mid 324.164418 -437.165208)
					(end 324.1421 -437.21909)
				)
			)
		)
	)
	(zone
		(layers "F.Cu" "In1.Cu" "In2.Cu" "In3.Cu" "In4.Cu" "In5.Cu" "In6.Cu" "In7.Cu"
			"In8.Cu" "In9.Cu" "In10.Cu" "In11.Cu" "In13.Cu" "In15.Cu" "In16.Cu"
		)
		(hatch none 0.5)
		(connect_pads
			(clearance 0)
		)
		(min_thickness 0.25)
		(keepout
			(tracks not_allowed)
			(vias allowed)
			(pads allowed)
			(copperpour not_allowed)
			(footprints allowed)
		)
		(placement
			(enabled no)
			(sheetname "")
		)
		(fill yes
			(thermal_gap 0.5)
			(thermal_bridge_width 0.5)
			(island_removal_mode 0)
		)
		(polygon
			(pts
				(arc
					(start 83.142074 -438.760616)
					(mid 83.164392 -438.814498)
					(end 83.218274 -438.836816)
				)
				(arc
					(start 84.158074 -438.836816)
					(mid 84.211956 -438.814498)
					(end 84.234274 -438.760616)
				)
				(arc
					(start 84.234274 -436.219092)
					(mid 84.211956 -436.16521)
					(end 84.158074 -436.142892)
				)
				(arc
					(start 83.218274 -436.142892)
					(mid 83.164392 -436.16521)
					(end 83.142074 -436.219092)
				)
			)
		)
	)
	(zone
		(layers "F.Cu" "In1.Cu" "In2.Cu" "In3.Cu" "In4.Cu" "In5.Cu" "In6.Cu" "In7.Cu"
			"In8.Cu" "In9.Cu" "In10.Cu" "In11.Cu" "In13.Cu" "In15.Cu" "In16.Cu"
		)
		(hatch none 0.5)
		(connect_pads
			(clearance 0)
		)
		(min_thickness 0.25)
		(keepout
			(tracks not_allowed)
			(vias allowed)
			(pads allowed)
			(copperpour not_allowed)
			(footprints allowed)
		)
		(placement
			(enabled no)
			(sheetname "")
		)
		(fill yes
			(thermal_gap 0.5)
			(thermal_bridge_width 0.5)
			(island_removal_mode 0)
		)
		(polygon
			(pts
				(arc
					(start 328.142092 -439.760614)
					(mid 328.16441 -439.814496)
					(end 328.218292 -439.836814)
				)
				(arc
					(start 329.158092 -439.836814)
					(mid 329.211974 -439.814496)
					(end 329.234292 -439.760614)
				)
				(arc
					(start 329.234292 -437.21909)
					(mid 329.211974 -437.165208)
					(end 329.158092 -437.14289)
				)
				(arc
					(start 328.218292 -437.14289)
					(mid 328.16441 -437.165208)
					(end 328.142092 -437.21909)
				)
			)
		)
	)
	(zone
		(layers "F.Cu" "In1.Cu" "In2.Cu" "In3.Cu" "In4.Cu" "In5.Cu" "In6.Cu" "In7.Cu"
			"In8.Cu" "In9.Cu" "In10.Cu" "In11.Cu" "In13.Cu" "In15.Cu" "In16.Cu"
		)
		(hatch none 0.5)
		(connect_pads
			(clearance 0)
		)
		(min_thickness 0.25)
		(keepout
			(tracks not_allowed)
			(vias allowed)
			(pads allowed)
			(copperpour not_allowed)
			(footprints allowed)
		)
		(placement
			(enabled no)
			(sheetname "")
		)
		(fill yes
			(thermal_gap 0.5)
			(thermal_bridge_width 0.5)
			(island_removal_mode 0)
		)
		(polygon
			(pts
				(arc
					(start 89.142062 -439.760614)
					(mid 89.16438 -439.814496)
					(end 89.218262 -439.836814)
				)
				(arc
					(start 90.158062 -439.836814)
					(mid 90.211944 -439.814496)
					(end 90.234262 -439.760614)
				)
				(arc
					(start 90.234262 -437.21909)
					(mid 90.211944 -437.165208)
					(end 90.158062 -437.14289)
				)
				(arc
					(start 89.218262 -437.14289)
					(mid 89.16438 -437.165208)
					(end 89.142062 -437.21909)
				)
			)
		)
	)
	(zone
		(layers "F.Cu" "In1.Cu" "In2.Cu" "In3.Cu" "In4.Cu" "In5.Cu" "In6.Cu" "In7.Cu"
			"In8.Cu" "In9.Cu" "In10.Cu" "In11.Cu" "In13.Cu" "In15.Cu" "In16.Cu"
		)
		(hatch none 0.5)
		(connect_pads
			(clearance 0)
		)
		(min_thickness 0.25)
		(keepout
			(tracks not_allowed)
			(vias allowed)
			(pads allowed)
			(copperpour not_allowed)
			(footprints allowed)
		)
		(placement
			(enabled no)
			(sheetname "")
		)
		(fill yes
			(thermal_gap 0.5)
			(thermal_bridge_width 0.5)
			(island_removal_mode 0)
		)
		(polygon
			(pts
				(arc
					(start 79.142082 -438.760616)
					(mid 79.1644 -438.814498)
					(end 79.218282 -438.836816)
				)
				(arc
					(start 80.158082 -438.836816)
					(mid 80.211964 -438.814498)
					(end 80.234282 -438.760616)
				)
				(arc
					(start 80.234282 -436.219092)
					(mid 80.211964 -436.16521)
					(end 80.158082 -436.142892)
				)
				(arc
					(start 79.218282 -436.142892)
					(mid 79.1644 -436.16521)
					(end 79.142082 -436.219092)
				)
			)
		)
	)
	(zone
		(layers "F.Cu" "In1.Cu" "In2.Cu" "In3.Cu" "In4.Cu" "In5.Cu" "In6.Cu" "In7.Cu"
			"In8.Cu" "In9.Cu" "In10.Cu" "In11.Cu" "In13.Cu" "In15.Cu" "In16.Cu"
		)
		(hatch none 0.5)
		(connect_pads
			(clearance 0)
		)
		(min_thickness 0.25)
		(keepout
			(tracks not_allowed)
			(vias allowed)
			(pads allowed)
			(copperpour not_allowed)
			(footprints allowed)
		)
		(placement
			(enabled no)
			(sheetname "")
		)
		(fill yes
			(thermal_gap 0.5)
			(thermal_bridge_width 0.5)
			(island_removal_mode 0)
		)
		(polygon
			(pts
				(arc
					(start 326.142096 -438.760616)
					(mid 326.164414 -438.814498)
					(end 326.218296 -438.836816)
				)
				(arc
					(start 327.158096 -438.836816)
					(mid 327.211978 -438.814498)
					(end 327.234296 -438.760616)
				)
				(arc
					(start 327.234296 -436.219092)
					(mid 327.211978 -436.16521)
					(end 327.158096 -436.142892)
				)
				(arc
					(start 326.218296 -436.142892)
					(mid 326.164414 -436.16521)
					(end 326.142096 -436.219092)
				)
			)
		)
	)
	(zone
		(layers "F.Cu" "In1.Cu" "In2.Cu" "In3.Cu" "In4.Cu" "In5.Cu" "In6.Cu" "In7.Cu"
			"In8.Cu" "In9.Cu" "In10.Cu" "In11.Cu" "In13.Cu" "In15.Cu" "In16.Cu"
		)
		(hatch none 0.5)
		(connect_pads
			(clearance 0)
		)
		(min_thickness 0.25)
		(keepout
			(tracks not_allowed)
			(vias allowed)
			(pads allowed)
			(copperpour not_allowed)
			(footprints allowed)
		)
		(placement
			(enabled no)
			(sheetname "")
		)
		(fill yes
			(thermal_gap 0.5)
			(thermal_bridge_width 0.5)
			(island_removal_mode 0)
		)
		(polygon
			(pts
				(arc
					(start 62.142116 -438.760616)
					(mid 62.164434 -438.814498)
					(end 62.218316 -438.836816)
				)
				(arc
					(start 63.158116 -438.836816)
					(mid 63.211998 -438.814498)
					(end 63.234316 -438.760616)
				)
				(arc
					(start 63.234316 -436.219092)
					(mid 63.211998 -436.16521)
					(end 63.158116 -436.142892)
				)
				(arc
					(start 62.218316 -436.142892)
					(mid 62.164434 -436.16521)
					(end 62.142116 -436.219092)
				)
			)
		)
	)
	(zone
		(layers "F.Cu" "In1.Cu" "In2.Cu" "In3.Cu" "In4.Cu" "In5.Cu" "In6.Cu" "In7.Cu"
			"In8.Cu" "In9.Cu" "In10.Cu" "In11.Cu" "In13.Cu" "In15.Cu" "In16.Cu"
		)
		(hatch none 0.5)
		(connect_pads
			(clearance 0)
		)
		(min_thickness 0.25)
		(keepout
			(tracks not_allowed)
			(vias allowed)
			(pads allowed)
			(copperpour not_allowed)
			(footprints allowed)
		)
		(placement
			(enabled no)
			(sheetname "")
		)
		(fill yes
			(thermal_gap 0.5)
			(thermal_bridge_width 0.5)
			(island_removal_mode 0)
		)
		(polygon
			(pts
				(arc
					(start 322.142104 -438.760616)
					(mid 322.164422 -438.814498)
					(end 322.218304 -438.836816)
				)
				(arc
					(start 323.158104 -438.836816)
					(mid 323.211986 -438.814498)
					(end 323.234304 -438.760616)
				)
				(arc
					(start 323.234304 -436.219092)
					(mid 323.211986 -436.16521)
					(end 323.158104 -436.142892)
				)
				(arc
					(start 322.218304 -436.142892)
					(mid 322.164422 -436.16521)
					(end 322.142104 -436.219092)
				)
			)
		)
	)
	(zone
		(layers "F.Cu" "In1.Cu" "In2.Cu" "In3.Cu" "In4.Cu" "In5.Cu" "In6.Cu" "In7.Cu"
			"In8.Cu" "In9.Cu" "In10.Cu" "In11.Cu" "In13.Cu" "In15.Cu" "In16.Cu"
		)
		(hatch none 0.5)
		(connect_pads
			(clearance 0)
		)
		(min_thickness 0.25)
		(keepout
			(tracks not_allowed)
			(vias allowed)
			(pads allowed)
			(copperpour not_allowed)
			(footprints allowed)
		)
		(placement
			(enabled no)
			(sheetname "")
		)
		(fill yes
			(thermal_gap 0.5)
			(thermal_bridge_width 0.5)
			(island_removal_mode 0)
		)
		(polygon
			(pts
				(arc
					(start 339.14207 -438.760616)
					(mid 339.164388 -438.814498)
					(end 339.21827 -438.836816)
				)
				(arc
					(start 340.15807 -438.836816)
					(mid 340.211952 -438.814498)
					(end 340.23427 -438.760616)
				)
				(arc
					(start 340.23427 -436.219092)
					(mid 340.211952 -436.16521)
					(end 340.15807 -436.142892)
				)
				(arc
					(start 339.21827 -436.142892)
					(mid 339.164388 -436.16521)
					(end 339.14207 -436.219092)
				)
			)
		)
	)
	(zone
		(layers "F.Cu" "In1.Cu" "In2.Cu" "In3.Cu" "In4.Cu" "In5.Cu" "In6.Cu" "In7.Cu"
			"In8.Cu" "In9.Cu" "In10.Cu" "In11.Cu" "In13.Cu" "In15.Cu" "In16.Cu"
		)
		(hatch none 0.5)
		(connect_pads
			(clearance 0)
		)
		(min_thickness 0.25)
		(keepout
			(tracks not_allowed)
			(vias allowed)
			(pads allowed)
			(copperpour not_allowed)
			(footprints allowed)
		)
		(placement
			(enabled no)
			(sheetname "")
		)
		(fill yes
			(thermal_gap 0.5)
			(thermal_bridge_width 0.5)
			(island_removal_mode 0)
		)
		(polygon
			(pts
				(arc
					(start 345.142058 -439.760614)
					(mid 345.164376 -439.814496)
					(end 345.218258 -439.836814)
				)
				(arc
					(start 346.158058 -439.836814)
					(mid 346.21194 -439.814496)
					(end 346.234258 -439.760614)
				)
				(arc
					(start 346.234258 -437.21909)
					(mid 346.21194 -437.165208)
					(end 346.158058 -437.14289)
				)
				(arc
					(start 345.218258 -437.14289)
					(mid 345.164376 -437.165208)
					(end 345.142058 -437.21909)
				)
			)
		)
	)
	(zone
		(layers "F.Cu" "In1.Cu" "In2.Cu" "In3.Cu" "In4.Cu" "In5.Cu" "In6.Cu" "In7.Cu"
			"In8.Cu" "In9.Cu" "In10.Cu" "In11.Cu" "In13.Cu" "In15.Cu" "In16.Cu"
		)
		(hatch none 0.5)
		(connect_pads
			(clearance 0)
		)
		(min_thickness 0.25)
		(keepout
			(tracks not_allowed)
			(vias allowed)
			(pads allowed)
			(copperpour not_allowed)
			(footprints allowed)
		)
		(placement
			(enabled no)
			(sheetname "")
		)
		(fill yes
			(thermal_gap 0.5)
			(thermal_bridge_width 0.5)
			(island_removal_mode 0)
		)
		(polygon
			(pts
				(arc
					(start 77.142086 -439.760614)
					(mid 77.164404 -439.814496)
					(end 77.218286 -439.836814)
				)
				(arc
					(start 78.158086 -439.836814)
					(mid 78.211968 -439.814496)
					(end 78.234286 -439.760614)
				)
				(arc
					(start 78.234286 -437.21909)
					(mid 78.211968 -437.165208)
					(end 78.158086 -437.14289)
				)
				(arc
					(start 77.218286 -437.14289)
					(mid 77.164404 -437.165208)
					(end 77.142086 -437.21909)
				)
			)
		)
	)
	(zone
		(layers "F.Cu" "In1.Cu" "In2.Cu" "In3.Cu" "In4.Cu" "In5.Cu" "In6.Cu" "In7.Cu"
			"In8.Cu" "In9.Cu" "In10.Cu" "In11.Cu" "In13.Cu" "In15.Cu" "In16.Cu"
		)
		(hatch none 0.5)
		(connect_pads
			(clearance 0)
		)
		(min_thickness 0.25)
		(keepout
			(tracks not_allowed)
			(vias allowed)
			(pads allowed)
			(copperpour not_allowed)
			(footprints allowed)
		)
		(placement
			(enabled no)
			(sheetname "")
		)
		(fill yes
			(thermal_gap 0.5)
			(thermal_bridge_width 0.5)
			(island_removal_mode 0)
		)
		(polygon
			(pts
				(arc
					(start 85.14207 -439.760614)
					(mid 85.164388 -439.814496)
					(end 85.21827 -439.836814)
				)
				(arc
					(start 86.15807 -439.836814)
					(mid 86.211952 -439.814496)
					(end 86.23427 -439.760614)
				)
				(arc
					(start 86.23427 -437.21909)
					(mid 86.211952 -437.165208)
					(end 86.15807 -437.14289)
				)
				(arc
					(start 85.21827 -437.14289)
					(mid 85.164388 -437.165208)
					(end 85.14207 -437.21909)
				)
			)
		)
	)
	(zone
		(layers "F.Cu" "In1.Cu" "In2.Cu" "In3.Cu" "In4.Cu" "In5.Cu" "In6.Cu" "In7.Cu"
			"In8.Cu" "In9.Cu" "In10.Cu" "In11.Cu" "In13.Cu" "In15.Cu" "In16.Cu"
		)
		(hatch none 0.5)
		(connect_pads
			(clearance 0)
		)
		(min_thickness 0.25)
		(keepout
			(tracks not_allowed)
			(vias allowed)
			(pads allowed)
			(copperpour not_allowed)
			(footprints allowed)
		)
		(placement
			(enabled no)
			(sheetname "")
		)
		(fill yes
			(thermal_gap 0.5)
			(thermal_bridge_width 0.5)
			(island_removal_mode 0)
		)
		(polygon
			(pts
				(arc
					(start 337.142074 -439.760614)
					(mid 337.164392 -439.814496)
					(end 337.218274 -439.836814)
				)
				(arc
					(start 338.158074 -439.836814)
					(mid 338.211956 -439.814496)
					(end 338.234274 -439.760614)
				)
				(arc
					(start 338.234274 -437.21909)
					(mid 338.211956 -437.165208)
					(end 338.158074 -437.14289)
				)
				(arc
					(start 337.218274 -437.14289)
					(mid 337.164392 -437.165208)
					(end 337.142074 -437.21909)
				)
			)
		)
	)
	(zone
		(layers "F.Cu" "In1.Cu" "In2.Cu" "In3.Cu" "In4.Cu" "In5.Cu" "In6.Cu" "In7.Cu"
			"In8.Cu" "In9.Cu" "In10.Cu" "In11.Cu" "In13.Cu" "In15.Cu" "In16.Cu"
		)
		(hatch none 0.5)
		(connect_pads
			(clearance 0)
		)
		(min_thickness 0.25)
		(keepout
			(tracks not_allowed)
			(vias allowed)
			(pads allowed)
			(copperpour not_allowed)
			(footprints allowed)
		)
		(placement
			(enabled no)
			(sheetname "")
		)
		(fill yes
			(thermal_gap 0.5)
			(thermal_bridge_width 0.5)
			(island_removal_mode 0)
		)
		(polygon
			(pts
				(arc
					(start 318.142112 -438.760616)
					(mid 318.16443 -438.814498)
					(end 318.218312 -438.836816)
				)
				(arc
					(start 319.158112 -438.836816)
					(mid 319.211994 -438.814498)
					(end 319.234312 -438.760616)
				)
				(arc
					(start 319.234312 -436.219092)
					(mid 319.211994 -436.16521)
					(end 319.158112 -436.142892)
				)
				(arc
					(start 318.218312 -436.142892)
					(mid 318.16443 -436.16521)
					(end 318.142112 -436.219092)
				)
			)
		)
	)
	(zone
		(layers "F.Cu" "In1.Cu" "In2.Cu" "In3.Cu" "In4.Cu" "In5.Cu" "In6.Cu" "In7.Cu"
			"In8.Cu" "In9.Cu" "In10.Cu" "In11.Cu" "In13.Cu" "In15.Cu" "In16.Cu"
		)
		(hatch none 0.5)
		(connect_pads
			(clearance 0)
		)
		(min_thickness 0.25)
		(keepout
			(tracks not_allowed)
			(vias allowed)
			(pads allowed)
			(copperpour not_allowed)
			(footprints allowed)
		)
		(placement
			(enabled no)
			(sheetname "")
		)
		(fill yes
			(thermal_gap 0.5)
			(thermal_bridge_width 0.5)
			(island_removal_mode 0)
		)
		(polygon
			(pts
				(arc
					(start 75.14209 -438.760616)
					(mid 75.164408 -438.814498)
					(end 75.21829 -438.836816)
				)
				(arc
					(start 76.15809 -438.836816)
					(mid 76.211972 -438.814498)
					(end 76.23429 -438.760616)
				)
				(arc
					(start 76.23429 -436.219092)
					(mid 76.211972 -436.16521)
					(end 76.15809 -436.142892)
				)
				(arc
					(start 75.21829 -436.142892)
					(mid 75.164408 -436.16521)
					(end 75.14209 -436.219092)
				)
			)
		)
	)
	(zone
		(layers "F.Cu" "In1.Cu" "In2.Cu" "In3.Cu" "In4.Cu" "In5.Cu" "In6.Cu" "In7.Cu"
			"In8.Cu" "In9.Cu" "In10.Cu" "In11.Cu" "In13.Cu" "In15.Cu" "In16.Cu"
		)
		(hatch none 0.5)
		(connect_pads
			(clearance 0)
		)
		(min_thickness 0.25)
		(keepout
			(tracks not_allowed)
			(vias allowed)
			(pads allowed)
			(copperpour not_allowed)
			(footprints allowed)
		)
		(placement
			(enabled no)
			(sheetname "")
		)
		(fill yes
			(thermal_gap 0.5)
			(thermal_bridge_width 0.5)
			(island_removal_mode 0)
		)
		(polygon
			(pts
				(arc
					(start 66.142108 -438.760616)
					(mid 66.164426 -438.814498)
					(end 66.218308 -438.836816)
				)
				(arc
					(start 67.158108 -438.836816)
					(mid 67.21199 -438.814498)
					(end 67.234308 -438.760616)
				)
				(arc
					(start 67.234308 -436.219092)
					(mid 67.21199 -436.16521)
					(end 67.158108 -436.142892)
				)
				(arc
					(start 66.218308 -436.142892)
					(mid 66.164426 -436.16521)
					(end 66.142108 -436.219092)
				)
			)
		)
	)
	(zone
		(layers "F.Cu" "In1.Cu" "In2.Cu" "In3.Cu" "In4.Cu" "In5.Cu" "In6.Cu" "In7.Cu"
			"In8.Cu" "In9.Cu" "In10.Cu" "In11.Cu" "In13.Cu" "In15.Cu" "In16.Cu"
		)
		(hatch none 0.5)
		(connect_pads
			(clearance 0)
		)
		(min_thickness 0.25)
		(keepout
			(tracks not_allowed)
			(vias allowed)
			(pads allowed)
			(copperpour not_allowed)
			(footprints allowed)
		)
		(placement
			(enabled no)
			(sheetname "")
		)
		(fill yes
			(thermal_gap 0.5)
			(thermal_bridge_width 0.5)
			(island_removal_mode 0)
		)
		(polygon
			(pts
				(arc
					(start 72.142096 -439.760614)
					(mid 72.164414 -439.814496)
					(end 72.218296 -439.836814)
				)
				(arc
					(start 73.158096 -439.836814)
					(mid 73.211978 -439.814496)
					(end 73.234296 -439.760614)
				)
				(arc
					(start 73.234296 -437.21909)
					(mid 73.211978 -437.165208)
					(end 73.158096 -437.14289)
				)
				(arc
					(start 72.218296 -437.14289)
					(mid 72.164414 -437.165208)
					(end 72.142096 -437.21909)
				)
			)
		)
	)
	(zone
		(layers "F.Cu" "In1.Cu" "In2.Cu" "In3.Cu" "In4.Cu" "In5.Cu" "In6.Cu" "In7.Cu"
			"In8.Cu" "In9.Cu" "In10.Cu" "In11.Cu" "In13.Cu" "In15.Cu" "In16.Cu"
		)
		(hatch none 0.5)
		(connect_pads
			(clearance 0)
		)
		(min_thickness 0.25)
		(keepout
			(tracks not_allowed)
			(vias allowed)
			(pads allowed)
			(copperpour not_allowed)
			(footprints allowed)
		)
		(placement
			(enabled no)
			(sheetname "")
		)
		(fill yes
			(thermal_gap 0.5)
			(thermal_bridge_width 0.5)
			(island_removal_mode 0)
		)
		(polygon
			(pts
				(arc
					(start 320.142108 -439.760614)
					(mid 320.164426 -439.814496)
					(end 320.218308 -439.836814)
				)
				(arc
					(start 321.158108 -439.836814)
					(mid 321.21199 -439.814496)
					(end 321.234308 -439.760614)
				)
				(arc
					(start 321.234308 -437.21909)
					(mid 321.21199 -437.165208)
					(end 321.158108 -437.14289)
				)
				(arc
					(start 320.218308 -437.14289)
					(mid 320.164426 -437.165208)
					(end 320.142108 -437.21909)
				)
			)
		)
	)
	(zone
		(layers "F.Cu" "In1.Cu" "In2.Cu" "In3.Cu" "In4.Cu" "In5.Cu" "In6.Cu" "In7.Cu"
			"In8.Cu" "In9.Cu" "In10.Cu" "In11.Cu" "In13.Cu" "In15.Cu" "In16.Cu"
		)
		(hatch none 0.5)
		(connect_pads
			(clearance 0)
		)
		(min_thickness 0.25)
		(keepout
			(tracks not_allowed)
			(vias allowed)
			(pads allowed)
			(copperpour not_allowed)
			(footprints allowed)
		)
		(placement
			(enabled no)
			(sheetname "")
		)
		(fill yes
			(thermal_gap 0.5)
			(thermal_bridge_width 0.5)
			(island_removal_mode 0)
		)
		(polygon
			(pts
				(arc
					(start 60.14212 -439.760614)
					(mid 60.164438 -439.814496)
					(end 60.21832 -439.836814)
				)
				(arc
					(start 61.15812 -439.836814)
					(mid 61.212002 -439.814496)
					(end 61.23432 -439.760614)
				)
				(arc
					(start 61.23432 -437.21909)
					(mid 61.212002 -437.165208)
					(end 61.15812 -437.14289)
				)
				(arc
					(start 60.21832 -437.14289)
					(mid 60.164438 -437.165208)
					(end 60.14212 -437.21909)
				)
			)
		)
	)
	(zone
		(layers "F.Cu" "In1.Cu" "In2.Cu" "In3.Cu" "In4.Cu" "In5.Cu" "In6.Cu" "In7.Cu"
			"In8.Cu" "In9.Cu" "In10.Cu" "In11.Cu" "In13.Cu" "In15.Cu" "In16.Cu"
		)
		(hatch none 0.5)
		(connect_pads
			(clearance 0)
		)
		(min_thickness 0.25)
		(keepout
			(tracks not_allowed)
			(vias allowed)
			(pads allowed)
			(copperpour not_allowed)
			(footprints allowed)
		)
		(placement
			(enabled no)
			(sheetname "")
		)
		(fill yes
			(thermal_gap 0.5)
			(thermal_bridge_width 0.5)
			(island_removal_mode 0)
		)
		(polygon
			(pts
				(arc
					(start 335.142078 -438.760616)
					(mid 335.164396 -438.814498)
					(end 335.218278 -438.836816)
				)
				(arc
					(start 336.158078 -438.836816)
					(mid 336.21196 -438.814498)
					(end 336.234278 -438.760616)
				)
				(arc
					(start 336.234278 -436.219092)
					(mid 336.21196 -436.16521)
					(end 336.158078 -436.142892)
				)
				(arc
					(start 335.218278 -436.142892)
					(mid 335.164396 -436.16521)
					(end 335.142078 -436.219092)
				)
			)
		)
	)
	(zone
		(layers "F.Cu" "In1.Cu" "In2.Cu" "In3.Cu" "In4.Cu" "In5.Cu" "In6.Cu" "In7.Cu"
			"In8.Cu" "In9.Cu" "In10.Cu" "In11.Cu" "In13.Cu" "In15.Cu" "In16.Cu"
		)
		(hatch none 0.5)
		(connect_pads
			(clearance 0)
		)
		(min_thickness 0.25)
		(keepout
			(tracks not_allowed)
			(vias allowed)
			(pads allowed)
			(copperpour not_allowed)
			(footprints allowed)
		)
		(placement
			(enabled no)
			(sheetname "")
		)
		(fill yes
			(thermal_gap 0.5)
			(thermal_bridge_width 0.5)
			(island_removal_mode 0)
		)
		(polygon
			(pts
				(arc
					(start 64.142112 -439.760614)
					(mid 64.16443 -439.814496)
					(end 64.218312 -439.836814)
				)
				(arc
					(start 65.158112 -439.836814)
					(mid 65.211994 -439.814496)
					(end 65.234312 -439.760614)
				)
				(arc
					(start 65.234312 -437.21909)
					(mid 65.211994 -437.165208)
					(end 65.158112 -437.14289)
				)
				(arc
					(start 64.218312 -437.14289)
					(mid 64.16443 -437.165208)
					(end 64.142112 -437.21909)
				)
			)
		)
	)
	(zone
		(layers "F.Cu" "In1.Cu" "In2.Cu" "In3.Cu" "In4.Cu" "In5.Cu" "In6.Cu" "In7.Cu"
			"In8.Cu" "In9.Cu" "In10.Cu" "In11.Cu" "In13.Cu" "In15.Cu" "In16.Cu"
		)
		(hatch none 0.5)
		(connect_pads
			(clearance 0)
		)
		(min_thickness 0.25)
		(keepout
			(tracks not_allowed)
			(vias allowed)
			(pads allowed)
			(copperpour not_allowed)
			(footprints allowed)
		)
		(placement
			(enabled no)
			(sheetname "")
		)
		(fill yes
			(thermal_gap 0.5)
			(thermal_bridge_width 0.5)
			(island_removal_mode 0)
		)
		(polygon
			(pts
				(arc
					(start 81.142078 -439.760614)
					(mid 81.164396 -439.814496)
					(end 81.218278 -439.836814)
				)
				(arc
					(start 82.158078 -439.836814)
					(mid 82.21196 -439.814496)
					(end 82.234278 -439.760614)
				)
				(arc
					(start 82.234278 -437.21909)
					(mid 82.21196 -437.165208)
					(end 82.158078 -437.14289)
				)
				(arc
					(start 81.218278 -437.14289)
					(mid 81.164396 -437.165208)
					(end 81.142078 -437.21909)
				)
			)
		)
	)
	(zone
		(layers "F.Cu" "In1.Cu" "In2.Cu" "In3.Cu" "In4.Cu" "In5.Cu" "In6.Cu" "In7.Cu"
			"In8.Cu" "In9.Cu" "In10.Cu" "In11.Cu" "In13.Cu" "In15.Cu" "In16.Cu"
		)
		(hatch none 0.5)
		(connect_pads
			(clearance 0)
		)
		(min_thickness 0.25)
		(keepout
			(tracks not_allowed)
			(vias allowed)
			(pads allowed)
			(copperpour not_allowed)
			(footprints allowed)
		)
		(placement
			(enabled no)
			(sheetname "")
		)
		(fill yes
			(thermal_gap 0.5)
			(thermal_bridge_width 0.5)
			(island_removal_mode 0)
		)
		(polygon
			(pts
				(arc
					(start 70.1421 -438.760616)
					(mid 70.164418 -438.814498)
					(end 70.2183 -438.836816)
				)
				(arc
					(start 71.1581 -438.836816)
					(mid 71.211982 -438.814498)
					(end 71.2343 -438.760616)
				)
				(arc
					(start 71.2343 -436.219092)
					(mid 71.211982 -436.16521)
					(end 71.1581 -436.142892)
				)
				(arc
					(start 70.2183 -436.142892)
					(mid 70.164418 -436.16521)
					(end 70.1421 -436.219092)
				)
			)
		)
	)
	(zone
		(layers "F.Cu" "In1.Cu" "In2.Cu" "In3.Cu" "In4.Cu" "In5.Cu" "In6.Cu" "In7.Cu"
			"In8.Cu" "In9.Cu" "In10.Cu" "In11.Cu" "In13.Cu" "In15.Cu" "In16.Cu"
		)
		(hatch none 0.5)
		(connect_pads
			(clearance 0)
		)
		(min_thickness 0.25)
		(keepout
			(tracks not_allowed)
			(vias allowed)
			(pads allowed)
			(copperpour not_allowed)
			(footprints allowed)
		)
		(placement
			(enabled no)
			(sheetname "")
		)
		(fill yes
			(thermal_gap 0.5)
			(thermal_bridge_width 0.5)
			(island_removal_mode 0)
		)
		(polygon
			(pts
				(arc
					(start 68.142104 -439.760614)
					(mid 68.164422 -439.814496)
					(end 68.218304 -439.836814)
				)
				(arc
					(start 69.158104 -439.836814)
					(mid 69.211986 -439.814496)
					(end 69.234304 -439.760614)
				)
				(arc
					(start 69.234304 -437.21909)
					(mid 69.211986 -437.165208)
					(end 69.158104 -437.14289)
				)
				(arc
					(start 68.218304 -437.14289)
					(mid 68.164422 -437.165208)
					(end 68.142104 -437.21909)
				)
			)
		)
	)
	(zone
		(layers "F.Cu" "In1.Cu" "In2.Cu" "In3.Cu" "In4.Cu" "In5.Cu" "In6.Cu" "In7.Cu"
			"In8.Cu" "In9.Cu" "In10.Cu" "In11.Cu" "In13.Cu" "In15.Cu" "In16.Cu"
		)
		(hatch none 0.5)
		(connect_pads
			(clearance 0)
		)
		(min_thickness 0.25)
		(keepout
			(tracks not_allowed)
			(vias allowed)
			(pads allowed)
			(copperpour not_allowed)
			(footprints allowed)
		)
		(placement
			(enabled no)
			(sheetname "")
		)
		(fill yes
			(thermal_gap 0.5)
			(thermal_bridge_width 0.5)
			(island_removal_mode 0)
		)
		(polygon
			(pts
				(arc
					(start 316.142116 -439.760614)
					(mid 316.164434 -439.814496)
					(end 316.218316 -439.836814)
				)
				(arc
					(start 317.158116 -439.836814)
					(mid 317.211998 -439.814496)
					(end 317.234316 -439.760614)
				)
				(arc
					(start 317.234316 -437.21909)
					(mid 317.211998 -437.165208)
					(end 317.158116 -437.14289)
				)
				(arc
					(start 316.218316 -437.14289)
					(mid 316.164434 -437.165208)
					(end 316.142116 -437.21909)
				)
			)
		)
	)
	(zone
		(layers "F.Cu" "In1.Cu" "In2.Cu" "In3.Cu" "In4.Cu" "In5.Cu" "In6.Cu" "In7.Cu"
			"In8.Cu" "In9.Cu" "In10.Cu" "In11.Cu" "In13.Cu" "In15.Cu" "In16.Cu"
		)
		(hatch none 0.5)
		(connect_pads
			(clearance 0)
		)
		(min_thickness 0.25)
		(keepout
			(tracks not_allowed)
			(vias allowed)
			(pads allowed)
			(copperpour not_allowed)
			(footprints allowed)
		)
		(placement
			(enabled no)
			(sheetname "")
		)
		(fill yes
			(thermal_gap 0.5)
			(thermal_bridge_width 0.5)
			(island_removal_mode 0)
		)
		(polygon
			(pts
				(arc
					(start 331.142086 -438.760616)
					(mid 331.164404 -438.814498)
					(end 331.218286 -438.836816)
				)
				(arc
					(start 332.158086 -438.836816)
					(mid 332.211968 -438.814498)
					(end 332.234286 -438.760616)
				)
				(arc
					(start 332.234286 -436.219092)
					(mid 332.211968 -436.16521)
					(end 332.158086 -436.142892)
				)
				(arc
					(start 331.218286 -436.142892)
					(mid 331.164404 -436.16521)
					(end 331.142086 -436.219092)
				)
			)
		)
	)
	(zone
		(layers "F.Cu" "In1.Cu" "In2.Cu" "In3.Cu" "In4.Cu" "In5.Cu" "In6.Cu" "In7.Cu"
			"In8.Cu" "In9.Cu" "In10.Cu" "In11.Cu" "In13.Cu" "In15.Cu" "In16.Cu"
		)
		(hatch none 0.5)
		(connect_pads
			(clearance 0)
		)
		(min_thickness 0.25)
		(keepout
			(tracks not_allowed)
			(vias allowed)
			(pads allowed)
			(copperpour not_allowed)
			(footprints allowed)
		)
		(placement
			(enabled no)
			(sheetname "")
		)
		(fill yes
			(thermal_gap 0.5)
			(thermal_bridge_width 0.5)
			(island_removal_mode 0)
		)
		(polygon
			(pts
				(arc
					(start 314.14212 -438.760616)
					(mid 314.164438 -438.814498)
					(end 314.21832 -438.836816)
				)
				(arc
					(start 315.15812 -438.836816)
					(mid 315.212002 -438.814498)
					(end 315.23432 -438.760616)
				)
				(arc
					(start 315.23432 -436.219092)
					(mid 315.212002 -436.16521)
					(end 315.15812 -436.142892)
				)
				(arc
					(start 314.21832 -436.142892)
					(mid 314.164438 -436.16521)
					(end 314.14212 -436.219092)
				)
			)
		)
	)
	(zone
		(layers "F.Cu" "In1.Cu" "In2.Cu" "In3.Cu" "In4.Cu" "In5.Cu" "In6.Cu" "In7.Cu"
			"In8.Cu" "In9.Cu" "In10.Cu" "In11.Cu" "In13.Cu" "In15.Cu" "In16.Cu"
		)
		(hatch none 0.5)
		(connect_pads
			(clearance 0)
		)
		(min_thickness 0.25)
		(keepout
			(tracks not_allowed)
			(vias allowed)
			(pads allowed)
			(copperpour not_allowed)
			(footprints allowed)
		)
		(placement
			(enabled no)
			(sheetname "")
		)
		(fill yes
			(thermal_gap 0.5)
			(thermal_bridge_width 0.5)
			(island_removal_mode 0)
		)
		(polygon
			(pts
				(arc
					(start 333.142082 -439.760614)
					(mid 333.1644 -439.814496)
					(end 333.218282 -439.836814)
				)
				(arc
					(start 334.158082 -439.836814)
					(mid 334.211964 -439.814496)
					(end 334.234282 -439.760614)
				)
				(arc
					(start 334.234282 -437.21909)
					(mid 334.211964 -437.165208)
					(end 334.158082 -437.14289)
				)
				(arc
					(start 333.218282 -437.14289)
					(mid 333.1644 -437.165208)
					(end 333.142082 -437.21909)
				)
			)
		)
	)
	(zone
		(layers "F.Cu" "In1.Cu" "In2.Cu" "In3.Cu" "In4.Cu" "In5.Cu" "In6.Cu" "In7.Cu"
			"In8.Cu" "In9.Cu" "In10.Cu" "In11.Cu" "In13.Cu" "In15.Cu" "In16.Cu"
		)
		(hatch none 0.5)
		(connect_pads
			(clearance 0)
		)
		(min_thickness 0.25)
		(keepout
			(tracks not_allowed)
			(vias allowed)
			(pads allowed)
			(copperpour not_allowed)
			(footprints allowed)
		)
		(placement
			(enabled no)
			(sheetname "")
		)
		(fill yes
			(thermal_gap 0.5)
			(thermal_bridge_width 0.5)
			(island_removal_mode 0)
		)
		(polygon
			(pts
				(arc
					(start 343.142062 -438.760616)
					(mid 343.16438 -438.814498)
					(end 343.218262 -438.836816)
				)
				(arc
					(start 344.158062 -438.836816)
					(mid 344.211944 -438.814498)
					(end 344.234262 -438.760616)
				)
				(arc
					(start 344.234262 -436.219092)
					(mid 344.211944 -436.16521)
					(end 344.158062 -436.142892)
				)
				(arc
					(start 343.218262 -436.142892)
					(mid 343.16438 -436.16521)
					(end 343.142062 -436.219092)
				)
			)
		)
	)
	(zone
		(layers "F.Cu" "In1.Cu" "In2.Cu" "In3.Cu" "In4.Cu" "In5.Cu" "In6.Cu" "In7.Cu"
			"In8.Cu" "In9.Cu" "In13.Cu" "In14.Cu" "In15.Cu" "In16.Cu"
		)
		(hatch none 0.5)
		(connect_pads
			(clearance 0)
		)
		(min_thickness 0.25)
		(keepout
			(tracks not_allowed)
			(vias allowed)
			(pads allowed)
			(copperpour not_allowed)
			(footprints allowed)
		)
		(placement
			(enabled no)
			(sheetname "")
		)
		(fill yes
			(thermal_gap 0.5)
			(thermal_bridge_width 0.5)
			(island_removal_mode 0)
		)
		(polygon
			(pts
				(arc
					(start 412.242 -428.960534)
					(mid 412.264318 -429.014416)
					(end 412.3182 -429.036734)
				)
				(arc
					(start 413.258 -429.036734)
					(mid 413.311882 -429.014416)
					(end 413.3342 -428.960534)
				)
				(arc
					(start 413.3342 -426.41901)
					(mid 413.311882 -426.365128)
					(end 413.258 -426.34281)
				)
				(arc
					(start 412.3182 -426.34281)
					(mid 412.264318 -426.365128)
					(end 412.242 -426.41901)
				)
			)
		)
	)
	(zone
		(layers "F.Cu" "In1.Cu" "In2.Cu" "In3.Cu" "In4.Cu" "In5.Cu" "In6.Cu" "In7.Cu"
			"In8.Cu" "In9.Cu" "In13.Cu" "In14.Cu" "In15.Cu" "In16.Cu"
		)
		(hatch none 0.5)
		(connect_pads
			(clearance 0)
		)
		(min_thickness 0.25)
		(keepout
			(tracks not_allowed)
			(vias allowed)
			(pads allowed)
			(copperpour not_allowed)
			(footprints allowed)
		)
		(placement
			(enabled no)
			(sheetname "")
		)
		(fill yes
			(thermal_gap 0.5)
			(thermal_bridge_width 0.5)
			(island_removal_mode 0)
		)
		(polygon
			(pts
				(arc
					(start 383.242058 -428.960534)
					(mid 383.264376 -429.014416)
					(end 383.318258 -429.036734)
				)
				(arc
					(start 384.258058 -429.036734)
					(mid 384.31194 -429.014416)
					(end 384.334258 -428.960534)
				)
				(arc
					(start 384.334258 -426.41901)
					(mid 384.31194 -426.365128)
					(end 384.258058 -426.34281)
				)
				(arc
					(start 383.318258 -426.34281)
					(mid 383.264376 -426.365128)
					(end 383.242058 -426.41901)
				)
			)
		)
	)
	(zone
		(layers "F.Cu" "In1.Cu" "In2.Cu" "In3.Cu" "In4.Cu" "In5.Cu" "In6.Cu" "In7.Cu"
			"In8.Cu" "In9.Cu" "In13.Cu" "In14.Cu" "In15.Cu" "In16.Cu"
		)
		(hatch none 0.5)
		(connect_pads
			(clearance 0)
		)
		(min_thickness 0.25)
		(keepout
			(tracks not_allowed)
			(vias allowed)
			(pads allowed)
			(copperpour not_allowed)
			(footprints allowed)
		)
		(placement
			(enabled no)
			(sheetname "")
		)
		(fill yes
			(thermal_gap 0.5)
			(thermal_bridge_width 0.5)
			(island_removal_mode 0)
		)
		(polygon
			(pts
				(arc
					(start 148.24202 -428.960534)
					(mid 148.264338 -429.014416)
					(end 148.31822 -429.036734)
				)
				(arc
					(start 149.25802 -429.036734)
					(mid 149.311902 -429.014416)
					(end 149.33422 -428.960534)
				)
				(arc
					(start 149.33422 -426.41901)
					(mid 149.311902 -426.365128)
					(end 149.25802 -426.34281)
				)
				(arc
					(start 148.31822 -426.34281)
					(mid 148.264338 -426.365128)
					(end 148.24202 -426.41901)
				)
			)
		)
	)
	(zone
		(layers "F.Cu" "In1.Cu" "In2.Cu" "In3.Cu" "In4.Cu" "In5.Cu" "In6.Cu" "In7.Cu"
			"In8.Cu" "In9.Cu" "In13.Cu" "In14.Cu" "In15.Cu" "In16.Cu"
		)
		(hatch none 0.5)
		(connect_pads
			(clearance 0)
		)
		(min_thickness 0.25)
		(keepout
			(tracks not_allowed)
			(vias allowed)
			(pads allowed)
			(copperpour not_allowed)
			(footprints allowed)
		)
		(placement
			(enabled no)
			(sheetname "")
		)
		(fill yes
			(thermal_gap 0.5)
			(thermal_bridge_width 0.5)
			(island_removal_mode 0)
		)
		(polygon
			(pts
				(arc
					(start 391.242042 -428.960534)
					(mid 391.26436 -429.014416)
					(end 391.318242 -429.036734)
				)
				(arc
					(start 392.258042 -429.036734)
					(mid 392.311924 -429.014416)
					(end 392.334242 -428.960534)
				)
				(arc
					(start 392.334242 -426.41901)
					(mid 392.311924 -426.365128)
					(end 392.258042 -426.34281)
				)
				(arc
					(start 391.318242 -426.34281)
					(mid 391.26436 -426.365128)
					(end 391.242042 -426.41901)
				)
			)
		)
	)
	(zone
		(layers "F.Cu" "In1.Cu" "In2.Cu" "In3.Cu" "In4.Cu" "In5.Cu" "In6.Cu" "In7.Cu"
			"In8.Cu" "In9.Cu" "In13.Cu" "In14.Cu" "In15.Cu" "In16.Cu"
		)
		(hatch none 0.5)
		(connect_pads
			(clearance 0)
		)
		(min_thickness 0.25)
		(keepout
			(tracks not_allowed)
			(vias allowed)
			(pads allowed)
			(copperpour not_allowed)
			(footprints allowed)
		)
		(placement
			(enabled no)
			(sheetname "")
		)
		(fill yes
			(thermal_gap 0.5)
			(thermal_bridge_width 0.5)
			(island_removal_mode 0)
		)
		(polygon
			(pts
				(arc
					(start 144.242028 -428.960534)
					(mid 144.264346 -429.014416)
					(end 144.318228 -429.036734)
				)
				(arc
					(start 145.258028 -429.036734)
					(mid 145.31191 -429.014416)
					(end 145.334228 -428.960534)
				)
				(arc
					(start 145.334228 -426.41901)
					(mid 145.31191 -426.365128)
					(end 145.258028 -426.34281)
				)
				(arc
					(start 144.318228 -426.34281)
					(mid 144.264346 -426.365128)
					(end 144.242028 -426.41901)
				)
			)
		)
	)
	(zone
		(layers "F.Cu" "In1.Cu" "In2.Cu" "In3.Cu" "In4.Cu" "In5.Cu" "In6.Cu" "In7.Cu"
			"In8.Cu" "In9.Cu" "In13.Cu" "In14.Cu" "In15.Cu" "In16.Cu"
		)
		(hatch none 0.5)
		(connect_pads
			(clearance 0)
		)
		(min_thickness 0.25)
		(keepout
			(tracks not_allowed)
			(vias allowed)
			(pads allowed)
			(copperpour not_allowed)
			(footprints allowed)
		)
		(placement
			(enabled no)
			(sheetname "")
		)
		(fill yes
			(thermal_gap 0.5)
			(thermal_bridge_width 0.5)
			(island_removal_mode 0)
		)
		(polygon
			(pts
				(arc
					(start 139.242038 -428.960534)
					(mid 139.264356 -429.014416)
					(end 139.318238 -429.036734)
				)
				(arc
					(start 140.258038 -429.036734)
					(mid 140.31192 -429.014416)
					(end 140.334238 -428.960534)
				)
				(arc
					(start 140.334238 -426.41901)
					(mid 140.31192 -426.365128)
					(end 140.258038 -426.34281)
				)
				(arc
					(start 139.318238 -426.34281)
					(mid 139.264356 -426.365128)
					(end 139.242038 -426.41901)
				)
			)
		)
	)
	(zone
		(layers "F.Cu" "In1.Cu" "In2.Cu" "In3.Cu" "In4.Cu" "In5.Cu" "In6.Cu" "In7.Cu"
			"In8.Cu" "In9.Cu" "In13.Cu" "In14.Cu" "In15.Cu" "In16.Cu"
		)
		(hatch none 0.5)
		(connect_pads
			(clearance 0)
		)
		(min_thickness 0.25)
		(keepout
			(tracks not_allowed)
			(vias allowed)
			(pads allowed)
			(copperpour not_allowed)
			(footprints allowed)
		)
		(placement
			(enabled no)
			(sheetname "")
		)
		(fill yes
			(thermal_gap 0.5)
			(thermal_bridge_width 0.5)
			(island_removal_mode 0)
		)
		(polygon
			(pts
				(arc
					(start 131.242054 -428.960534)
					(mid 131.264372 -429.014416)
					(end 131.318254 -429.036734)
				)
				(arc
					(start 132.258054 -429.036734)
					(mid 132.311936 -429.014416)
					(end 132.334254 -428.960534)
				)
				(arc
					(start 132.334254 -426.41901)
					(mid 132.311936 -426.365128)
					(end 132.258054 -426.34281)
				)
				(arc
					(start 131.318254 -426.34281)
					(mid 131.264372 -426.365128)
					(end 131.242054 -426.41901)
				)
			)
		)
	)
	(zone
		(layers "F.Cu" "In1.Cu" "In2.Cu" "In3.Cu" "In4.Cu" "In5.Cu" "In6.Cu" "In7.Cu"
			"In8.Cu" "In9.Cu" "In13.Cu" "In14.Cu" "In15.Cu" "In16.Cu"
		)
		(hatch none 0.5)
		(connect_pads
			(clearance 0)
		)
		(min_thickness 0.25)
		(keepout
			(tracks not_allowed)
			(vias allowed)
			(pads allowed)
			(copperpour not_allowed)
			(footprints allowed)
		)
		(placement
			(enabled no)
			(sheetname "")
		)
		(fill yes
			(thermal_gap 0.5)
			(thermal_bridge_width 0.5)
			(island_removal_mode 0)
		)
		(polygon
			(pts
				(arc
					(start 408.242008 -428.960534)
					(mid 408.264326 -429.014416)
					(end 408.318208 -429.036734)
				)
				(arc
					(start 409.258008 -429.036734)
					(mid 409.31189 -429.014416)
					(end 409.334208 -428.960534)
				)
				(arc
					(start 409.334208 -426.41901)
					(mid 409.31189 -426.365128)
					(end 409.258008 -426.34281)
				)
				(arc
					(start 408.318208 -426.34281)
					(mid 408.264326 -426.365128)
					(end 408.242008 -426.41901)
				)
			)
		)
	)
	(zone
		(layers "F.Cu" "In1.Cu" "In2.Cu" "In3.Cu" "In4.Cu" "In5.Cu" "In6.Cu" "In7.Cu"
			"In8.Cu" "In9.Cu" "In13.Cu" "In14.Cu" "In15.Cu" "In16.Cu"
		)
		(hatch none 0.5)
		(connect_pads
			(clearance 0)
		)
		(min_thickness 0.25)
		(keepout
			(tracks not_allowed)
			(vias allowed)
			(pads allowed)
			(copperpour not_allowed)
			(footprints allowed)
		)
		(placement
			(enabled no)
			(sheetname "")
		)
		(fill yes
			(thermal_gap 0.5)
			(thermal_bridge_width 0.5)
			(island_removal_mode 0)
		)
		(polygon
			(pts
				(arc
					(start 127.242062 -428.960534)
					(mid 127.26438 -429.014416)
					(end 127.318262 -429.036734)
				)
				(arc
					(start 128.258062 -429.036734)
					(mid 128.311944 -429.014416)
					(end 128.334262 -428.960534)
				)
				(arc
					(start 128.334262 -426.41901)
					(mid 128.311944 -426.365128)
					(end 128.258062 -426.34281)
				)
				(arc
					(start 127.318262 -426.34281)
					(mid 127.26438 -426.365128)
					(end 127.242062 -426.41901)
				)
			)
		)
	)
	(zone
		(layers "F.Cu" "In1.Cu" "In2.Cu" "In3.Cu" "In4.Cu" "In5.Cu" "In6.Cu" "In7.Cu"
			"In8.Cu" "In9.Cu" "In13.Cu" "In14.Cu" "In15.Cu" "In16.Cu"
		)
		(hatch none 0.5)
		(connect_pads
			(clearance 0)
		)
		(min_thickness 0.25)
		(keepout
			(tracks not_allowed)
			(vias allowed)
			(pads allowed)
			(copperpour not_allowed)
			(footprints allowed)
		)
		(placement
			(enabled no)
			(sheetname "")
		)
		(fill yes
			(thermal_gap 0.5)
			(thermal_bridge_width 0.5)
			(island_removal_mode 0)
		)
		(polygon
			(pts
				(arc
					(start 152.242012 -428.960534)
					(mid 152.26433 -429.014416)
					(end 152.318212 -429.036734)
				)
				(arc
					(start 153.258012 -429.036734)
					(mid 153.311894 -429.014416)
					(end 153.334212 -428.960534)
				)
				(arc
					(start 153.334212 -426.41901)
					(mid 153.311894 -426.365128)
					(end 153.258012 -426.34281)
				)
				(arc
					(start 152.318212 -426.34281)
					(mid 152.26433 -426.365128)
					(end 152.242012 -426.41901)
				)
			)
		)
	)
	(zone
		(layers "F.Cu" "In1.Cu" "In2.Cu" "In3.Cu" "In4.Cu" "In5.Cu" "In6.Cu" "In7.Cu"
			"In8.Cu" "In9.Cu" "In13.Cu" "In14.Cu" "In15.Cu" "In16.Cu"
		)
		(hatch none 0.5)
		(connect_pads
			(clearance 0)
		)
		(min_thickness 0.25)
		(keepout
			(tracks not_allowed)
			(vias allowed)
			(pads allowed)
			(copperpour not_allowed)
			(footprints allowed)
		)
		(placement
			(enabled no)
			(sheetname "")
		)
		(fill yes
			(thermal_gap 0.5)
			(thermal_bridge_width 0.5)
			(island_removal_mode 0)
		)
		(polygon
			(pts
				(arc
					(start 135.242046 -428.960534)
					(mid 135.264364 -429.014416)
					(end 135.318246 -429.036734)
				)
				(arc
					(start 136.258046 -429.036734)
					(mid 136.311928 -429.014416)
					(end 136.334246 -428.960534)
				)
				(arc
					(start 136.334246 -426.41901)
					(mid 136.311928 -426.365128)
					(end 136.258046 -426.34281)
				)
				(arc
					(start 135.318246 -426.34281)
					(mid 135.264364 -426.365128)
					(end 135.242046 -426.41901)
				)
			)
		)
	)
	(zone
		(layers "F.Cu" "In1.Cu" "In2.Cu" "In3.Cu" "In4.Cu" "In5.Cu" "In6.Cu" "In7.Cu"
			"In8.Cu" "In9.Cu" "In13.Cu" "In14.Cu" "In15.Cu" "In16.Cu"
		)
		(hatch none 0.5)
		(connect_pads
			(clearance 0)
		)
		(min_thickness 0.25)
		(keepout
			(tracks not_allowed)
			(vias allowed)
			(pads allowed)
			(copperpour not_allowed)
			(footprints allowed)
		)
		(placement
			(enabled no)
			(sheetname "")
		)
		(fill yes
			(thermal_gap 0.5)
			(thermal_bridge_width 0.5)
			(island_removal_mode 0)
		)
		(polygon
			(pts
				(arc
					(start 387.24205 -428.960534)
					(mid 387.264368 -429.014416)
					(end 387.31825 -429.036734)
				)
				(arc
					(start 388.25805 -429.036734)
					(mid 388.311932 -429.014416)
					(end 388.33425 -428.960534)
				)
				(arc
					(start 388.33425 -426.41901)
					(mid 388.311932 -426.365128)
					(end 388.25805 -426.34281)
				)
				(arc
					(start 387.31825 -426.34281)
					(mid 387.264368 -426.365128)
					(end 387.24205 -426.41901)
				)
			)
		)
	)
	(zone
		(layers "F.Cu" "In1.Cu" "In2.Cu" "In3.Cu" "In4.Cu" "In5.Cu" "In6.Cu" "In7.Cu"
			"In8.Cu" "In9.Cu" "In13.Cu" "In14.Cu" "In15.Cu" "In16.Cu"
		)
		(hatch none 0.5)
		(connect_pads
			(clearance 0)
		)
		(min_thickness 0.25)
		(keepout
			(tracks not_allowed)
			(vias allowed)
			(pads allowed)
			(copperpour not_allowed)
			(footprints allowed)
		)
		(placement
			(enabled no)
			(sheetname "")
		)
		(fill yes
			(thermal_gap 0.5)
			(thermal_bridge_width 0.5)
			(island_removal_mode 0)
		)
		(polygon
			(pts
				(arc
					(start 400.242024 -428.960534)
					(mid 400.264342 -429.014416)
					(end 400.318224 -429.036734)
				)
				(arc
					(start 401.258024 -429.036734)
					(mid 401.311906 -429.014416)
					(end 401.334224 -428.960534)
				)
				(arc
					(start 401.334224 -426.41901)
					(mid 401.311906 -426.365128)
					(end 401.258024 -426.34281)
				)
				(arc
					(start 400.318224 -426.34281)
					(mid 400.264342 -426.365128)
					(end 400.242024 -426.41901)
				)
			)
		)
	)
	(zone
		(layers "F.Cu" "In1.Cu" "In2.Cu" "In3.Cu" "In4.Cu" "In5.Cu" "In6.Cu" "In7.Cu"
			"In8.Cu" "In9.Cu" "In13.Cu" "In14.Cu" "In15.Cu" "In16.Cu"
		)
		(hatch none 0.5)
		(connect_pads
			(clearance 0)
		)
		(min_thickness 0.25)
		(keepout
			(tracks not_allowed)
			(vias allowed)
			(pads allowed)
			(copperpour not_allowed)
			(footprints allowed)
		)
		(placement
			(enabled no)
			(sheetname "")
		)
		(fill yes
			(thermal_gap 0.5)
			(thermal_bridge_width 0.5)
			(island_removal_mode 0)
		)
		(polygon
			(pts
				(arc
					(start 395.242034 -428.960534)
					(mid 395.264352 -429.014416)
					(end 395.318234 -429.036734)
				)
				(arc
					(start 396.258034 -429.036734)
					(mid 396.311916 -429.014416)
					(end 396.334234 -428.960534)
				)
				(arc
					(start 396.334234 -426.41901)
					(mid 396.311916 -426.365128)
					(end 396.258034 -426.34281)
				)
				(arc
					(start 395.318234 -426.34281)
					(mid 395.264352 -426.365128)
					(end 395.242034 -426.41901)
				)
			)
		)
	)
	(zone
		(layers "F.Cu" "In1.Cu" "In2.Cu" "In3.Cu" "In4.Cu" "In5.Cu" "In6.Cu" "In7.Cu"
			"In8.Cu" "In9.Cu" "In13.Cu" "In14.Cu" "In15.Cu" "In16.Cu"
		)
		(hatch none 0.5)
		(connect_pads
			(clearance 0)
		)
		(min_thickness 0.25)
		(keepout
			(tracks not_allowed)
			(vias allowed)
			(pads allowed)
			(copperpour not_allowed)
			(footprints allowed)
		)
		(placement
			(enabled no)
			(sheetname "")
		)
		(fill yes
			(thermal_gap 0.5)
			(thermal_bridge_width 0.5)
			(island_removal_mode 0)
		)
		(polygon
			(pts
				(arc
					(start 404.242016 -428.960534)
					(mid 404.264334 -429.014416)
					(end 404.318216 -429.036734)
				)
				(arc
					(start 405.258016 -429.036734)
					(mid 405.311898 -429.014416)
					(end 405.334216 -428.960534)
				)
				(arc
					(start 405.334216 -426.41901)
					(mid 405.311898 -426.365128)
					(end 405.258016 -426.34281)
				)
				(arc
					(start 404.318216 -426.34281)
					(mid 404.264334 -426.365128)
					(end 404.242016 -426.41901)
				)
			)
		)
	)
	(zone
		(layers "F.Cu" "In1.Cu" "In2.Cu" "In3.Cu" "In4.Cu" "In6.Cu" "In8.Cu" "In9.Cu"
			"In10.Cu" "In11.Cu" "In12.Cu" "In13.Cu" "In14.Cu" "In15.Cu" "In16.Cu"
		)
		(hatch none 0.5)
		(connect_pads
			(clearance 0)
		)
		(min_thickness 0.25)
		(keepout
			(tracks not_allowed)
			(vias allowed)
			(pads allowed)
			(copperpour not_allowed)
			(footprints allowed)
		)
		(placement
			(enabled no)
			(sheetname "")
		)
		(fill yes
			(thermal_gap 0.5)
			(thermal_bridge_width 0.5)
			(island_removal_mode 0)
		)
		(polygon
			(pts
				(arc
					(start 68.142104 -428.960534)
					(mid 68.164422 -429.014416)
					(end 68.218304 -429.036734)
				)
				(arc
					(start 69.158104 -429.036734)
					(mid 69.211986 -429.014416)
					(end 69.234304 -428.960534)
				)
				(arc
					(start 69.234304 -426.41901)
					(mid 69.211986 -426.365128)
					(end 69.158104 -426.34281)
				)
				(arc
					(start 68.218304 -426.34281)
					(mid 68.164422 -426.365128)
					(end 68.142104 -426.41901)
				)
			)
		)
	)
	(zone
		(layers "F.Cu" "In1.Cu" "In2.Cu" "In3.Cu" "In4.Cu" "In6.Cu" "In8.Cu" "In9.Cu"
			"In10.Cu" "In11.Cu" "In12.Cu" "In13.Cu" "In14.Cu" "In15.Cu" "In16.Cu"
		)
		(hatch none 0.5)
		(connect_pads
			(clearance 0)
		)
		(min_thickness 0.25)
		(keepout
			(tracks not_allowed)
			(vias allowed)
			(pads allowed)
			(copperpour not_allowed)
			(footprints allowed)
		)
		(placement
			(enabled no)
			(sheetname "")
		)
		(fill yes
			(thermal_gap 0.5)
			(thermal_bridge_width 0.5)
			(island_removal_mode 0)
		)
		(polygon
			(pts
				(arc
					(start 72.142096 -428.960534)
					(mid 72.164414 -429.014416)
					(end 72.218296 -429.036734)
				)
				(arc
					(start 73.158096 -429.036734)
					(mid 73.211978 -429.014416)
					(end 73.234296 -428.960534)
				)
				(arc
					(start 73.234296 -426.41901)
					(mid 73.211978 -426.365128)
					(end 73.158096 -426.34281)
				)
				(arc
					(start 72.218296 -426.34281)
					(mid 72.164414 -426.365128)
					(end 72.142096 -426.41901)
				)
			)
		)
	)
	(zone
		(layers "F.Cu" "In1.Cu" "In2.Cu" "In3.Cu" "In4.Cu" "In6.Cu" "In8.Cu" "In9.Cu"
			"In10.Cu" "In11.Cu" "In12.Cu" "In13.Cu" "In14.Cu" "In15.Cu" "In16.Cu"
		)
		(hatch none 0.5)
		(connect_pads
			(clearance 0)
		)
		(min_thickness 0.25)
		(keepout
			(tracks not_allowed)
			(vias allowed)
			(pads allowed)
			(copperpour not_allowed)
			(footprints allowed)
		)
		(placement
			(enabled no)
			(sheetname "")
		)
		(fill yes
			(thermal_gap 0.5)
			(thermal_bridge_width 0.5)
			(island_removal_mode 0)
		)
		(polygon
			(pts
				(arc
					(start 64.142112 -428.960534)
					(mid 64.16443 -429.014416)
					(end 64.218312 -429.036734)
				)
				(arc
					(start 65.158112 -429.036734)
					(mid 65.211994 -429.014416)
					(end 65.234312 -428.960534)
				)
				(arc
					(start 65.234312 -426.41901)
					(mid 65.211994 -426.365128)
					(end 65.158112 -426.34281)
				)
				(arc
					(start 64.218312 -426.34281)
					(mid 64.16443 -426.365128)
					(end 64.142112 -426.41901)
				)
			)
		)
	)
	(zone
		(layers "F.Cu" "In1.Cu" "In2.Cu" "In3.Cu" "In4.Cu" "In6.Cu" "In8.Cu" "In9.Cu"
			"In10.Cu" "In11.Cu" "In12.Cu" "In13.Cu" "In14.Cu" "In15.Cu" "In16.Cu"
		)
		(hatch none 0.5)
		(connect_pads
			(clearance 0)
		)
		(min_thickness 0.25)
		(keepout
			(tracks not_allowed)
			(vias allowed)
			(pads allowed)
			(copperpour not_allowed)
			(footprints allowed)
		)
		(placement
			(enabled no)
			(sheetname "")
		)
		(fill yes
			(thermal_gap 0.5)
			(thermal_bridge_width 0.5)
			(island_removal_mode 0)
		)
		(polygon
			(pts
				(arc
					(start 60.14212 -428.960534)
					(mid 60.164438 -429.014416)
					(end 60.21832 -429.036734)
				)
				(arc
					(start 61.15812 -429.036734)
					(mid 61.212002 -429.014416)
					(end 61.23432 -428.960534)
				)
				(arc
					(start 61.23432 -426.41901)
					(mid 61.212002 -426.365128)
					(end 61.15812 -426.34281)
				)
				(arc
					(start 60.21832 -426.34281)
					(mid 60.164438 -426.365128)
					(end 60.14212 -426.41901)
				)
			)
		)
	)
	(zone
		(layers "F.Cu" "In1.Cu" "In2.Cu" "In3.Cu" "In4.Cu" "In6.Cu" "In8.Cu" "In9.Cu"
			"In10.Cu" "In12.Cu" "In13.Cu" "In14.Cu" "In15.Cu" "In16.Cu"
		)
		(hatch none 0.5)
		(connect_pads
			(clearance 0)
		)
		(min_thickness 0.25)
		(keepout
			(tracks not_allowed)
			(vias allowed)
			(pads allowed)
			(copperpour not_allowed)
			(footprints allowed)
		)
		(placement
			(enabled no)
			(sheetname "")
		)
		(fill yes
			(thermal_gap 0.5)
			(thermal_bridge_width 0.5)
			(island_removal_mode 0)
		)
		(polygon
			(pts
				(arc
					(start 77.142086 -428.960534)
					(mid 77.164404 -429.014416)
					(end 77.218286 -429.036734)
				)
				(arc
					(start 78.158086 -429.036734)
					(mid 78.211968 -429.014416)
					(end 78.234286 -428.960534)
				)
				(arc
					(start 78.234286 -426.41901)
					(mid 78.211968 -426.365128)
					(end 78.158086 -426.34281)
				)
				(arc
					(start 77.218286 -426.34281)
					(mid 77.164404 -426.365128)
					(end 77.142086 -426.41901)
				)
			)
		)
	)
	(zone
		(layers "F.Cu" "In1.Cu" "In2.Cu" "In3.Cu" "In4.Cu" "In6.Cu" "In8.Cu" "In9.Cu"
			"In10.Cu" "In12.Cu" "In13.Cu" "In14.Cu" "In15.Cu" "In16.Cu"
		)
		(hatch none 0.5)
		(connect_pads
			(clearance 0)
		)
		(min_thickness 0.25)
		(keepout
			(tracks not_allowed)
			(vias allowed)
			(pads allowed)
			(copperpour not_allowed)
			(footprints allowed)
		)
		(placement
			(enabled no)
			(sheetname "")
		)
		(fill yes
			(thermal_gap 0.5)
			(thermal_bridge_width 0.5)
			(island_removal_mode 0)
		)
		(polygon
			(pts
				(arc
					(start 81.142078 -428.960534)
					(mid 81.164396 -429.014416)
					(end 81.218278 -429.036734)
				)
				(arc
					(start 82.158078 -429.036734)
					(mid 82.21196 -429.014416)
					(end 82.234278 -428.960534)
				)
				(arc
					(start 82.234278 -426.41901)
					(mid 82.21196 -426.365128)
					(end 82.158078 -426.34281)
				)
				(arc
					(start 81.218278 -426.34281)
					(mid 81.164396 -426.365128)
					(end 81.142078 -426.41901)
				)
			)
		)
	)
	(zone
		(layers "F.Cu" "In1.Cu" "In2.Cu" "In3.Cu" "In4.Cu" "In6.Cu" "In8.Cu" "In9.Cu"
			"In10.Cu" "In12.Cu" "In13.Cu" "In14.Cu" "In15.Cu" "In16.Cu"
		)
		(hatch none 0.5)
		(connect_pads
			(clearance 0)
		)
		(min_thickness 0.25)
		(keepout
			(tracks not_allowed)
			(vias allowed)
			(pads allowed)
			(copperpour not_allowed)
			(footprints allowed)
		)
		(placement
			(enabled no)
			(sheetname "")
		)
		(fill yes
			(thermal_gap 0.5)
			(thermal_bridge_width 0.5)
			(island_removal_mode 0)
		)
		(polygon
			(pts
				(arc
					(start 324.1421 -428.960534)
					(mid 324.164418 -429.014416)
					(end 324.2183 -429.036734)
				)
				(arc
					(start 325.1581 -429.036734)
					(mid 325.211982 -429.014416)
					(end 325.2343 -428.960534)
				)
				(arc
					(start 325.2343 -426.41901)
					(mid 325.211982 -426.365128)
					(end 325.1581 -426.34281)
				)
				(arc
					(start 324.2183 -426.34281)
					(mid 324.164418 -426.365128)
					(end 324.1421 -426.41901)
				)
			)
		)
	)
	(zone
		(layers "F.Cu" "In1.Cu" "In2.Cu" "In3.Cu" "In4.Cu" "In6.Cu" "In8.Cu" "In9.Cu"
			"In10.Cu" "In12.Cu" "In13.Cu" "In14.Cu" "In15.Cu" "In16.Cu"
		)
		(hatch none 0.5)
		(connect_pads
			(clearance 0)
		)
		(min_thickness 0.25)
		(keepout
			(tracks not_allowed)
			(vias allowed)
			(pads allowed)
			(copperpour not_allowed)
			(footprints allowed)
		)
		(placement
			(enabled no)
			(sheetname "")
		)
		(fill yes
			(thermal_gap 0.5)
			(thermal_bridge_width 0.5)
			(island_removal_mode 0)
		)
		(polygon
			(pts
				(arc
					(start 341.142066 -428.960534)
					(mid 341.164384 -429.014416)
					(end 341.218266 -429.036734)
				)
				(arc
					(start 342.158066 -429.036734)
					(mid 342.211948 -429.014416)
					(end 342.234266 -428.960534)
				)
				(arc
					(start 342.234266 -426.41901)
					(mid 342.211948 -426.365128)
					(end 342.158066 -426.34281)
				)
				(arc
					(start 341.218266 -426.34281)
					(mid 341.164384 -426.365128)
					(end 341.142066 -426.41901)
				)
			)
		)
	)
	(zone
		(layers "F.Cu" "In1.Cu" "In2.Cu" "In3.Cu" "In4.Cu" "In6.Cu" "In8.Cu" "In9.Cu"
			"In10.Cu" "In12.Cu" "In13.Cu" "In14.Cu" "In15.Cu" "In16.Cu"
		)
		(hatch none 0.5)
		(connect_pads
			(clearance 0)
		)
		(min_thickness 0.25)
		(keepout
			(tracks not_allowed)
			(vias allowed)
			(pads allowed)
			(copperpour not_allowed)
			(footprints allowed)
		)
		(placement
			(enabled no)
			(sheetname "")
		)
		(fill yes
			(thermal_gap 0.5)
			(thermal_bridge_width 0.5)
			(island_removal_mode 0)
		)
		(polygon
			(pts
				(arc
					(start 345.142058 -428.960534)
					(mid 345.164376 -429.014416)
					(end 345.218258 -429.036734)
				)
				(arc
					(start 346.158058 -429.036734)
					(mid 346.21194 -429.014416)
					(end 346.234258 -428.960534)
				)
				(arc
					(start 346.234258 -426.41901)
					(mid 346.21194 -426.365128)
					(end 346.158058 -426.34281)
				)
				(arc
					(start 345.218258 -426.34281)
					(mid 345.164376 -426.365128)
					(end 345.142058 -426.41901)
				)
			)
		)
	)
	(zone
		(layers "F.Cu" "In1.Cu" "In2.Cu" "In3.Cu" "In4.Cu" "In6.Cu" "In8.Cu" "In9.Cu"
			"In10.Cu" "In12.Cu" "In13.Cu" "In14.Cu" "In15.Cu" "In16.Cu"
		)
		(hatch none 0.5)
		(connect_pads
			(clearance 0)
		)
		(min_thickness 0.25)
		(keepout
			(tracks not_allowed)
			(vias allowed)
			(pads allowed)
			(copperpour not_allowed)
			(footprints allowed)
		)
		(placement
			(enabled no)
			(sheetname "")
		)
		(fill yes
			(thermal_gap 0.5)
			(thermal_bridge_width 0.5)
			(island_removal_mode 0)
		)
		(polygon
			(pts
				(arc
					(start 316.142116 -428.960534)
					(mid 316.164434 -429.014416)
					(end 316.218316 -429.036734)
				)
				(arc
					(start 317.158116 -429.036734)
					(mid 317.211998 -429.014416)
					(end 317.234316 -428.960534)
				)
				(arc
					(start 317.234316 -426.41901)
					(mid 317.211998 -426.365128)
					(end 317.158116 -426.34281)
				)
				(arc
					(start 316.218316 -426.34281)
					(mid 316.164434 -426.365128)
					(end 316.142116 -426.41901)
				)
			)
		)
	)
	(zone
		(layers "F.Cu" "In1.Cu" "In2.Cu" "In3.Cu" "In4.Cu" "In6.Cu" "In8.Cu" "In9.Cu"
			"In10.Cu" "In12.Cu" "In13.Cu" "In14.Cu" "In15.Cu" "In16.Cu"
		)
		(hatch none 0.5)
		(connect_pads
			(clearance 0)
		)
		(min_thickness 0.25)
		(keepout
			(tracks not_allowed)
			(vias allowed)
			(pads allowed)
			(copperpour not_allowed)
			(footprints allowed)
		)
		(placement
			(enabled no)
			(sheetname "")
		)
		(fill yes
			(thermal_gap 0.5)
			(thermal_bridge_width 0.5)
			(island_removal_mode 0)
		)
		(polygon
			(pts
				(arc
					(start 337.142074 -428.960534)
					(mid 337.164392 -429.014416)
					(end 337.218274 -429.036734)
				)
				(arc
					(start 338.158074 -429.036734)
					(mid 338.211956 -429.014416)
					(end 338.234274 -428.960534)
				)
				(arc
					(start 338.234274 -426.41901)
					(mid 338.211956 -426.365128)
					(end 338.158074 -426.34281)
				)
				(arc
					(start 337.218274 -426.34281)
					(mid 337.164392 -426.365128)
					(end 337.142074 -426.41901)
				)
			)
		)
	)
	(zone
		(layers "F.Cu" "In1.Cu" "In2.Cu" "In3.Cu" "In4.Cu" "In6.Cu" "In8.Cu" "In9.Cu"
			"In10.Cu" "In12.Cu" "In13.Cu" "In14.Cu" "In15.Cu" "In16.Cu"
		)
		(hatch none 0.5)
		(connect_pads
			(clearance 0)
		)
		(min_thickness 0.25)
		(keepout
			(tracks not_allowed)
			(vias allowed)
			(pads allowed)
			(copperpour not_allowed)
			(footprints allowed)
		)
		(placement
			(enabled no)
			(sheetname "")
		)
		(fill yes
			(thermal_gap 0.5)
			(thermal_bridge_width 0.5)
			(island_removal_mode 0)
		)
		(polygon
			(pts
				(arc
					(start 328.142092 -428.960534)
					(mid 328.16441 -429.014416)
					(end 328.218292 -429.036734)
				)
				(arc
					(start 329.158092 -429.036734)
					(mid 329.211974 -429.014416)
					(end 329.234292 -428.960534)
				)
				(arc
					(start 329.234292 -426.41901)
					(mid 329.211974 -426.365128)
					(end 329.158092 -426.34281)
				)
				(arc
					(start 328.218292 -426.34281)
					(mid 328.16441 -426.365128)
					(end 328.142092 -426.41901)
				)
			)
		)
	)
	(zone
		(layers "F.Cu" "In1.Cu" "In2.Cu" "In3.Cu" "In4.Cu" "In6.Cu" "In8.Cu" "In9.Cu"
			"In10.Cu" "In12.Cu" "In13.Cu" "In14.Cu" "In15.Cu" "In16.Cu"
		)
		(hatch none 0.5)
		(connect_pads
			(clearance 0)
		)
		(min_thickness 0.25)
		(keepout
			(tracks not_allowed)
			(vias allowed)
			(pads allowed)
			(copperpour not_allowed)
			(footprints allowed)
		)
		(placement
			(enabled no)
			(sheetname "")
		)
		(fill yes
			(thermal_gap 0.5)
			(thermal_bridge_width 0.5)
			(island_removal_mode 0)
		)
		(polygon
			(pts
				(arc
					(start 85.14207 -428.960534)
					(mid 85.164388 -429.014416)
					(end 85.21827 -429.036734)
				)
				(arc
					(start 86.15807 -429.036734)
					(mid 86.211952 -429.014416)
					(end 86.23427 -428.960534)
				)
				(arc
					(start 86.23427 -426.41901)
					(mid 86.211952 -426.365128)
					(end 86.15807 -426.34281)
				)
				(arc
					(start 85.21827 -426.34281)
					(mid 85.164388 -426.365128)
					(end 85.14207 -426.41901)
				)
			)
		)
	)
	(zone
		(layers "F.Cu" "In1.Cu" "In2.Cu" "In3.Cu" "In4.Cu" "In6.Cu" "In8.Cu" "In9.Cu"
			"In10.Cu" "In12.Cu" "In13.Cu" "In14.Cu" "In15.Cu" "In16.Cu"
		)
		(hatch none 0.5)
		(connect_pads
			(clearance 0)
		)
		(min_thickness 0.25)
		(keepout
			(tracks not_allowed)
			(vias allowed)
			(pads allowed)
			(copperpour not_allowed)
			(footprints allowed)
		)
		(placement
			(enabled no)
			(sheetname "")
		)
		(fill yes
			(thermal_gap 0.5)
			(thermal_bridge_width 0.5)
			(island_removal_mode 0)
		)
		(polygon
			(pts
				(arc
					(start 333.142082 -428.960534)
					(mid 333.1644 -429.014416)
					(end 333.218282 -429.036734)
				)
				(arc
					(start 334.158082 -429.036734)
					(mid 334.211964 -429.014416)
					(end 334.234282 -428.960534)
				)
				(arc
					(start 334.234282 -426.41901)
					(mid 334.211964 -426.365128)
					(end 334.158082 -426.34281)
				)
				(arc
					(start 333.218282 -426.34281)
					(mid 333.1644 -426.365128)
					(end 333.142082 -426.41901)
				)
			)
		)
	)
	(zone
		(layers "F.Cu" "In1.Cu" "In2.Cu" "In3.Cu" "In4.Cu" "In6.Cu" "In8.Cu" "In9.Cu"
			"In10.Cu" "In12.Cu" "In13.Cu" "In14.Cu" "In15.Cu" "In16.Cu"
		)
		(hatch none 0.5)
		(connect_pads
			(clearance 0)
		)
		(min_thickness 0.25)
		(keepout
			(tracks not_allowed)
			(vias allowed)
			(pads allowed)
			(copperpour not_allowed)
			(footprints allowed)
		)
		(placement
			(enabled no)
			(sheetname "")
		)
		(fill yes
			(thermal_gap 0.5)
			(thermal_bridge_width 0.5)
			(island_removal_mode 0)
		)
		(polygon
			(pts
				(arc
					(start 320.142108 -428.960534)
					(mid 320.164426 -429.014416)
					(end 320.218308 -429.036734)
				)
				(arc
					(start 321.158108 -429.036734)
					(mid 321.21199 -429.014416)
					(end 321.234308 -428.960534)
				)
				(arc
					(start 321.234308 -426.41901)
					(mid 321.21199 -426.365128)
					(end 321.158108 -426.34281)
				)
				(arc
					(start 320.218308 -426.34281)
					(mid 320.164426 -426.365128)
					(end 320.142108 -426.41901)
				)
			)
		)
	)
	(zone
		(layers "F.Cu" "In1.Cu" "In2.Cu" "In3.Cu" "In4.Cu" "In6.Cu" "In8.Cu" "In9.Cu"
			"In10.Cu" "In12.Cu" "In13.Cu" "In14.Cu" "In15.Cu" "In16.Cu"
		)
		(hatch none 0.5)
		(connect_pads
			(clearance 0)
		)
		(min_thickness 0.25)
		(keepout
			(tracks not_allowed)
			(vias allowed)
			(pads allowed)
			(copperpour not_allowed)
			(footprints allowed)
		)
		(placement
			(enabled no)
			(sheetname "")
		)
		(fill yes
			(thermal_gap 0.5)
			(thermal_bridge_width 0.5)
			(island_removal_mode 0)
		)
		(polygon
			(pts
				(arc
					(start 89.142062 -428.960534)
					(mid 89.16438 -429.014416)
					(end 89.218262 -429.036734)
				)
				(arc
					(start 90.158062 -429.036734)
					(mid 90.211944 -429.014416)
					(end 90.234262 -428.960534)
				)
				(arc
					(start 90.234262 -426.41901)
					(mid 90.211944 -426.365128)
					(end 90.158062 -426.34281)
				)
				(arc
					(start 89.218262 -426.34281)
					(mid 89.16438 -426.365128)
					(end 89.142062 -426.41901)
				)
			)
		)
	)
	(zone
		(layers "F.Cu" "In1.Cu" "In2.Cu" "In4.Cu" "In6.Cu" "In8.Cu" "In9.Cu" "In10.Cu"
			"In11.Cu" "In12.Cu" "In13.Cu" "In14.Cu" "In15.Cu" "In16.Cu"
		)
		(hatch none 0.5)
		(connect_pads
			(clearance 0)
		)
		(min_thickness 0.25)
		(keepout
			(tracks not_allowed)
			(vias allowed)
			(pads allowed)
			(copperpour not_allowed)
			(footprints allowed)
		)
		(placement
			(enabled no)
			(sheetname "")
		)
		(fill yes
			(thermal_gap 0.5)
			(thermal_bridge_width 0.5)
			(island_removal_mode 0)
		)
		(polygon
			(pts
				(arc
					(start 412.242 -439.760614)
					(mid 412.264318 -439.814496)
					(end 412.3182 -439.836814)
				)
				(arc
					(start 413.258 -439.836814)
					(mid 413.311882 -439.814496)
					(end 413.3342 -439.760614)
				)
				(arc
					(start 413.3342 -437.21909)
					(mid 413.311882 -437.165208)
					(end 413.258 -437.14289)
				)
				(arc
					(start 412.3182 -437.14289)
					(mid 412.264318 -437.165208)
					(end 412.242 -437.21909)
				)
			)
		)
	)
	(zone
		(layers "F.Cu" "In1.Cu" "In2.Cu" "In4.Cu" "In6.Cu" "In8.Cu" "In9.Cu" "In10.Cu"
			"In11.Cu" "In12.Cu" "In13.Cu" "In14.Cu" "In15.Cu" "In16.Cu"
		)
		(hatch none 0.5)
		(connect_pads
			(clearance 0)
		)
		(min_thickness 0.25)
		(keepout
			(tracks not_allowed)
			(vias allowed)
			(pads allowed)
			(copperpour not_allowed)
			(footprints allowed)
		)
		(placement
			(enabled no)
			(sheetname "")
		)
		(fill yes
			(thermal_gap 0.5)
			(thermal_bridge_width 0.5)
			(island_removal_mode 0)
		)
		(polygon
			(pts
				(arc
					(start 410.242004 -438.760616)
					(mid 410.264322 -438.814498)
					(end 410.318204 -438.836816)
				)
				(arc
					(start 411.258004 -438.836816)
					(mid 411.311886 -438.814498)
					(end 411.334204 -438.760616)
				)
				(arc
					(start 411.334204 -436.219092)
					(mid 411.311886 -436.16521)
					(end 411.258004 -436.142892)
				)
				(arc
					(start 410.318204 -436.142892)
					(mid 410.264322 -436.16521)
					(end 410.242004 -436.219092)
				)
			)
		)
	)
	(zone
		(layers "F.Cu" "In1.Cu" "In2.Cu" "In4.Cu" "In6.Cu" "In8.Cu" "In9.Cu" "In10.Cu"
			"In11.Cu" "In12.Cu" "In13.Cu" "In14.Cu" "In15.Cu" "In16.Cu"
		)
		(hatch none 0.5)
		(connect_pads
			(clearance 0)
		)
		(min_thickness 0.25)
		(keepout
			(tracks not_allowed)
			(vias allowed)
			(pads allowed)
			(copperpour not_allowed)
			(footprints allowed)
		)
		(placement
			(enabled no)
			(sheetname "")
		)
		(fill yes
			(thermal_gap 0.5)
			(thermal_bridge_width 0.5)
			(island_removal_mode 0)
		)
		(polygon
			(pts
				(arc
					(start 139.242038 -439.760614)
					(mid 139.264356 -439.814496)
					(end 139.318238 -439.836814)
				)
				(arc
					(start 140.258038 -439.836814)
					(mid 140.31192 -439.814496)
					(end 140.334238 -439.760614)
				)
				(arc
					(start 140.334238 -437.21909)
					(mid 140.31192 -437.165208)
					(end 140.258038 -437.14289)
				)
				(arc
					(start 139.318238 -437.14289)
					(mid 139.264356 -437.165208)
					(end 139.242038 -437.21909)
				)
			)
		)
	)
	(zone
		(layers "F.Cu" "In1.Cu" "In2.Cu" "In4.Cu" "In6.Cu" "In8.Cu" "In9.Cu" "In10.Cu"
			"In11.Cu" "In12.Cu" "In13.Cu" "In14.Cu" "In15.Cu" "In16.Cu"
		)
		(hatch none 0.5)
		(connect_pads
			(clearance 0)
		)
		(min_thickness 0.25)
		(keepout
			(tracks not_allowed)
			(vias allowed)
			(pads allowed)
			(copperpour not_allowed)
			(footprints allowed)
		)
		(placement
			(enabled no)
			(sheetname "")
		)
		(fill yes
			(thermal_gap 0.5)
			(thermal_bridge_width 0.5)
			(island_removal_mode 0)
		)
		(polygon
			(pts
				(arc
					(start 393.242038 -438.760616)
					(mid 393.264356 -438.814498)
					(end 393.318238 -438.836816)
				)
				(arc
					(start 394.258038 -438.836816)
					(mid 394.31192 -438.814498)
					(end 394.334238 -438.760616)
				)
				(arc
					(start 394.334238 -436.219092)
					(mid 394.31192 -436.16521)
					(end 394.258038 -436.142892)
				)
				(arc
					(start 393.318238 -436.142892)
					(mid 393.264356 -436.16521)
					(end 393.242038 -436.219092)
				)
			)
		)
	)
	(zone
		(layers "F.Cu" "In1.Cu" "In2.Cu" "In4.Cu" "In6.Cu" "In8.Cu" "In9.Cu" "In10.Cu"
			"In11.Cu" "In12.Cu" "In13.Cu" "In14.Cu" "In15.Cu" "In16.Cu"
		)
		(hatch none 0.5)
		(connect_pads
			(clearance 0)
		)
		(min_thickness 0.25)
		(keepout
			(tracks not_allowed)
			(vias allowed)
			(pads allowed)
			(copperpour not_allowed)
			(footprints allowed)
		)
		(placement
			(enabled no)
			(sheetname "")
		)
		(fill yes
			(thermal_gap 0.5)
			(thermal_bridge_width 0.5)
			(island_removal_mode 0)
		)
		(polygon
			(pts
				(arc
					(start 389.242046 -438.760616)
					(mid 389.264364 -438.814498)
					(end 389.318246 -438.836816)
				)
				(arc
					(start 390.258046 -438.836816)
					(mid 390.311928 -438.814498)
					(end 390.334246 -438.760616)
				)
				(arc
					(start 390.334246 -436.219092)
					(mid 390.311928 -436.16521)
					(end 390.258046 -436.142892)
				)
				(arc
					(start 389.318246 -436.142892)
					(mid 389.264364 -436.16521)
					(end 389.242046 -436.219092)
				)
			)
		)
	)
	(zone
		(layers "F.Cu" "In1.Cu" "In2.Cu" "In4.Cu" "In6.Cu" "In8.Cu" "In9.Cu" "In10.Cu"
			"In11.Cu" "In12.Cu" "In13.Cu" "In14.Cu" "In15.Cu" "In16.Cu"
		)
		(hatch none 0.5)
		(connect_pads
			(clearance 0)
		)
		(min_thickness 0.25)
		(keepout
			(tracks not_allowed)
			(vias allowed)
			(pads allowed)
			(copperpour not_allowed)
			(footprints allowed)
		)
		(placement
			(enabled no)
			(sheetname "")
		)
		(fill yes
			(thermal_gap 0.5)
			(thermal_bridge_width 0.5)
			(island_removal_mode 0)
		)
		(polygon
			(pts
				(arc
					(start 406.242012 -438.760616)
					(mid 406.26433 -438.814498)
					(end 406.318212 -438.836816)
				)
				(arc
					(start 407.258012 -438.836816)
					(mid 407.311894 -438.814498)
					(end 407.334212 -438.760616)
				)
				(arc
					(start 407.334212 -436.219092)
					(mid 407.311894 -436.16521)
					(end 407.258012 -436.142892)
				)
				(arc
					(start 406.318212 -436.142892)
					(mid 406.26433 -436.16521)
					(end 406.242012 -436.219092)
				)
			)
		)
	)
	(zone
		(layers "F.Cu" "In1.Cu" "In2.Cu" "In4.Cu" "In6.Cu" "In8.Cu" "In9.Cu" "In10.Cu"
			"In11.Cu" "In12.Cu" "In13.Cu" "In14.Cu" "In15.Cu" "In16.Cu"
		)
		(hatch none 0.5)
		(connect_pads
			(clearance 0)
		)
		(min_thickness 0.25)
		(keepout
			(tracks not_allowed)
			(vias allowed)
			(pads allowed)
			(copperpour not_allowed)
			(footprints allowed)
		)
		(placement
			(enabled no)
			(sheetname "")
		)
		(fill yes
			(thermal_gap 0.5)
			(thermal_bridge_width 0.5)
			(island_removal_mode 0)
		)
		(polygon
			(pts
				(arc
					(start 400.242024 -439.760614)
					(mid 400.264342 -439.814496)
					(end 400.318224 -439.836814)
				)
				(arc
					(start 401.258024 -439.836814)
					(mid 401.311906 -439.814496)
					(end 401.334224 -439.760614)
				)
				(arc
					(start 401.334224 -437.21909)
					(mid 401.311906 -437.165208)
					(end 401.258024 -437.14289)
				)
				(arc
					(start 400.318224 -437.14289)
					(mid 400.264342 -437.165208)
					(end 400.242024 -437.21909)
				)
			)
		)
	)
	(zone
		(layers "F.Cu" "In1.Cu" "In2.Cu" "In4.Cu" "In6.Cu" "In8.Cu" "In9.Cu" "In10.Cu"
			"In11.Cu" "In12.Cu" "In13.Cu" "In14.Cu" "In15.Cu" "In16.Cu"
		)
		(hatch none 0.5)
		(connect_pads
			(clearance 0)
		)
		(min_thickness 0.25)
		(keepout
			(tracks not_allowed)
			(vias allowed)
			(pads allowed)
			(copperpour not_allowed)
			(footprints allowed)
		)
		(placement
			(enabled no)
			(sheetname "")
		)
		(fill yes
			(thermal_gap 0.5)
			(thermal_bridge_width 0.5)
			(island_removal_mode 0)
		)
		(polygon
			(pts
				(arc
					(start 142.242032 -438.760616)
					(mid 142.26435 -438.814498)
					(end 142.318232 -438.836816)
				)
				(arc
					(start 143.258032 -438.836816)
					(mid 143.311914 -438.814498)
					(end 143.334232 -438.760616)
				)
				(arc
					(start 143.334232 -436.219092)
					(mid 143.311914 -436.16521)
					(end 143.258032 -436.142892)
				)
				(arc
					(start 142.318232 -436.142892)
					(mid 142.26435 -436.16521)
					(end 142.242032 -436.219092)
				)
			)
		)
	)
	(zone
		(layers "F.Cu" "In1.Cu" "In2.Cu" "In4.Cu" "In6.Cu" "In8.Cu" "In9.Cu" "In10.Cu"
			"In11.Cu" "In12.Cu" "In13.Cu" "In14.Cu" "In15.Cu" "In16.Cu"
		)
		(hatch none 0.5)
		(connect_pads
			(clearance 0)
		)
		(min_thickness 0.25)
		(keepout
			(tracks not_allowed)
			(vias allowed)
			(pads allowed)
			(copperpour not_allowed)
			(footprints allowed)
		)
		(placement
			(enabled no)
			(sheetname "")
		)
		(fill yes
			(thermal_gap 0.5)
			(thermal_bridge_width 0.5)
			(island_removal_mode 0)
		)
		(polygon
			(pts
				(arc
					(start 146.242024 -438.760616)
					(mid 146.264342 -438.814498)
					(end 146.318224 -438.836816)
				)
				(arc
					(start 147.258024 -438.836816)
					(mid 147.311906 -438.814498)
					(end 147.334224 -438.760616)
				)
				(arc
					(start 147.334224 -436.219092)
					(mid 147.311906 -436.16521)
					(end 147.258024 -436.142892)
				)
				(arc
					(start 146.318224 -436.142892)
					(mid 146.264342 -436.16521)
					(end 146.242024 -436.219092)
				)
			)
		)
	)
	(zone
		(layers "F.Cu" "In1.Cu" "In2.Cu" "In4.Cu" "In6.Cu" "In8.Cu" "In9.Cu" "In10.Cu"
			"In11.Cu" "In12.Cu" "In13.Cu" "In14.Cu" "In15.Cu" "In16.Cu"
		)
		(hatch none 0.5)
		(connect_pads
			(clearance 0)
		)
		(min_thickness 0.25)
		(keepout
			(tracks not_allowed)
			(vias allowed)
			(pads allowed)
			(copperpour not_allowed)
			(footprints allowed)
		)
		(placement
			(enabled no)
			(sheetname "")
		)
		(fill yes
			(thermal_gap 0.5)
			(thermal_bridge_width 0.5)
			(island_removal_mode 0)
		)
		(polygon
			(pts
				(arc
					(start 381.242062 -438.760616)
					(mid 381.26438 -438.814498)
					(end 381.318262 -438.836816)
				)
				(arc
					(start 382.258062 -438.836816)
					(mid 382.311944 -438.814498)
					(end 382.334262 -438.760616)
				)
				(arc
					(start 382.334262 -436.219092)
					(mid 382.311944 -436.16521)
					(end 382.258062 -436.142892)
				)
				(arc
					(start 381.318262 -436.142892)
					(mid 381.26438 -436.16521)
					(end 381.242062 -436.219092)
				)
			)
		)
	)
	(zone
		(layers "F.Cu" "In1.Cu" "In2.Cu" "In4.Cu" "In6.Cu" "In8.Cu" "In9.Cu" "In10.Cu"
			"In11.Cu" "In12.Cu" "In13.Cu" "In14.Cu" "In15.Cu" "In16.Cu"
		)
		(hatch none 0.5)
		(connect_pads
			(clearance 0)
		)
		(min_thickness 0.25)
		(keepout
			(tracks not_allowed)
			(vias allowed)
			(pads allowed)
			(copperpour not_allowed)
			(footprints allowed)
		)
		(placement
			(enabled no)
			(sheetname "")
		)
		(fill yes
			(thermal_gap 0.5)
			(thermal_bridge_width 0.5)
			(island_removal_mode 0)
		)
		(polygon
			(pts
				(arc
					(start 127.242062 -439.760614)
					(mid 127.26438 -439.814496)
					(end 127.318262 -439.836814)
				)
				(arc
					(start 128.258062 -439.836814)
					(mid 128.311944 -439.814496)
					(end 128.334262 -439.760614)
				)
				(arc
					(start 128.334262 -437.21909)
					(mid 128.311944 -437.165208)
					(end 128.258062 -437.14289)
				)
				(arc
					(start 127.318262 -437.14289)
					(mid 127.26438 -437.165208)
					(end 127.242062 -437.21909)
				)
			)
		)
	)
	(zone
		(layers "F.Cu" "In1.Cu" "In2.Cu" "In4.Cu" "In6.Cu" "In8.Cu" "In9.Cu" "In10.Cu"
			"In11.Cu" "In12.Cu" "In13.Cu" "In14.Cu" "In15.Cu" "In16.Cu"
		)
		(hatch none 0.5)
		(connect_pads
			(clearance 0)
		)
		(min_thickness 0.25)
		(keepout
			(tracks not_allowed)
			(vias allowed)
			(pads allowed)
			(copperpour not_allowed)
			(footprints allowed)
		)
		(placement
			(enabled no)
			(sheetname "")
		)
		(fill yes
			(thermal_gap 0.5)
			(thermal_bridge_width 0.5)
			(island_removal_mode 0)
		)
		(polygon
			(pts
				(arc
					(start 129.242058 -438.760616)
					(mid 129.264376 -438.814498)
					(end 129.318258 -438.836816)
				)
				(arc
					(start 130.258058 -438.836816)
					(mid 130.31194 -438.814498)
					(end 130.334258 -438.760616)
				)
				(arc
					(start 130.334258 -436.219092)
					(mid 130.31194 -436.16521)
					(end 130.258058 -436.142892)
				)
				(arc
					(start 129.318258 -436.142892)
					(mid 129.264376 -436.16521)
					(end 129.242058 -436.219092)
				)
			)
		)
	)
	(zone
		(layers "F.Cu" "In1.Cu" "In2.Cu" "In4.Cu" "In6.Cu" "In8.Cu" "In9.Cu" "In10.Cu"
			"In11.Cu" "In12.Cu" "In13.Cu" "In14.Cu" "In15.Cu" "In16.Cu"
		)
		(hatch none 0.5)
		(connect_pads
			(clearance 0)
		)
		(min_thickness 0.25)
		(keepout
			(tracks not_allowed)
			(vias allowed)
			(pads allowed)
			(copperpour not_allowed)
			(footprints allowed)
		)
		(placement
			(enabled no)
			(sheetname "")
		)
		(fill yes
			(thermal_gap 0.5)
			(thermal_bridge_width 0.5)
			(island_removal_mode 0)
		)
		(polygon
			(pts
				(arc
					(start 398.242028 -438.760616)
					(mid 398.264346 -438.814498)
					(end 398.318228 -438.836816)
				)
				(arc
					(start 399.258028 -438.836816)
					(mid 399.31191 -438.814498)
					(end 399.334228 -438.760616)
				)
				(arc
					(start 399.334228 -436.219092)
					(mid 399.31191 -436.16521)
					(end 399.258028 -436.142892)
				)
				(arc
					(start 398.318228 -436.142892)
					(mid 398.264346 -436.16521)
					(end 398.242028 -436.219092)
				)
			)
		)
	)
	(zone
		(layers "F.Cu" "In1.Cu" "In2.Cu" "In4.Cu" "In6.Cu" "In8.Cu" "In9.Cu" "In10.Cu"
			"In11.Cu" "In12.Cu" "In13.Cu" "In14.Cu" "In15.Cu" "In16.Cu"
		)
		(hatch none 0.5)
		(connect_pads
			(clearance 0)
		)
		(min_thickness 0.25)
		(keepout
			(tracks not_allowed)
			(vias allowed)
			(pads allowed)
			(copperpour not_allowed)
			(footprints allowed)
		)
		(placement
			(enabled no)
			(sheetname "")
		)
		(fill yes
			(thermal_gap 0.5)
			(thermal_bridge_width 0.5)
			(island_removal_mode 0)
		)
		(polygon
			(pts
				(arc
					(start 395.242034 -439.760614)
					(mid 395.264352 -439.814496)
					(end 395.318234 -439.836814)
				)
				(arc
					(start 396.258034 -439.836814)
					(mid 396.311916 -439.814496)
					(end 396.334234 -439.760614)
				)
				(arc
					(start 396.334234 -437.21909)
					(mid 396.311916 -437.165208)
					(end 396.258034 -437.14289)
				)
				(arc
					(start 395.318234 -437.14289)
					(mid 395.264352 -437.165208)
					(end 395.242034 -437.21909)
				)
			)
		)
	)
	(zone
		(layers "F.Cu" "In1.Cu" "In2.Cu" "In4.Cu" "In6.Cu" "In8.Cu" "In9.Cu" "In10.Cu"
			"In11.Cu" "In12.Cu" "In13.Cu" "In14.Cu" "In15.Cu" "In16.Cu"
		)
		(hatch none 0.5)
		(connect_pads
			(clearance 0)
		)
		(min_thickness 0.25)
		(keepout
			(tracks not_allowed)
			(vias allowed)
			(pads allowed)
			(copperpour not_allowed)
			(footprints allowed)
		)
		(placement
			(enabled no)
			(sheetname "")
		)
		(fill yes
			(thermal_gap 0.5)
			(thermal_bridge_width 0.5)
			(island_removal_mode 0)
		)
		(polygon
			(pts
				(arc
					(start 133.24205 -438.760616)
					(mid 133.264368 -438.814498)
					(end 133.31825 -438.836816)
				)
				(arc
					(start 134.25805 -438.836816)
					(mid 134.311932 -438.814498)
					(end 134.33425 -438.760616)
				)
				(arc
					(start 134.33425 -436.219092)
					(mid 134.311932 -436.16521)
					(end 134.25805 -436.142892)
				)
				(arc
					(start 133.31825 -436.142892)
					(mid 133.264368 -436.16521)
					(end 133.24205 -436.219092)
				)
			)
		)
	)
	(zone
		(layers "F.Cu" "In1.Cu" "In2.Cu" "In4.Cu" "In6.Cu" "In8.Cu" "In9.Cu" "In10.Cu"
			"In11.Cu" "In12.Cu" "In13.Cu" "In14.Cu" "In15.Cu" "In16.Cu"
		)
		(hatch none 0.5)
		(connect_pads
			(clearance 0)
		)
		(min_thickness 0.25)
		(keepout
			(tracks not_allowed)
			(vias allowed)
			(pads allowed)
			(copperpour not_allowed)
			(footprints allowed)
		)
		(placement
			(enabled no)
			(sheetname "")
		)
		(fill yes
			(thermal_gap 0.5)
			(thermal_bridge_width 0.5)
			(island_removal_mode 0)
		)
		(polygon
			(pts
				(arc
					(start 131.242054 -439.760614)
					(mid 131.264372 -439.814496)
					(end 131.318254 -439.836814)
				)
				(arc
					(start 132.258054 -439.836814)
					(mid 132.311936 -439.814496)
					(end 132.334254 -439.760614)
				)
				(arc
					(start 132.334254 -437.21909)
					(mid 132.311936 -437.165208)
					(end 132.258054 -437.14289)
				)
				(arc
					(start 131.318254 -437.14289)
					(mid 131.264372 -437.165208)
					(end 131.242054 -437.21909)
				)
			)
		)
	)
	(zone
		(layers "F.Cu" "In1.Cu" "In2.Cu" "In4.Cu" "In6.Cu" "In8.Cu" "In9.Cu" "In10.Cu"
			"In11.Cu" "In12.Cu" "In13.Cu" "In14.Cu" "In15.Cu" "In16.Cu"
		)
		(hatch none 0.5)
		(connect_pads
			(clearance 0)
		)
		(min_thickness 0.25)
		(keepout
			(tracks not_allowed)
			(vias allowed)
			(pads allowed)
			(copperpour not_allowed)
			(footprints allowed)
		)
		(placement
			(enabled no)
			(sheetname "")
		)
		(fill yes
			(thermal_gap 0.5)
			(thermal_bridge_width 0.5)
			(island_removal_mode 0)
		)
		(polygon
			(pts
				(arc
					(start 387.24205 -439.760614)
					(mid 387.264368 -439.814496)
					(end 387.31825 -439.836814)
				)
				(arc
					(start 388.25805 -439.836814)
					(mid 388.311932 -439.814496)
					(end 388.33425 -439.760614)
				)
				(arc
					(start 388.33425 -437.21909)
					(mid 388.311932 -437.165208)
					(end 388.25805 -437.14289)
				)
				(arc
					(start 387.31825 -437.14289)
					(mid 387.264368 -437.165208)
					(end 387.24205 -437.21909)
				)
			)
		)
	)
	(zone
		(layers "F.Cu" "In1.Cu" "In2.Cu" "In4.Cu" "In6.Cu" "In8.Cu" "In9.Cu" "In10.Cu"
			"In11.Cu" "In12.Cu" "In13.Cu" "In14.Cu" "In15.Cu" "In16.Cu"
		)
		(hatch none 0.5)
		(connect_pads
			(clearance 0)
		)
		(min_thickness 0.25)
		(keepout
			(tracks not_allowed)
			(vias allowed)
			(pads allowed)
			(copperpour not_allowed)
			(footprints allowed)
		)
		(placement
			(enabled no)
			(sheetname "")
		)
		(fill yes
			(thermal_gap 0.5)
			(thermal_bridge_width 0.5)
			(island_removal_mode 0)
		)
		(polygon
			(pts
				(arc
					(start 402.24202 -438.760616)
					(mid 402.264338 -438.814498)
					(end 402.31822 -438.836816)
				)
				(arc
					(start 403.25802 -438.836816)
					(mid 403.311902 -438.814498)
					(end 403.33422 -438.760616)
				)
				(arc
					(start 403.33422 -436.219092)
					(mid 403.311902 -436.16521)
					(end 403.25802 -436.142892)
				)
				(arc
					(start 402.31822 -436.142892)
					(mid 402.264338 -436.16521)
					(end 402.24202 -436.219092)
				)
			)
		)
	)
	(zone
		(layers "F.Cu" "In1.Cu" "In2.Cu" "In4.Cu" "In6.Cu" "In8.Cu" "In9.Cu" "In10.Cu"
			"In11.Cu" "In12.Cu" "In13.Cu" "In14.Cu" "In15.Cu" "In16.Cu"
		)
		(hatch none 0.5)
		(connect_pads
			(clearance 0)
		)
		(min_thickness 0.25)
		(keepout
			(tracks not_allowed)
			(vias allowed)
			(pads allowed)
			(copperpour not_allowed)
			(footprints allowed)
		)
		(placement
			(enabled no)
			(sheetname "")
		)
		(fill yes
			(thermal_gap 0.5)
			(thermal_bridge_width 0.5)
			(island_removal_mode 0)
		)
		(polygon
			(pts
				(arc
					(start 408.242008 -439.760614)
					(mid 408.264326 -439.814496)
					(end 408.318208 -439.836814)
				)
				(arc
					(start 409.258008 -439.836814)
					(mid 409.31189 -439.814496)
					(end 409.334208 -439.760614)
				)
				(arc
					(start 409.334208 -437.21909)
					(mid 409.31189 -437.165208)
					(end 409.258008 -437.14289)
				)
				(arc
					(start 408.318208 -437.14289)
					(mid 408.264326 -437.165208)
					(end 408.242008 -437.21909)
				)
			)
		)
	)
	(zone
		(layers "F.Cu" "In1.Cu" "In2.Cu" "In4.Cu" "In6.Cu" "In8.Cu" "In9.Cu" "In10.Cu"
			"In11.Cu" "In12.Cu" "In13.Cu" "In14.Cu" "In15.Cu" "In16.Cu"
		)
		(hatch none 0.5)
		(connect_pads
			(clearance 0)
		)
		(min_thickness 0.25)
		(keepout
			(tracks not_allowed)
			(vias allowed)
			(pads allowed)
			(copperpour not_allowed)
			(footprints allowed)
		)
		(placement
			(enabled no)
			(sheetname "")
		)
		(fill yes
			(thermal_gap 0.5)
			(thermal_bridge_width 0.5)
			(island_removal_mode 0)
		)
		(polygon
			(pts
				(arc
					(start 385.242054 -438.760616)
					(mid 385.264372 -438.814498)
					(end 385.318254 -438.836816)
				)
				(arc
					(start 386.258054 -438.836816)
					(mid 386.311936 -438.814498)
					(end 386.334254 -438.760616)
				)
				(arc
					(start 386.334254 -436.219092)
					(mid 386.311936 -436.16521)
					(end 386.258054 -436.142892)
				)
				(arc
					(start 385.318254 -436.142892)
					(mid 385.264372 -436.16521)
					(end 385.242054 -436.219092)
				)
			)
		)
	)
	(zone
		(layers "F.Cu" "In1.Cu" "In2.Cu" "In4.Cu" "In6.Cu" "In8.Cu" "In9.Cu" "In10.Cu"
			"In11.Cu" "In12.Cu" "In13.Cu" "In14.Cu" "In15.Cu" "In16.Cu"
		)
		(hatch none 0.5)
		(connect_pads
			(clearance 0)
		)
		(min_thickness 0.25)
		(keepout
			(tracks not_allowed)
			(vias allowed)
			(pads allowed)
			(copperpour not_allowed)
			(footprints allowed)
		)
		(placement
			(enabled no)
			(sheetname "")
		)
		(fill yes
			(thermal_gap 0.5)
			(thermal_bridge_width 0.5)
			(island_removal_mode 0)
		)
		(polygon
			(pts
				(arc
					(start 144.242028 -439.760614)
					(mid 144.264346 -439.814496)
					(end 144.318228 -439.836814)
				)
				(arc
					(start 145.258028 -439.836814)
					(mid 145.31191 -439.814496)
					(end 145.334228 -439.760614)
				)
				(arc
					(start 145.334228 -437.21909)
					(mid 145.31191 -437.165208)
					(end 145.258028 -437.14289)
				)
				(arc
					(start 144.318228 -437.14289)
					(mid 144.264346 -437.165208)
					(end 144.242028 -437.21909)
				)
			)
		)
	)
	(zone
		(layers "F.Cu" "In1.Cu" "In2.Cu" "In4.Cu" "In6.Cu" "In8.Cu" "In9.Cu" "In10.Cu"
			"In11.Cu" "In12.Cu" "In13.Cu" "In14.Cu" "In15.Cu" "In16.Cu"
		)
		(hatch none 0.5)
		(connect_pads
			(clearance 0)
		)
		(min_thickness 0.25)
		(keepout
			(tracks not_allowed)
			(vias allowed)
			(pads allowed)
			(copperpour not_allowed)
			(footprints allowed)
		)
		(placement
			(enabled no)
			(sheetname "")
		)
		(fill yes
			(thermal_gap 0.5)
			(thermal_bridge_width 0.5)
			(island_removal_mode 0)
		)
		(polygon
			(pts
				(arc
					(start 150.242016 -438.760616)
					(mid 150.264334 -438.814498)
					(end 150.318216 -438.836816)
				)
				(arc
					(start 151.258016 -438.836816)
					(mid 151.311898 -438.814498)
					(end 151.334216 -438.760616)
				)
				(arc
					(start 151.334216 -436.219092)
					(mid 151.311898 -436.16521)
					(end 151.258016 -436.142892)
				)
				(arc
					(start 150.318216 -436.142892)
					(mid 150.264334 -436.16521)
					(end 150.242016 -436.219092)
				)
			)
		)
	)
	(zone
		(layers "F.Cu" "In1.Cu" "In2.Cu" "In4.Cu" "In6.Cu" "In8.Cu" "In9.Cu" "In10.Cu"
			"In11.Cu" "In12.Cu" "In13.Cu" "In14.Cu" "In15.Cu" "In16.Cu"
		)
		(hatch none 0.5)
		(connect_pads
			(clearance 0)
		)
		(min_thickness 0.25)
		(keepout
			(tracks not_allowed)
			(vias allowed)
			(pads allowed)
			(copperpour not_allowed)
			(footprints allowed)
		)
		(placement
			(enabled no)
			(sheetname "")
		)
		(fill yes
			(thermal_gap 0.5)
			(thermal_bridge_width 0.5)
			(island_removal_mode 0)
		)
		(polygon
			(pts
				(arc
					(start 148.24202 -439.760614)
					(mid 148.264338 -439.814496)
					(end 148.31822 -439.836814)
				)
				(arc
					(start 149.25802 -439.836814)
					(mid 149.311902 -439.814496)
					(end 149.33422 -439.760614)
				)
				(arc
					(start 149.33422 -437.21909)
					(mid 149.311902 -437.165208)
					(end 149.25802 -437.14289)
				)
				(arc
					(start 148.31822 -437.14289)
					(mid 148.264338 -437.165208)
					(end 148.24202 -437.21909)
				)
			)
		)
	)
	(zone
		(layers "F.Cu" "In1.Cu" "In2.Cu" "In4.Cu" "In6.Cu" "In8.Cu" "In9.Cu" "In10.Cu"
			"In11.Cu" "In12.Cu" "In13.Cu" "In14.Cu" "In15.Cu" "In16.Cu"
		)
		(hatch none 0.5)
		(connect_pads
			(clearance 0)
		)
		(min_thickness 0.25)
		(keepout
			(tracks not_allowed)
			(vias allowed)
			(pads allowed)
			(copperpour not_allowed)
			(footprints allowed)
		)
		(placement
			(enabled no)
			(sheetname "")
		)
		(fill yes
			(thermal_gap 0.5)
			(thermal_bridge_width 0.5)
			(island_removal_mode 0)
		)
		(polygon
			(pts
				(arc
					(start 137.242042 -438.760616)
					(mid 137.26436 -438.814498)
					(end 137.318242 -438.836816)
				)
				(arc
					(start 138.258042 -438.836816)
					(mid 138.311924 -438.814498)
					(end 138.334242 -438.760616)
				)
				(arc
					(start 138.334242 -436.219092)
					(mid 138.311924 -436.16521)
					(end 138.258042 -436.142892)
				)
				(arc
					(start 137.318242 -436.142892)
					(mid 137.26436 -436.16521)
					(end 137.242042 -436.219092)
				)
			)
		)
	)
	(zone
		(layers "F.Cu" "In1.Cu" "In2.Cu" "In4.Cu" "In6.Cu" "In8.Cu" "In9.Cu" "In10.Cu"
			"In11.Cu" "In12.Cu" "In13.Cu" "In14.Cu" "In15.Cu" "In16.Cu"
		)
		(hatch none 0.5)
		(connect_pads
			(clearance 0)
		)
		(min_thickness 0.25)
		(keepout
			(tracks not_allowed)
			(vias allowed)
			(pads allowed)
			(copperpour not_allowed)
			(footprints allowed)
		)
		(placement
			(enabled no)
			(sheetname "")
		)
		(fill yes
			(thermal_gap 0.5)
			(thermal_bridge_width 0.5)
			(island_removal_mode 0)
		)
		(polygon
			(pts
				(arc
					(start 391.242042 -439.760614)
					(mid 391.26436 -439.814496)
					(end 391.318242 -439.836814)
				)
				(arc
					(start 392.258042 -439.836814)
					(mid 392.311924 -439.814496)
					(end 392.334242 -439.760614)
				)
				(arc
					(start 392.334242 -437.21909)
					(mid 392.311924 -437.165208)
					(end 392.258042 -437.14289)
				)
				(arc
					(start 391.318242 -437.14289)
					(mid 391.26436 -437.165208)
					(end 391.242042 -437.21909)
				)
			)
		)
	)
	(zone
		(layers "F.Cu" "In1.Cu" "In2.Cu" "In4.Cu" "In6.Cu" "In8.Cu" "In9.Cu" "In10.Cu"
			"In11.Cu" "In12.Cu" "In13.Cu" "In14.Cu" "In15.Cu" "In16.Cu"
		)
		(hatch none 0.5)
		(connect_pads
			(clearance 0)
		)
		(min_thickness 0.25)
		(keepout
			(tracks not_allowed)
			(vias allowed)
			(pads allowed)
			(copperpour not_allowed)
			(footprints allowed)
		)
		(placement
			(enabled no)
			(sheetname "")
		)
		(fill yes
			(thermal_gap 0.5)
			(thermal_bridge_width 0.5)
			(island_removal_mode 0)
		)
		(polygon
			(pts
				(arc
					(start 404.242016 -439.760614)
					(mid 404.264334 -439.814496)
					(end 404.318216 -439.836814)
				)
				(arc
					(start 405.258016 -439.836814)
					(mid 405.311898 -439.814496)
					(end 405.334216 -439.760614)
				)
				(arc
					(start 405.334216 -437.21909)
					(mid 405.311898 -437.165208)
					(end 405.258016 -437.14289)
				)
				(arc
					(start 404.318216 -437.14289)
					(mid 404.264334 -437.165208)
					(end 404.242016 -437.21909)
				)
			)
		)
	)
	(zone
		(layers "F.Cu" "In1.Cu" "In2.Cu" "In4.Cu" "In6.Cu" "In8.Cu" "In9.Cu" "In10.Cu"
			"In11.Cu" "In12.Cu" "In13.Cu" "In14.Cu" "In15.Cu" "In16.Cu"
		)
		(hatch none 0.5)
		(connect_pads
			(clearance 0)
		)
		(min_thickness 0.25)
		(keepout
			(tracks not_allowed)
			(vias allowed)
			(pads allowed)
			(copperpour not_allowed)
			(footprints allowed)
		)
		(placement
			(enabled no)
			(sheetname "")
		)
		(fill yes
			(thermal_gap 0.5)
			(thermal_bridge_width 0.5)
			(island_removal_mode 0)
		)
		(polygon
			(pts
				(arc
					(start 383.242058 -439.760614)
					(mid 383.264376 -439.814496)
					(end 383.318258 -439.836814)
				)
				(arc
					(start 384.258058 -439.836814)
					(mid 384.31194 -439.814496)
					(end 384.334258 -439.760614)
				)
				(arc
					(start 384.334258 -437.21909)
					(mid 384.31194 -437.165208)
					(end 384.258058 -437.14289)
				)
				(arc
					(start 383.318258 -437.14289)
					(mid 383.264376 -437.165208)
					(end 383.242058 -437.21909)
				)
			)
		)
	)
	(zone
		(layers "F.Cu" "In1.Cu" "In2.Cu" "In4.Cu" "In6.Cu" "In8.Cu" "In9.Cu" "In10.Cu"
			"In11.Cu" "In12.Cu" "In13.Cu" "In14.Cu" "In15.Cu" "In16.Cu"
		)
		(hatch none 0.5)
		(connect_pads
			(clearance 0)
		)
		(min_thickness 0.25)
		(keepout
			(tracks not_allowed)
			(vias allowed)
			(pads allowed)
			(copperpour not_allowed)
			(footprints allowed)
		)
		(placement
			(enabled no)
			(sheetname "")
		)
		(fill yes
			(thermal_gap 0.5)
			(thermal_bridge_width 0.5)
			(island_removal_mode 0)
		)
		(polygon
			(pts
				(arc
					(start 152.242012 -439.760614)
					(mid 152.26433 -439.814496)
					(end 152.318212 -439.836814)
				)
				(arc
					(start 153.258012 -439.836814)
					(mid 153.311894 -439.814496)
					(end 153.334212 -439.760614)
				)
				(arc
					(start 153.334212 -437.21909)
					(mid 153.311894 -437.165208)
					(end 153.258012 -437.14289)
				)
				(arc
					(start 152.318212 -437.14289)
					(mid 152.26433 -437.165208)
					(end 152.242012 -437.21909)
				)
			)
		)
	)
	(zone
		(layers "F.Cu" "In1.Cu" "In2.Cu" "In4.Cu" "In6.Cu" "In8.Cu" "In9.Cu" "In10.Cu"
			"In11.Cu" "In12.Cu" "In13.Cu" "In14.Cu" "In15.Cu" "In16.Cu"
		)
		(hatch none 0.5)
		(connect_pads
			(clearance 0)
		)
		(min_thickness 0.25)
		(keepout
			(tracks not_allowed)
			(vias allowed)
			(pads allowed)
			(copperpour not_allowed)
			(footprints allowed)
		)
		(placement
			(enabled no)
			(sheetname "")
		)
		(fill yes
			(thermal_gap 0.5)
			(thermal_bridge_width 0.5)
			(island_removal_mode 0)
		)
		(polygon
			(pts
				(arc
					(start 135.242046 -439.760614)
					(mid 135.264364 -439.814496)
					(end 135.318246 -439.836814)
				)
				(arc
					(start 136.258046 -439.836814)
					(mid 136.311928 -439.814496)
					(end 136.334246 -439.760614)
				)
				(arc
					(start 136.334246 -437.21909)
					(mid 136.311928 -437.165208)
					(end 136.258046 -437.14289)
				)
				(arc
					(start 135.318246 -437.14289)
					(mid 135.264364 -437.165208)
					(end 135.242046 -437.21909)
				)
			)
		)
	)
	(zone
		(layers "F.Cu" "In1.Cu" "In2.Cu" "In4.Cu" "In6.Cu" "In8.Cu" "In9.Cu" "In10.Cu"
			"In11.Cu" "In12.Cu" "In13.Cu" "In14.Cu" "In15.Cu" "In16.Cu"
		)
		(hatch none 0.5)
		(connect_pads
			(clearance 0)
		)
		(min_thickness 0.25)
		(keepout
			(tracks not_allowed)
			(vias allowed)
			(pads allowed)
			(copperpour not_allowed)
			(footprints allowed)
		)
		(placement
			(enabled no)
			(sheetname "")
		)
		(fill yes
			(thermal_gap 0.5)
			(thermal_bridge_width 0.5)
			(island_removal_mode 0)
		)
		(polygon
			(pts
				(arc
					(start 125.242066 -438.760616)
					(mid 125.264384 -438.814498)
					(end 125.318266 -438.836816)
				)
				(arc
					(start 126.258066 -438.836816)
					(mid 126.311948 -438.814498)
					(end 126.334266 -438.760616)
				)
				(arc
					(start 126.334266 -436.219092)
					(mid 126.311948 -436.16521)
					(end 126.258066 -436.142892)
				)
				(arc
					(start 125.318266 -436.142892)
					(mid 125.264384 -436.16521)
					(end 125.242066 -436.219092)
				)
			)
		)
	)
	(zone
		(layers "F.Cu" "In1.Cu" "In3.Cu" "In4.Cu" "In5.Cu" "In6.Cu" "In7.Cu" "In8.Cu"
			"In9.Cu" "In13.Cu" "In14.Cu" "In15.Cu" "In16.Cu"
		)
		(hatch none 0.5)
		(connect_pads
			(clearance 0)
		)
		(min_thickness 0.25)
		(keepout
			(tracks not_allowed)
			(vias allowed)
			(pads allowed)
			(copperpour not_allowed)
			(footprints allowed)
		)
		(placement
			(enabled no)
			(sheetname "")
		)
		(fill yes
			(thermal_gap 0.5)
			(thermal_bridge_width 0.5)
			(island_removal_mode 0)
		)
		(polygon
			(pts
				(arc
					(start 156.242004 -428.960534)
					(mid 156.264322 -429.014416)
					(end 156.318204 -429.036734)
				)
				(arc
					(start 157.258004 -429.036734)
					(mid 157.311886 -429.014416)
					(end 157.334204 -428.960534)
				)
				(arc
					(start 157.334204 -426.41901)
					(mid 157.311886 -426.365128)
					(end 157.258004 -426.34281)
				)
				(arc
					(start 156.318204 -426.34281)
					(mid 156.264322 -426.365128)
					(end 156.242004 -426.41901)
				)
			)
		)
	)
	(zone
		(layers "F.Cu" "In1.Cu" "In4.Cu" "In6.Cu" "In8.Cu" "In9.Cu" "In10.Cu" "In11.Cu"
			"In12.Cu" "In13.Cu" "In14.Cu" "In15.Cu" "In16.Cu"
		)
		(hatch none 0.5)
		(connect_pads
			(clearance 0)
		)
		(min_thickness 0.25)
		(keepout
			(tracks not_allowed)
			(vias allowed)
			(pads allowed)
			(copperpour not_allowed)
			(footprints allowed)
		)
		(placement
			(enabled no)
			(sheetname "")
		)
		(fill yes
			(thermal_gap 0.5)
			(thermal_bridge_width 0.5)
			(island_removal_mode 0)
		)
		(polygon
			(pts
				(arc
					(start 156.242004 -439.760614)
					(mid 156.264322 -439.814496)
					(end 156.318204 -439.836814)
				)
				(arc
					(start 157.258004 -439.836814)
					(mid 157.311886 -439.814496)
					(end 157.334204 -439.760614)
				)
				(arc
					(start 157.334204 -437.21909)
					(mid 157.311886 -437.165208)
					(end 157.258004 -437.14289)
				)
				(arc
					(start 156.318204 -437.14289)
					(mid 156.264322 -437.165208)
					(end 156.242004 -437.21909)
				)
			)
		)
	)
	(zone
		(layers "F.Cu" "In1.Cu" "In4.Cu" "In6.Cu" "In8.Cu" "In9.Cu" "In10.Cu" "In11.Cu"
			"In12.Cu" "In13.Cu" "In14.Cu" "In15.Cu" "In16.Cu"
		)
		(hatch none 0.5)
		(connect_pads
			(clearance 0)
		)
		(min_thickness 0.25)
		(keepout
			(tracks not_allowed)
			(vias allowed)
			(pads allowed)
			(copperpour not_allowed)
			(footprints allowed)
		)
		(placement
			(enabled no)
			(sheetname "")
		)
		(fill yes
			(thermal_gap 0.5)
			(thermal_bridge_width 0.5)
			(island_removal_mode 0)
		)
		(polygon
			(pts
				(arc
					(start 154.242008 -438.760616)
					(mid 154.264326 -438.814498)
					(end 154.318208 -438.836816)
				)
				(arc
					(start 155.258008 -438.836816)
					(mid 155.31189 -438.814498)
					(end 155.334208 -438.760616)
				)
				(arc
					(start 155.334208 -436.219092)
					(mid 155.31189 -436.16521)
					(end 155.258008 -436.142892)
				)
				(arc
					(start 154.318208 -436.142892)
					(mid 154.264326 -436.16521)
					(end 154.242008 -436.219092)
				)
			)
		)
	)
	(zone
		(layers "F.Cu" "In2.Cu" "In4.Cu")
		(hatch none 0.5)
		(connect_pads
			(clearance 0)
		)
		(min_thickness 0.25)
		(keepout
			(tracks not_allowed)
			(vias allowed)
			(pads allowed)
			(copperpour not_allowed)
			(footprints allowed)
		)
		(placement
			(enabled no)
			(sheetname "")
		)
		(fill yes
			(thermal_gap 0.5)
			(thermal_bridge_width 0.5)
			(island_removal_mode 0)
		)
		(polygon
			(pts
				(arc
					(start 342.089486 -83.561174)
					(mid 341.385906 -83.561174)
					(end 342.089486 -83.561174)
				)
			)
		)
	)
	(zone
		(layers "F.Cu" "In2.Cu" "In4.Cu")
		(hatch none 0.5)
		(connect_pads
			(clearance 0)
		)
		(min_thickness 0.25)
		(keepout
			(tracks not_allowed)
			(vias allowed)
			(pads allowed)
			(copperpour not_allowed)
			(footprints allowed)
		)
		(placement
			(enabled no)
			(sheetname "")
		)
		(fill yes
			(thermal_gap 0.5)
			(thermal_bridge_width 0.5)
			(island_removal_mode 0)
		)
		(polygon
			(pts
				(arc
					(start 340.211664 -81.964022)
					(mid 339.508084 -81.964022)
					(end 340.211664 -81.964022)
				)
			)
		)
	)
	(zone
		(layers "F.Cu" "In2.Cu" "In4.Cu")
		(hatch none 0.5)
		(connect_pads
			(clearance 0)
		)
		(min_thickness 0.25)
		(keepout
			(tracks not_allowed)
			(vias allowed)
			(pads allowed)
			(copperpour not_allowed)
			(footprints allowed)
		)
		(placement
			(enabled no)
			(sheetname "")
		)
		(fill yes
			(thermal_gap 0.5)
			(thermal_bridge_width 0.5)
			(island_removal_mode 0)
		)
		(polygon
			(pts
				(arc
					(start 343.70899 -85.812122)
					(mid 343.00541 -85.812122)
					(end 343.70899 -85.812122)
				)
			)
		)
	)
	(zone
		(layers "F.Cu" "In2.Cu" "In4.Cu")
		(hatch none 0.5)
		(connect_pads
			(clearance 0)
		)
		(min_thickness 0.25)
		(keepout
			(tracks not_allowed)
			(vias allowed)
			(pads allowed)
			(copperpour not_allowed)
			(footprints allowed)
		)
		(placement
			(enabled no)
			(sheetname "")
		)
		(fill yes
			(thermal_gap 0.5)
			(thermal_bridge_width 0.5)
			(island_removal_mode 0)
		)
		(polygon
			(pts
				(arc
					(start 336.92211 -82.271108)
					(mid 336.21853 -82.271108)
					(end 336.92211 -82.271108)
				)
			)
		)
	)
	(zone
		(layers "F.Cu" "In2.Cu" "In4.Cu")
		(hatch none 0.5)
		(connect_pads
			(clearance 0)
		)
		(min_thickness 0.25)
		(keepout
			(tracks not_allowed)
			(vias allowed)
			(pads allowed)
			(copperpour not_allowed)
			(footprints allowed)
		)
		(placement
			(enabled no)
			(sheetname "")
		)
		(fill yes
			(thermal_gap 0.5)
			(thermal_bridge_width 0.5)
			(island_removal_mode 0)
		)
		(polygon
			(pts
				(arc
					(start 337.78571 -82.271108)
					(mid 337.08213 -82.271108)
					(end 337.78571 -82.271108)
				)
			)
		)
	)
	(zone
		(layers "F.Cu" "In2.Cu" "In4.Cu")
		(hatch none 0.5)
		(connect_pads
			(clearance 0)
		)
		(min_thickness 0.25)
		(keepout
			(tracks not_allowed)
			(vias allowed)
			(pads allowed)
			(copperpour not_allowed)
			(footprints allowed)
		)
		(placement
			(enabled no)
			(sheetname "")
		)
		(fill yes
			(thermal_gap 0.5)
			(thermal_bridge_width 0.5)
			(island_removal_mode 0)
		)
		(polygon
			(pts
				(arc
					(start 345.378024 -84.39785)
					(mid 344.674444 -84.39785)
					(end 345.378024 -84.39785)
				)
			)
		)
	)
	(zone
		(layers "F.Cu" "In2.Cu" "In4.Cu")
		(hatch none 0.5)
		(connect_pads
			(clearance 0)
		)
		(min_thickness 0.25)
		(keepout
			(tracks not_allowed)
			(vias allowed)
			(pads allowed)
			(copperpour not_allowed)
			(footprints allowed)
		)
		(placement
			(enabled no)
			(sheetname "")
		)
		(fill yes
			(thermal_gap 0.5)
			(thermal_bridge_width 0.5)
			(island_removal_mode 0)
		)
		(polygon
			(pts
				(arc
					(start 339.47862 -84.484464)
					(mid 338.77504 -84.484464)
					(end 339.47862 -84.484464)
				)
			)
		)
	)
	(zone
		(layers "F.Cu" "In2.Cu" "In4.Cu")
		(hatch none 0.5)
		(connect_pads
			(clearance 0)
		)
		(min_thickness 0.25)
		(keepout
			(tracks not_allowed)
			(vias allowed)
			(pads allowed)
			(copperpour not_allowed)
			(footprints allowed)
		)
		(placement
			(enabled no)
			(sheetname "")
		)
		(fill yes
			(thermal_gap 0.5)
			(thermal_bridge_width 0.5)
			(island_removal_mode 0)
		)
		(polygon
			(pts
				(arc
					(start 335.534762 -80.790542)
					(mid 334.831182 -80.790542)
					(end 335.534762 -80.790542)
				)
			)
		)
	)
	(zone
		(layers "F.Cu" "In2.Cu" "In4.Cu")
		(hatch none 0.5)
		(connect_pads
			(clearance 0)
		)
		(min_thickness 0.25)
		(keepout
			(tracks not_allowed)
			(vias allowed)
			(pads allowed)
			(copperpour not_allowed)
			(footprints allowed)
		)
		(placement
			(enabled no)
			(sheetname "")
		)
		(fill yes
			(thermal_gap 0.5)
			(thermal_bridge_width 0.5)
			(island_removal_mode 0)
		)
		(polygon
			(pts
				(arc
					(start 338.61502 -84.484464)
					(mid 337.91144 -84.484464)
					(end 338.61502 -84.484464)
				)
			)
		)
	)
	(zone
		(layers "F.Cu" "In2.Cu" "In4.Cu")
		(hatch none 0.5)
		(connect_pads
			(clearance 0)
		)
		(min_thickness 0.25)
		(keepout
			(tracks not_allowed)
			(vias allowed)
			(pads allowed)
			(copperpour not_allowed)
			(footprints allowed)
		)
		(placement
			(enabled no)
			(sheetname "")
		)
		(fill yes
			(thermal_gap 0.5)
			(thermal_bridge_width 0.5)
			(island_removal_mode 0)
		)
		(polygon
			(pts
				(arc
					(start 344.57259 -85.812122)
					(mid 343.86901 -85.812122)
					(end 344.57259 -85.812122)
				)
			)
		)
	)
	(zone
		(layers "F.Cu" "In2.Cu" "In4.Cu")
		(hatch none 0.5)
		(connect_pads
			(clearance 0)
		)
		(min_thickness 0.25)
		(keepout
			(tracks not_allowed)
			(vias allowed)
			(pads allowed)
			(copperpour not_allowed)
			(footprints allowed)
		)
		(placement
			(enabled no)
			(sheetname "")
		)
		(fill yes
			(thermal_gap 0.5)
			(thermal_bridge_width 0.5)
			(island_removal_mode 0)
		)
		(polygon
			(pts
				(arc
					(start 346.241624 -84.39785)
					(mid 345.538044 -84.39785)
					(end 346.241624 -84.39785)
				)
			)
		)
	)
	(zone
		(layers "F.Cu" "In2.Cu" "In4.Cu")
		(hatch none 0.5)
		(connect_pads
			(clearance 0)
		)
		(min_thickness 0.25)
		(keepout
			(tracks not_allowed)
			(vias allowed)
			(pads allowed)
			(copperpour not_allowed)
			(footprints allowed)
		)
		(placement
			(enabled no)
			(sheetname "")
		)
		(fill yes
			(thermal_gap 0.5)
			(thermal_bridge_width 0.5)
			(island_removal_mode 0)
		)
		(polygon
			(pts
				(arc
					(start 334.671162 -80.790542)
					(mid 333.967582 -80.790542)
					(end 334.671162 -80.790542)
				)
			)
		)
	)
	(zone
		(layers "F.Cu" "In2.Cu" "In4.Cu")
		(hatch none 0.5)
		(connect_pads
			(clearance 0)
		)
		(min_thickness 0.25)
		(keepout
			(tracks not_allowed)
			(vias allowed)
			(pads allowed)
			(copperpour not_allowed)
			(footprints allowed)
		)
		(placement
			(enabled no)
			(sheetname "")
		)
		(fill yes
			(thermal_gap 0.5)
			(thermal_bridge_width 0.5)
			(island_removal_mode 0)
		)
		(polygon
			(pts
				(arc
					(start 342.953086 -83.561174)
					(mid 342.249506 -83.561174)
					(end 342.953086 -83.561174)
				)
			)
		)
	)
	(zone
		(layers "F.Cu" "In2.Cu" "In4.Cu")
		(hatch none 0.5)
		(connect_pads
			(clearance 0)
		)
		(min_thickness 0.25)
		(keepout
			(tracks not_allowed)
			(vias allowed)
			(pads allowed)
			(copperpour not_allowed)
			(footprints allowed)
		)
		(placement
			(enabled no)
			(sheetname "")
		)
		(fill yes
			(thermal_gap 0.5)
			(thermal_bridge_width 0.5)
			(island_removal_mode 0)
		)
		(polygon
			(pts
				(arc
					(start 332.501748 -82.040984)
					(mid 331.798168 -82.040984)
					(end 332.501748 -82.040984)
				)
			)
		)
	)
	(zone
		(layers "F.Cu" "In2.Cu" "In4.Cu")
		(hatch none 0.5)
		(connect_pads
			(clearance 0)
		)
		(min_thickness 0.25)
		(keepout
			(tracks not_allowed)
			(vias allowed)
			(pads allowed)
			(copperpour not_allowed)
			(footprints allowed)
		)
		(placement
			(enabled no)
			(sheetname "")
		)
		(fill yes
			(thermal_gap 0.5)
			(thermal_bridge_width 0.5)
			(island_removal_mode 0)
		)
		(polygon
			(pts
				(arc
					(start 341.075264 -81.964022)
					(mid 340.371684 -81.964022)
					(end 341.075264 -81.964022)
				)
			)
		)
	)
	(zone
		(layers "F.Cu" "In2.Cu" "In4.Cu")
		(hatch none 0.5)
		(connect_pads
			(clearance 0)
		)
		(min_thickness 0.25)
		(keepout
			(tracks not_allowed)
			(vias allowed)
			(pads allowed)
			(copperpour not_allowed)
			(footprints allowed)
		)
		(placement
			(enabled no)
			(sheetname "")
		)
		(fill yes
			(thermal_gap 0.5)
			(thermal_bridge_width 0.5)
			(island_removal_mode 0)
		)
		(polygon
			(pts
				(arc
					(start 333.365348 -82.040984)
					(mid 332.661768 -82.040984)
					(end 333.365348 -82.040984)
				)
			)
		)
	)
	(zone
		(layers "F.Cu" "In2.Cu" "In4.Cu" "In6.Cu")
		(hatch none 0.5)
		(connect_pads
			(clearance 0)
		)
		(min_thickness 0.25)
		(keepout
			(tracks not_allowed)
			(vias allowed)
			(pads allowed)
			(copperpour not_allowed)
			(footprints allowed)
		)
		(placement
			(enabled no)
			(sheetname "")
		)
		(fill yes
			(thermal_gap 0.5)
			(thermal_bridge_width 0.5)
			(island_removal_mode 0)
		)
		(polygon
			(pts
				(arc
					(start 184.004204 5.8928)
					(mid 183.300624 5.8928)
					(end 184.004204 5.8928)
				)
			)
		)
	)
	(zone
		(layers "F.Cu" "In2.Cu" "In4.Cu" "In6.Cu")
		(hatch none 0.5)
		(connect_pads
			(clearance 0)
		)
		(min_thickness 0.25)
		(keepout
			(tracks not_allowed)
			(vias allowed)
			(pads allowed)
			(copperpour not_allowed)
			(footprints allowed)
		)
		(placement
			(enabled no)
			(sheetname "")
		)
		(fill yes
			(thermal_gap 0.5)
			(thermal_bridge_width 0.5)
			(island_removal_mode 0)
		)
		(polygon
			(pts
				(arc
					(start 213.712044 -2.5908)
					(mid 213.008464 -2.5908)
					(end 213.712044 -2.5908)
				)
			)
		)
	)
	(zone
		(layers "F.Cu" "In2.Cu" "In4.Cu" "In6.Cu")
		(hatch none 0.5)
		(connect_pads
			(clearance 0)
		)
		(min_thickness 0.25)
		(keepout
			(tracks not_allowed)
			(vias allowed)
			(pads allowed)
			(copperpour not_allowed)
			(footprints allowed)
		)
		(placement
			(enabled no)
			(sheetname "")
		)
		(fill yes
			(thermal_gap 0.5)
			(thermal_bridge_width 0.5)
			(island_removal_mode 0)
		)
		(polygon
			(pts
				(arc
					(start 249.500136 5.8928)
					(mid 248.796556 5.8928)
					(end 249.500136 5.8928)
				)
			)
		)
	)
	(zone
		(layers "F.Cu" "In2.Cu" "In4.Cu" "In6.Cu")
		(hatch none 0.5)
		(connect_pads
			(clearance 0)
		)
		(min_thickness 0.25)
		(keepout
			(tracks not_allowed)
			(vias allowed)
			(pads allowed)
			(copperpour not_allowed)
			(footprints allowed)
		)
		(placement
			(enabled no)
			(sheetname "")
		)
		(fill yes
			(thermal_gap 0.5)
			(thermal_bridge_width 0.5)
			(island_removal_mode 0)
		)
		(polygon
			(pts
				(arc
					(start 213.712044 -1.7272)
					(mid 213.008464 -1.7272)
					(end 213.712044 -1.7272)
				)
			)
		)
	)
	(zone
		(layers "F.Cu" "In2.Cu" "In4.Cu" "In6.Cu")
		(hatch none 0.5)
		(connect_pads
			(clearance 0)
		)
		(min_thickness 0.25)
		(keepout
			(tracks not_allowed)
			(vias allowed)
			(pads allowed)
			(copperpour not_allowed)
			(footprints allowed)
		)
		(placement
			(enabled no)
			(sheetname "")
		)
		(fill yes
			(thermal_gap 0.5)
			(thermal_bridge_width 0.5)
			(island_removal_mode 0)
		)
		(polygon
			(pts
				(arc
					(start 249.500136 -2.5908)
					(mid 248.796556 -2.5908)
					(end 249.500136 -2.5908)
				)
			)
		)
	)
	(zone
		(layers "F.Cu" "In2.Cu" "In4.Cu" "In6.Cu")
		(hatch none 0.5)
		(connect_pads
			(clearance 0)
		)
		(min_thickness 0.25)
		(keepout
			(tracks not_allowed)
			(vias allowed)
			(pads allowed)
			(copperpour not_allowed)
			(footprints allowed)
		)
		(placement
			(enabled no)
			(sheetname "")
		)
		(fill yes
			(thermal_gap 0.5)
			(thermal_bridge_width 0.5)
			(island_removal_mode 0)
		)
		(polygon
			(pts
				(arc
					(start 249.500136 5.0292)
					(mid 248.796556 5.0292)
					(end 249.500136 5.0292)
				)
			)
		)
	)
	(zone
		(layers "F.Cu" "In2.Cu" "In4.Cu" "In6.Cu")
		(hatch none 0.5)
		(connect_pads
			(clearance 0)
		)
		(min_thickness 0.25)
		(keepout
			(tracks not_allowed)
			(vias allowed)
			(pads allowed)
			(copperpour not_allowed)
			(footprints allowed)
		)
		(placement
			(enabled no)
			(sheetname "")
		)
		(fill yes
			(thermal_gap 0.5)
			(thermal_bridge_width 0.5)
			(island_removal_mode 0)
		)
		(polygon
			(pts
				(arc
					(start 249.500136 -1.7272)
					(mid 248.796556 -1.7272)
					(end 249.500136 -1.7272)
				)
			)
		)
	)
	(zone
		(layers "F.Cu" "In2.Cu" "In4.Cu" "In6.Cu")
		(hatch none 0.5)
		(connect_pads
			(clearance 0)
		)
		(min_thickness 0.25)
		(keepout
			(tracks not_allowed)
			(vias allowed)
			(pads allowed)
			(copperpour not_allowed)
			(footprints allowed)
		)
		(placement
			(enabled no)
			(sheetname "")
		)
		(fill yes
			(thermal_gap 0.5)
			(thermal_bridge_width 0.5)
			(island_removal_mode 0)
		)
		(polygon
			(pts
				(arc
					(start 184.004204 5.0292)
					(mid 183.300624 5.0292)
					(end 184.004204 5.0292)
				)
			)
		)
	)
	(zone
		(layers "F.Cu" "In2.Cu" "In4.Cu" "In6.Cu" "In11.Cu")
		(hatch none 0.5)
		(connect_pads
			(clearance 0)
		)
		(min_thickness 0.25)
		(keepout
			(tracks not_allowed)
			(vias allowed)
			(pads allowed)
			(copperpour not_allowed)
			(footprints allowed)
		)
		(placement
			(enabled no)
			(sheetname "")
		)
		(fill yes
			(thermal_gap 0.5)
			(thermal_bridge_width 0.5)
			(island_removal_mode 0)
		)
		(polygon
			(pts
				(arc
					(start 341.156798 8.435594)
					(mid 340.453218 8.435594)
					(end 341.156798 8.435594)
				)
			)
		)
	)
	(zone
		(layers "F.Cu" "In2.Cu" "In4.Cu" "In6.Cu" "In11.Cu")
		(hatch none 0.5)
		(connect_pads
			(clearance 0)
		)
		(min_thickness 0.25)
		(keepout
			(tracks not_allowed)
			(vias allowed)
			(pads allowed)
			(copperpour not_allowed)
			(footprints allowed)
		)
		(placement
			(enabled no)
			(sheetname "")
		)
		(fill yes
			(thermal_gap 0.5)
			(thermal_bridge_width 0.5)
			(island_removal_mode 0)
		)
		(polygon
			(pts
				(arc
					(start 328.085704 8.435594)
					(mid 327.382124 8.435594)
					(end 328.085704 8.435594)
				)
			)
		)
	)
	(zone
		(layers "F.Cu" "In2.Cu" "In4.Cu" "In6.Cu" "In11.Cu")
		(hatch none 0.5)
		(connect_pads
			(clearance 0)
		)
		(min_thickness 0.25)
		(keepout
			(tracks not_allowed)
			(vias allowed)
			(pads allowed)
			(copperpour not_allowed)
			(footprints allowed)
		)
		(placement
			(enabled no)
			(sheetname "")
		)
		(fill yes
			(thermal_gap 0.5)
			(thermal_bridge_width 0.5)
			(island_removal_mode 0)
		)
		(polygon
			(pts
				(arc
					(start 376.94489 8.435594)
					(mid 376.24131 8.435594)
					(end 376.94489 8.435594)
				)
			)
		)
	)
	(zone
		(layers "F.Cu" "In2.Cu" "In4.Cu" "In6.Cu" "In11.Cu")
		(hatch none 0.5)
		(connect_pads
			(clearance 0)
		)
		(min_thickness 0.25)
		(keepout
			(tracks not_allowed)
			(vias allowed)
			(pads allowed)
			(copperpour not_allowed)
			(footprints allowed)
		)
		(placement
			(enabled no)
			(sheetname "")
		)
		(fill yes
			(thermal_gap 0.5)
			(thermal_bridge_width 0.5)
			(island_removal_mode 0)
		)
		(polygon
			(pts
				(arc
					(start 341.156798 7.571994)
					(mid 340.453218 7.571994)
					(end 341.156798 7.571994)
				)
			)
		)
	)
	(zone
		(layers "F.Cu" "In2.Cu" "In4.Cu" "In6.Cu" "In11.Cu")
		(hatch none 0.5)
		(connect_pads
			(clearance 0)
		)
		(min_thickness 0.25)
		(keepout
			(tracks not_allowed)
			(vias allowed)
			(pads allowed)
			(copperpour not_allowed)
			(footprints allowed)
		)
		(placement
			(enabled no)
			(sheetname "")
		)
		(fill yes
			(thermal_gap 0.5)
			(thermal_bridge_width 0.5)
			(island_removal_mode 0)
		)
		(polygon
			(pts
				(arc
					(start 376.94489 7.571994)
					(mid 376.24131 7.571994)
					(end 376.94489 7.571994)
				)
			)
		)
	)
	(zone
		(layers "F.Cu" "In2.Cu" "In4.Cu" "In6.Cu" "In11.Cu")
		(hatch none 0.5)
		(connect_pads
			(clearance 0)
		)
		(min_thickness 0.25)
		(keepout
			(tracks not_allowed)
			(vias allowed)
			(pads allowed)
			(copperpour not_allowed)
			(footprints allowed)
		)
		(placement
			(enabled no)
			(sheetname "")
		)
		(fill yes
			(thermal_gap 0.5)
			(thermal_bridge_width 0.5)
			(island_removal_mode 0)
		)
		(polygon
			(pts
				(arc
					(start 262.589772 7.571994)
					(mid 261.886192 7.571994)
					(end 262.589772 7.571994)
				)
			)
		)
	)
	(zone
		(layers "F.Cu" "In2.Cu" "In4.Cu" "In6.Cu" "In11.Cu")
		(hatch none 0.5)
		(connect_pads
			(clearance 0)
		)
		(min_thickness 0.25)
		(keepout
			(tracks not_allowed)
			(vias allowed)
			(pads allowed)
			(copperpour not_allowed)
			(footprints allowed)
		)
		(placement
			(enabled no)
			(sheetname "")
		)
		(fill yes
			(thermal_gap 0.5)
			(thermal_bridge_width 0.5)
			(island_removal_mode 0)
		)
		(polygon
			(pts
				(arc
					(start 328.085704 7.571994)
					(mid 327.382124 7.571994)
					(end 328.085704 7.571994)
				)
			)
		)
	)
	(zone
		(layers "F.Cu" "In2.Cu" "In4.Cu" "In6.Cu" "In11.Cu")
		(hatch none 0.5)
		(connect_pads
			(clearance 0)
		)
		(min_thickness 0.25)
		(keepout
			(tracks not_allowed)
			(vias allowed)
			(pads allowed)
			(copperpour not_allowed)
			(footprints allowed)
		)
		(placement
			(enabled no)
			(sheetname "")
		)
		(fill yes
			(thermal_gap 0.5)
			(thermal_bridge_width 0.5)
			(island_removal_mode 0)
		)
		(polygon
			(pts
				(arc
					(start 262.589772 8.435594)
					(mid 261.886192 8.435594)
					(end 262.589772 8.435594)
				)
			)
		)
	)
	(zone
		(layers "F.Cu" "In2.Cu" "In4.Cu" "In6.Cu" "In11.Cu" "In13.Cu")
		(hatch none 0.5)
		(connect_pads
			(clearance 0)
		)
		(min_thickness 0.25)
		(keepout
			(tracks not_allowed)
			(vias allowed)
			(pads allowed)
			(copperpour not_allowed)
			(footprints allowed)
		)
		(placement
			(enabled no)
			(sheetname "")
		)
		(fill yes
			(thermal_gap 0.5)
			(thermal_bridge_width 0.5)
			(island_removal_mode 0)
		)
		(polygon
			(pts
				(arc
					(start 12.851638 -114.706908)
					(mid 12.148058 -114.706908)
					(end 12.851638 -114.706908)
				)
			)
		)
	)
	(zone
		(layers "F.Cu" "In2.Cu" "In4.Cu" "In6.Cu" "In11.Cu" "In13.Cu")
		(hatch none 0.5)
		(connect_pads
			(clearance 0)
		)
		(min_thickness 0.25)
		(keepout
			(tracks not_allowed)
			(vias allowed)
			(pads allowed)
			(copperpour not_allowed)
			(footprints allowed)
		)
		(placement
			(enabled no)
			(sheetname "")
		)
		(fill yes
			(thermal_gap 0.5)
			(thermal_bridge_width 0.5)
			(island_removal_mode 0)
		)
		(polygon
			(pts
				(arc
					(start 11.988038 -114.706908)
					(mid 11.284458 -114.706908)
					(end 11.988038 -114.706908)
				)
			)
		)
	)
	(zone
		(layers "F.Cu" "In2.Cu" "In4.Cu" "In6.Cu" "In11.Cu" "In13.Cu")
		(hatch none 0.5)
		(connect_pads
			(clearance 0)
		)
		(min_thickness 0.25)
		(keepout
			(tracks not_allowed)
			(vias allowed)
			(pads allowed)
			(copperpour not_allowed)
			(footprints allowed)
		)
		(placement
			(enabled no)
			(sheetname "")
		)
		(fill yes
			(thermal_gap 0.5)
			(thermal_bridge_width 0.5)
			(island_removal_mode 0)
		)
		(polygon
			(pts
				(arc
					(start 328.085704 3.355594)
					(mid 327.382124 3.355594)
					(end 328.085704 3.355594)
				)
			)
		)
	)
	(zone
		(layers "F.Cu" "In2.Cu" "In4.Cu" "In6.Cu" "In11.Cu" "In13.Cu")
		(hatch none 0.5)
		(connect_pads
			(clearance 0)
		)
		(min_thickness 0.25)
		(keepout
			(tracks not_allowed)
			(vias allowed)
			(pads allowed)
			(copperpour not_allowed)
			(footprints allowed)
		)
		(placement
			(enabled no)
			(sheetname "")
		)
		(fill yes
			(thermal_gap 0.5)
			(thermal_bridge_width 0.5)
			(island_removal_mode 0)
		)
		(polygon
			(pts
				(arc
					(start 328.085704 2.491994)
					(mid 327.382124 2.491994)
					(end 328.085704 2.491994)
				)
			)
		)
	)
	(zone
		(layers "F.Cu" "In2.Cu" "In4.Cu" "In6.Cu" "In11.Cu" "In13.Cu")
		(hatch none 0.5)
		(connect_pads
			(clearance 0)
		)
		(min_thickness 0.25)
		(keepout
			(tracks not_allowed)
			(vias allowed)
			(pads allowed)
			(copperpour not_allowed)
			(footprints allowed)
		)
		(placement
			(enabled no)
			(sheetname "")
		)
		(fill yes
			(thermal_gap 0.5)
			(thermal_bridge_width 0.5)
			(island_removal_mode 0)
		)
		(polygon
			(pts
				(arc
					(start 376.94489 3.355594)
					(mid 376.24131 3.355594)
					(end 376.94489 3.355594)
				)
			)
		)
	)
	(zone
		(layers "F.Cu" "In2.Cu" "In4.Cu" "In6.Cu" "In11.Cu" "In13.Cu")
		(hatch none 0.5)
		(connect_pads
			(clearance 0)
		)
		(min_thickness 0.25)
		(keepout
			(tracks not_allowed)
			(vias allowed)
			(pads allowed)
			(copperpour not_allowed)
			(footprints allowed)
		)
		(placement
			(enabled no)
			(sheetname "")
		)
		(fill yes
			(thermal_gap 0.5)
			(thermal_bridge_width 0.5)
			(island_removal_mode 0)
		)
		(polygon
			(pts
				(arc
					(start 16.71193 -406.171908)
					(mid 16.00835 -406.171908)
					(end 16.71193 -406.171908)
				)
			)
		)
	)
	(zone
		(layers "F.Cu" "In2.Cu" "In4.Cu" "In6.Cu" "In11.Cu" "In13.Cu")
		(hatch none 0.5)
		(connect_pads
			(clearance 0)
		)
		(min_thickness 0.25)
		(keepout
			(tracks not_allowed)
			(vias allowed)
			(pads allowed)
			(copperpour not_allowed)
			(footprints allowed)
		)
		(placement
			(enabled no)
			(sheetname "")
		)
		(fill yes
			(thermal_gap 0.5)
			(thermal_bridge_width 0.5)
			(island_removal_mode 0)
		)
		(polygon
			(pts
				(arc
					(start 341.156798 3.355594)
					(mid 340.453218 3.355594)
					(end 341.156798 3.355594)
				)
			)
		)
	)
	(zone
		(layers "F.Cu" "In2.Cu" "In4.Cu" "In6.Cu" "In11.Cu" "In13.Cu")
		(hatch none 0.5)
		(connect_pads
			(clearance 0)
		)
		(min_thickness 0.25)
		(keepout
			(tracks not_allowed)
			(vias allowed)
			(pads allowed)
			(copperpour not_allowed)
			(footprints allowed)
		)
		(placement
			(enabled no)
			(sheetname "")
		)
		(fill yes
			(thermal_gap 0.5)
			(thermal_bridge_width 0.5)
			(island_removal_mode 0)
		)
		(polygon
			(pts
				(arc
					(start 16.71193 -407.035508)
					(mid 16.00835 -407.035508)
					(end 16.71193 -407.035508)
				)
			)
		)
	)
	(zone
		(layers "F.Cu" "In2.Cu" "In4.Cu" "In6.Cu" "In11.Cu" "In13.Cu")
		(hatch none 0.5)
		(connect_pads
			(clearance 0)
		)
		(min_thickness 0.25)
		(keepout
			(tracks not_allowed)
			(vias allowed)
			(pads allowed)
			(copperpour not_allowed)
			(footprints allowed)
		)
		(placement
			(enabled no)
			(sheetname "")
		)
		(fill yes
			(thermal_gap 0.5)
			(thermal_bridge_width 0.5)
			(island_removal_mode 0)
		)
		(polygon
			(pts
				(arc
					(start 376.94489 2.491994)
					(mid 376.24131 2.491994)
					(end 376.94489 2.491994)
				)
			)
		)
	)
	(zone
		(layers "F.Cu" "In2.Cu" "In4.Cu" "In6.Cu" "In11.Cu" "In13.Cu")
		(hatch none 0.5)
		(connect_pads
			(clearance 0)
		)
		(min_thickness 0.25)
		(keepout
			(tracks not_allowed)
			(vias allowed)
			(pads allowed)
			(copperpour not_allowed)
			(footprints allowed)
		)
		(placement
			(enabled no)
			(sheetname "")
		)
		(fill yes
			(thermal_gap 0.5)
			(thermal_bridge_width 0.5)
			(island_removal_mode 0)
		)
		(polygon
			(pts
				(arc
					(start 262.589772 3.355594)
					(mid 261.886192 3.355594)
					(end 262.589772 3.355594)
				)
			)
		)
	)
	(zone
		(layers "F.Cu" "In2.Cu" "In4.Cu" "In6.Cu" "In11.Cu" "In13.Cu")
		(hatch none 0.5)
		(connect_pads
			(clearance 0)
		)
		(min_thickness 0.25)
		(keepout
			(tracks not_allowed)
			(vias allowed)
			(pads allowed)
			(copperpour not_allowed)
			(footprints allowed)
		)
		(placement
			(enabled no)
			(sheetname "")
		)
		(fill yes
			(thermal_gap 0.5)
			(thermal_bridge_width 0.5)
			(island_removal_mode 0)
		)
		(polygon
			(pts
				(arc
					(start 262.589772 2.491994)
					(mid 261.886192 2.491994)
					(end 262.589772 2.491994)
				)
			)
		)
	)
	(zone
		(layers "F.Cu" "In2.Cu" "In4.Cu" "In6.Cu" "In11.Cu" "In13.Cu")
		(hatch none 0.5)
		(connect_pads
			(clearance 0)
		)
		(min_thickness 0.25)
		(keepout
			(tracks not_allowed)
			(vias allowed)
			(pads allowed)
			(copperpour not_allowed)
			(footprints allowed)
		)
		(placement
			(enabled no)
			(sheetname "")
		)
		(fill yes
			(thermal_gap 0.5)
			(thermal_bridge_width 0.5)
			(island_removal_mode 0)
		)
		(polygon
			(pts
				(arc
					(start 341.156798 2.491994)
					(mid 340.453218 2.491994)
					(end 341.156798 2.491994)
				)
			)
		)
	)
	(zone
		(layers "F.Cu" "In2.Cu" "In4.Cu" "In6.Cu" "In11.Cu" "In13.Cu" "In15.Cu")
		(hatch none 0.5)
		(connect_pads
			(clearance 0)
		)
		(min_thickness 0.25)
		(keepout
			(tracks not_allowed)
			(vias allowed)
			(pads allowed)
			(copperpour not_allowed)
			(footprints allowed)
		)
		(placement
			(enabled no)
			(sheetname "")
		)
		(fill yes
			(thermal_gap 0.5)
			(thermal_bridge_width 0.5)
			(island_removal_mode 0)
		)
		(polygon
			(pts
				(arc
					(start 395.242034 -436.160672)
					(mid 395.264352 -436.214554)
					(end 395.318234 -436.236872)
				)
				(arc
					(start 396.258034 -436.236872)
					(mid 396.311916 -436.214554)
					(end 396.334234 -436.160672)
				)
				(arc
					(start 396.334234 -433.619148)
					(mid 396.311916 -433.565266)
					(end 396.258034 -433.542948)
				)
				(arc
					(start 395.318234 -433.542948)
					(mid 395.264352 -433.565266)
					(end 395.242034 -433.619148)
				)
			)
		)
	)
	(zone
		(layers "F.Cu" "In2.Cu" "In4.Cu" "In6.Cu" "In11.Cu" "In13.Cu" "In15.Cu")
		(hatch none 0.5)
		(connect_pads
			(clearance 0)
		)
		(min_thickness 0.25)
		(keepout
			(tracks not_allowed)
			(vias allowed)
			(pads allowed)
			(copperpour not_allowed)
			(footprints allowed)
		)
		(placement
			(enabled no)
			(sheetname "")
		)
		(fill yes
			(thermal_gap 0.5)
			(thermal_bridge_width 0.5)
			(island_removal_mode 0)
		)
		(polygon
			(pts
				(arc
					(start 324.1421 -436.160672)
					(mid 324.164418 -436.214554)
					(end 324.2183 -436.236872)
				)
				(arc
					(start 325.1581 -436.236872)
					(mid 325.211982 -436.214554)
					(end 325.2343 -436.160672)
				)
				(arc
					(start 325.2343 -433.619148)
					(mid 325.211982 -433.565266)
					(end 325.1581 -433.542948)
				)
				(arc
					(start 324.2183 -433.542948)
					(mid 324.164418 -433.565266)
					(end 324.1421 -433.619148)
				)
			)
		)
	)
	(zone
		(layers "F.Cu" "In2.Cu" "In4.Cu" "In6.Cu" "In11.Cu" "In13.Cu" "In15.Cu")
		(hatch none 0.5)
		(connect_pads
			(clearance 0)
		)
		(min_thickness 0.25)
		(keepout
			(tracks not_allowed)
			(vias allowed)
			(pads allowed)
			(copperpour not_allowed)
			(footprints allowed)
		)
		(placement
			(enabled no)
			(sheetname "")
		)
		(fill yes
			(thermal_gap 0.5)
			(thermal_bridge_width 0.5)
			(island_removal_mode 0)
		)
		(polygon
			(pts
				(arc
					(start 79.142082 -435.160674)
					(mid 79.1644 -435.214556)
					(end 79.218282 -435.236874)
				)
				(arc
					(start 80.158082 -435.236874)
					(mid 80.211964 -435.214556)
					(end 80.234282 -435.160674)
				)
				(arc
					(start 80.234282 -432.61915)
					(mid 80.211964 -432.565268)
					(end 80.158082 -432.54295)
				)
				(arc
					(start 79.218282 -432.54295)
					(mid 79.1644 -432.565268)
					(end 79.142082 -432.61915)
				)
			)
		)
	)
	(zone
		(layers "F.Cu" "In2.Cu" "In4.Cu" "In6.Cu" "In11.Cu" "In13.Cu" "In15.Cu")
		(hatch none 0.5)
		(connect_pads
			(clearance 0)
		)
		(min_thickness 0.25)
		(keepout
			(tracks not_allowed)
			(vias allowed)
			(pads allowed)
			(copperpour not_allowed)
			(footprints allowed)
		)
		(placement
			(enabled no)
			(sheetname "")
		)
		(fill yes
			(thermal_gap 0.5)
			(thermal_bridge_width 0.5)
			(island_removal_mode 0)
		)
		(polygon
			(pts
				(arc
					(start 398.242028 -435.160674)
					(mid 398.264346 -435.214556)
					(end 398.318228 -435.236874)
				)
				(arc
					(start 399.258028 -435.236874)
					(mid 399.31191 -435.214556)
					(end 399.334228 -435.160674)
				)
				(arc
					(start 399.334228 -432.61915)
					(mid 399.31191 -432.565268)
					(end 399.258028 -432.54295)
				)
				(arc
					(start 398.318228 -432.54295)
					(mid 398.264346 -432.565268)
					(end 398.242028 -432.61915)
				)
			)
		)
	)
	(zone
		(layers "F.Cu" "In2.Cu" "In4.Cu" "In6.Cu" "In11.Cu" "In13.Cu" "In15.Cu")
		(hatch none 0.5)
		(connect_pads
			(clearance 0)
		)
		(min_thickness 0.25)
		(keepout
			(tracks not_allowed)
			(vias allowed)
			(pads allowed)
			(copperpour not_allowed)
			(footprints allowed)
		)
		(placement
			(enabled no)
			(sheetname "")
		)
		(fill yes
			(thermal_gap 0.5)
			(thermal_bridge_width 0.5)
			(island_removal_mode 0)
		)
		(polygon
			(pts
				(arc
					(start 131.242054 -432.56073)
					(mid 131.264372 -432.614612)
					(end 131.318254 -432.63693)
				)
				(arc
					(start 132.258054 -432.63693)
					(mid 132.311936 -432.614612)
					(end 132.334254 -432.56073)
				)
				(arc
					(start 132.334254 -430.019206)
					(mid 132.311936 -429.965324)
					(end 132.258054 -429.943006)
				)
				(arc
					(start 131.318254 -429.943006)
					(mid 131.264372 -429.965324)
					(end 131.242054 -430.019206)
				)
			)
		)
	)
	(zone
		(layers "F.Cu" "In2.Cu" "In4.Cu" "In6.Cu" "In11.Cu" "In13.Cu" "In15.Cu")
		(hatch none 0.5)
		(connect_pads
			(clearance 0)
		)
		(min_thickness 0.25)
		(keepout
			(tracks not_allowed)
			(vias allowed)
			(pads allowed)
			(copperpour not_allowed)
			(footprints allowed)
		)
		(placement
			(enabled no)
			(sheetname "")
		)
		(fill yes
			(thermal_gap 0.5)
			(thermal_bridge_width 0.5)
			(island_removal_mode 0)
		)
		(polygon
			(pts
				(arc
					(start 133.24205 -435.160674)
					(mid 133.264368 -435.214556)
					(end 133.31825 -435.236874)
				)
				(arc
					(start 134.25805 -435.236874)
					(mid 134.311932 -435.214556)
					(end 134.33425 -435.160674)
				)
				(arc
					(start 134.33425 -432.61915)
					(mid 134.311932 -432.565268)
					(end 134.25805 -432.54295)
				)
				(arc
					(start 133.31825 -432.54295)
					(mid 133.264368 -432.565268)
					(end 133.24205 -432.61915)
				)
			)
		)
	)
	(zone
		(layers "F.Cu" "In2.Cu" "In4.Cu" "In6.Cu" "In11.Cu" "In13.Cu" "In15.Cu")
		(hatch none 0.5)
		(connect_pads
			(clearance 0)
		)
		(min_thickness 0.25)
		(keepout
			(tracks not_allowed)
			(vias allowed)
			(pads allowed)
			(copperpour not_allowed)
			(footprints allowed)
		)
		(placement
			(enabled no)
			(sheetname "")
		)
		(fill yes
			(thermal_gap 0.5)
			(thermal_bridge_width 0.5)
			(island_removal_mode 0)
		)
		(polygon
			(pts
				(arc
					(start 81.142078 -432.56073)
					(mid 81.164396 -432.614612)
					(end 81.218278 -432.63693)
				)
				(arc
					(start 82.158078 -432.63693)
					(mid 82.21196 -432.614612)
					(end 82.234278 -432.56073)
				)
				(arc
					(start 82.234278 -430.019206)
					(mid 82.21196 -429.965324)
					(end 82.158078 -429.943006)
				)
				(arc
					(start 81.218278 -429.943006)
					(mid 81.164396 -429.965324)
					(end 81.142078 -430.019206)
				)
			)
		)
	)
	(zone
		(layers "F.Cu" "In2.Cu" "In4.Cu" "In6.Cu" "In11.Cu" "In13.Cu" "In15.Cu")
		(hatch none 0.5)
		(connect_pads
			(clearance 0)
		)
		(min_thickness 0.25)
		(keepout
			(tracks not_allowed)
			(vias allowed)
			(pads allowed)
			(copperpour not_allowed)
			(footprints allowed)
		)
		(placement
			(enabled no)
			(sheetname "")
		)
		(fill yes
			(thermal_gap 0.5)
			(thermal_bridge_width 0.5)
			(island_removal_mode 0)
		)
		(polygon
			(pts
				(arc
					(start 127.242062 -436.160672)
					(mid 127.26438 -436.214554)
					(end 127.318262 -436.236872)
				)
				(arc
					(start 128.258062 -436.236872)
					(mid 128.311944 -436.214554)
					(end 128.334262 -436.160672)
				)
				(arc
					(start 128.334262 -433.619148)
					(mid 128.311944 -433.565266)
					(end 128.258062 -433.542948)
				)
				(arc
					(start 127.318262 -433.542948)
					(mid 127.26438 -433.565266)
					(end 127.242062 -433.619148)
				)
			)
		)
	)
	(zone
		(layers "F.Cu" "In2.Cu" "In4.Cu" "In6.Cu" "In11.Cu" "In13.Cu" "In15.Cu")
		(hatch none 0.5)
		(connect_pads
			(clearance 0)
		)
		(min_thickness 0.25)
		(keepout
			(tracks not_allowed)
			(vias allowed)
			(pads allowed)
			(copperpour not_allowed)
			(footprints allowed)
		)
		(placement
			(enabled no)
			(sheetname "")
		)
		(fill yes
			(thermal_gap 0.5)
			(thermal_bridge_width 0.5)
			(island_removal_mode 0)
		)
		(polygon
			(pts
				(arc
					(start 335.142078 -435.160674)
					(mid 335.164396 -435.214556)
					(end 335.218278 -435.236874)
				)
				(arc
					(start 336.158078 -435.236874)
					(mid 336.21196 -435.214556)
					(end 336.234278 -435.160674)
				)
				(arc
					(start 336.234278 -432.61915)
					(mid 336.21196 -432.565268)
					(end 336.158078 -432.54295)
				)
				(arc
					(start 335.218278 -432.54295)
					(mid 335.164396 -432.565268)
					(end 335.142078 -432.61915)
				)
			)
		)
	)
	(zone
		(layers "F.Cu" "In2.Cu" "In4.Cu" "In6.Cu" "In11.Cu" "In13.Cu" "In15.Cu")
		(hatch none 0.5)
		(connect_pads
			(clearance 0)
		)
		(min_thickness 0.25)
		(keepout
			(tracks not_allowed)
			(vias allowed)
			(pads allowed)
			(copperpour not_allowed)
			(footprints allowed)
		)
		(placement
			(enabled no)
			(sheetname "")
		)
		(fill yes
			(thermal_gap 0.5)
			(thermal_bridge_width 0.5)
			(island_removal_mode 0)
		)
		(polygon
			(pts
				(arc
					(start 335.142078 -431.560732)
					(mid 335.164396 -431.614614)
					(end 335.218278 -431.636932)
				)
				(arc
					(start 336.158078 -431.636932)
					(mid 336.21196 -431.614614)
					(end 336.234278 -431.560732)
				)
				(arc
					(start 336.234278 -429.019208)
					(mid 336.21196 -428.965326)
					(end 336.158078 -428.943008)
				)
				(arc
					(start 335.218278 -428.943008)
					(mid 335.164396 -428.965326)
					(end 335.142078 -429.019208)
				)
			)
		)
	)
	(zone
		(layers "F.Cu" "In2.Cu" "In4.Cu" "In6.Cu" "In11.Cu" "In13.Cu" "In15.Cu")
		(hatch none 0.5)
		(connect_pads
			(clearance 0)
		)
		(min_thickness 0.25)
		(keepout
			(tracks not_allowed)
			(vias allowed)
			(pads allowed)
			(copperpour not_allowed)
			(footprints allowed)
		)
		(placement
			(enabled no)
			(sheetname "")
		)
		(fill yes
			(thermal_gap 0.5)
			(thermal_bridge_width 0.5)
			(island_removal_mode 0)
		)
		(polygon
			(pts
				(arc
					(start 322.142104 -431.560732)
					(mid 322.164422 -431.614614)
					(end 322.218304 -431.636932)
				)
				(arc
					(start 323.158104 -431.636932)
					(mid 323.211986 -431.614614)
					(end 323.234304 -431.560732)
				)
				(arc
					(start 323.234304 -429.019208)
					(mid 323.211986 -428.965326)
					(end 323.158104 -428.943008)
				)
				(arc
					(start 322.218304 -428.943008)
					(mid 322.164422 -428.965326)
					(end 322.142104 -429.019208)
				)
			)
		)
	)
	(zone
		(layers "F.Cu" "In2.Cu" "In4.Cu" "In6.Cu" "In11.Cu" "In13.Cu" "In15.Cu")
		(hatch none 0.5)
		(connect_pads
			(clearance 0)
		)
		(min_thickness 0.25)
		(keepout
			(tracks not_allowed)
			(vias allowed)
			(pads allowed)
			(copperpour not_allowed)
			(footprints allowed)
		)
		(placement
			(enabled no)
			(sheetname "")
		)
		(fill yes
			(thermal_gap 0.5)
			(thermal_bridge_width 0.5)
			(island_removal_mode 0)
		)
		(polygon
			(pts
				(arc
					(start 135.242046 -432.56073)
					(mid 135.264364 -432.614612)
					(end 135.318246 -432.63693)
				)
				(arc
					(start 136.258046 -432.63693)
					(mid 136.311928 -432.614612)
					(end 136.334246 -432.56073)
				)
				(arc
					(start 136.334246 -430.019206)
					(mid 136.311928 -429.965324)
					(end 136.258046 -429.943006)
				)
				(arc
					(start 135.318246 -429.943006)
					(mid 135.264364 -429.965324)
					(end 135.242046 -430.019206)
				)
			)
		)
	)
	(zone
		(layers "F.Cu" "In2.Cu" "In4.Cu" "In6.Cu" "In11.Cu" "In13.Cu" "In15.Cu")
		(hatch none 0.5)
		(connect_pads
			(clearance 0)
		)
		(min_thickness 0.25)
		(keepout
			(tracks not_allowed)
			(vias allowed)
			(pads allowed)
			(copperpour not_allowed)
			(footprints allowed)
		)
		(placement
			(enabled no)
			(sheetname "")
		)
		(fill yes
			(thermal_gap 0.5)
			(thermal_bridge_width 0.5)
			(island_removal_mode 0)
		)
		(polygon
			(pts
				(arc
					(start 146.242024 -435.160674)
					(mid 146.264342 -435.214556)
					(end 146.318224 -435.236874)
				)
				(arc
					(start 147.258024 -435.236874)
					(mid 147.311906 -435.214556)
					(end 147.334224 -435.160674)
				)
				(arc
					(start 147.334224 -432.61915)
					(mid 147.311906 -432.565268)
					(end 147.258024 -432.54295)
				)
				(arc
					(start 146.318224 -432.54295)
					(mid 146.264342 -432.565268)
					(end 146.242024 -432.61915)
				)
			)
		)
	)
	(zone
		(layers "F.Cu" "In2.Cu" "In4.Cu" "In6.Cu" "In11.Cu" "In13.Cu" "In15.Cu")
		(hatch none 0.5)
		(connect_pads
			(clearance 0)
		)
		(min_thickness 0.25)
		(keepout
			(tracks not_allowed)
			(vias allowed)
			(pads allowed)
			(copperpour not_allowed)
			(footprints allowed)
		)
		(placement
			(enabled no)
			(sheetname "")
		)
		(fill yes
			(thermal_gap 0.5)
			(thermal_bridge_width 0.5)
			(island_removal_mode 0)
		)
		(polygon
			(pts
				(arc
					(start 383.242058 -432.56073)
					(mid 383.264376 -432.614612)
					(end 383.318258 -432.63693)
				)
				(arc
					(start 384.258058 -432.63693)
					(mid 384.31194 -432.614612)
					(end 384.334258 -432.56073)
				)
				(arc
					(start 384.334258 -430.019206)
					(mid 384.31194 -429.965324)
					(end 384.258058 -429.943006)
				)
				(arc
					(start 383.318258 -429.943006)
					(mid 383.264376 -429.965324)
					(end 383.242058 -430.019206)
				)
			)
		)
	)
	(zone
		(layers "F.Cu" "In2.Cu" "In4.Cu" "In6.Cu" "In11.Cu" "In13.Cu" "In15.Cu")
		(hatch none 0.5)
		(connect_pads
			(clearance 0)
		)
		(min_thickness 0.25)
		(keepout
			(tracks not_allowed)
			(vias allowed)
			(pads allowed)
			(copperpour not_allowed)
			(footprints allowed)
		)
		(placement
			(enabled no)
			(sheetname "")
		)
		(fill yes
			(thermal_gap 0.5)
			(thermal_bridge_width 0.5)
			(island_removal_mode 0)
		)
		(polygon
			(pts
				(arc
					(start 408.242008 -432.56073)
					(mid 408.264326 -432.614612)
					(end 408.318208 -432.63693)
				)
				(arc
					(start 409.258008 -432.63693)
					(mid 409.31189 -432.614612)
					(end 409.334208 -432.56073)
				)
				(arc
					(start 409.334208 -430.019206)
					(mid 409.31189 -429.965324)
					(end 409.258008 -429.943006)
				)
				(arc
					(start 408.318208 -429.943006)
					(mid 408.264326 -429.965324)
					(end 408.242008 -430.019206)
				)
			)
		)
	)
	(zone
		(layers "F.Cu" "In2.Cu" "In4.Cu" "In6.Cu" "In11.Cu" "In13.Cu" "In15.Cu")
		(hatch none 0.5)
		(connect_pads
			(clearance 0)
		)
		(min_thickness 0.25)
		(keepout
			(tracks not_allowed)
			(vias allowed)
			(pads allowed)
			(copperpour not_allowed)
			(footprints allowed)
		)
		(placement
			(enabled no)
			(sheetname "")
		)
		(fill yes
			(thermal_gap 0.5)
			(thermal_bridge_width 0.5)
			(island_removal_mode 0)
		)
		(polygon
			(pts
				(arc
					(start 387.24205 -432.56073)
					(mid 387.264368 -432.614612)
					(end 387.31825 -432.63693)
				)
				(arc
					(start 388.25805 -432.63693)
					(mid 388.311932 -432.614612)
					(end 388.33425 -432.56073)
				)
				(arc
					(start 388.33425 -430.019206)
					(mid 388.311932 -429.965324)
					(end 388.25805 -429.943006)
				)
				(arc
					(start 387.31825 -429.943006)
					(mid 387.264368 -429.965324)
					(end 387.24205 -430.019206)
				)
			)
		)
	)
	(zone
		(layers "F.Cu" "In2.Cu" "In4.Cu" "In6.Cu" "In11.Cu" "In13.Cu" "In15.Cu")
		(hatch none 0.5)
		(connect_pads
			(clearance 0)
		)
		(min_thickness 0.25)
		(keepout
			(tracks not_allowed)
			(vias allowed)
			(pads allowed)
			(copperpour not_allowed)
			(footprints allowed)
		)
		(placement
			(enabled no)
			(sheetname "")
		)
		(fill yes
			(thermal_gap 0.5)
			(thermal_bridge_width 0.5)
			(island_removal_mode 0)
		)
		(polygon
			(pts
				(arc
					(start 79.142082 -431.560732)
					(mid 79.1644 -431.614614)
					(end 79.218282 -431.636932)
				)
				(arc
					(start 80.158082 -431.636932)
					(mid 80.211964 -431.614614)
					(end 80.234282 -431.560732)
				)
				(arc
					(start 80.234282 -429.019208)
					(mid 80.211964 -428.965326)
					(end 80.158082 -428.943008)
				)
				(arc
					(start 79.218282 -428.943008)
					(mid 79.1644 -428.965326)
					(end 79.142082 -429.019208)
				)
			)
		)
	)
	(zone
		(layers "F.Cu" "In2.Cu" "In4.Cu" "In6.Cu" "In11.Cu" "In13.Cu" "In15.Cu")
		(hatch none 0.5)
		(connect_pads
			(clearance 0)
		)
		(min_thickness 0.25)
		(keepout
			(tracks not_allowed)
			(vias allowed)
			(pads allowed)
			(copperpour not_allowed)
			(footprints allowed)
		)
		(placement
			(enabled no)
			(sheetname "")
		)
		(fill yes
			(thermal_gap 0.5)
			(thermal_bridge_width 0.5)
			(island_removal_mode 0)
		)
		(polygon
			(pts
				(arc
					(start 152.242012 -432.56073)
					(mid 152.26433 -432.614612)
					(end 152.318212 -432.63693)
				)
				(arc
					(start 153.258012 -432.63693)
					(mid 153.311894 -432.614612)
					(end 153.334212 -432.56073)
				)
				(arc
					(start 153.334212 -430.019206)
					(mid 153.311894 -429.965324)
					(end 153.258012 -429.943006)
				)
				(arc
					(start 152.318212 -429.943006)
					(mid 152.26433 -429.965324)
					(end 152.242012 -430.019206)
				)
			)
		)
	)
	(zone
		(layers "F.Cu" "In2.Cu" "In4.Cu" "In6.Cu" "In11.Cu" "In13.Cu" "In15.Cu")
		(hatch none 0.5)
		(connect_pads
			(clearance 0)
		)
		(min_thickness 0.25)
		(keepout
			(tracks not_allowed)
			(vias allowed)
			(pads allowed)
			(copperpour not_allowed)
			(footprints allowed)
		)
		(placement
			(enabled no)
			(sheetname "")
		)
		(fill yes
			(thermal_gap 0.5)
			(thermal_bridge_width 0.5)
			(island_removal_mode 0)
		)
		(polygon
			(pts
				(arc
					(start 85.14207 -432.56073)
					(mid 85.164388 -432.614612)
					(end 85.21827 -432.63693)
				)
				(arc
					(start 86.15807 -432.63693)
					(mid 86.211952 -432.614612)
					(end 86.23427 -432.56073)
				)
				(arc
					(start 86.23427 -430.019206)
					(mid 86.211952 -429.965324)
					(end 86.15807 -429.943006)
				)
				(arc
					(start 85.21827 -429.943006)
					(mid 85.164388 -429.965324)
					(end 85.14207 -430.019206)
				)
			)
		)
	)
	(zone
		(layers "F.Cu" "In2.Cu" "In4.Cu" "In6.Cu" "In11.Cu" "In13.Cu" "In15.Cu")
		(hatch none 0.5)
		(connect_pads
			(clearance 0)
		)
		(min_thickness 0.25)
		(keepout
			(tracks not_allowed)
			(vias allowed)
			(pads allowed)
			(copperpour not_allowed)
			(footprints allowed)
		)
		(placement
			(enabled no)
			(sheetname "")
		)
		(fill yes
			(thermal_gap 0.5)
			(thermal_bridge_width 0.5)
			(island_removal_mode 0)
		)
		(polygon
			(pts
				(arc
					(start 402.24202 -435.160674)
					(mid 402.264338 -435.214556)
					(end 402.31822 -435.236874)
				)
				(arc
					(start 403.25802 -435.236874)
					(mid 403.311902 -435.214556)
					(end 403.33422 -435.160674)
				)
				(arc
					(start 403.33422 -432.61915)
					(mid 403.311902 -432.565268)
					(end 403.25802 -432.54295)
				)
				(arc
					(start 402.31822 -432.54295)
					(mid 402.264338 -432.565268)
					(end 402.24202 -432.61915)
				)
			)
		)
	)
	(zone
		(layers "F.Cu" "In2.Cu" "In4.Cu" "In6.Cu" "In11.Cu" "In13.Cu" "In15.Cu")
		(hatch none 0.5)
		(connect_pads
			(clearance 0)
		)
		(min_thickness 0.25)
		(keepout
			(tracks not_allowed)
			(vias allowed)
			(pads allowed)
			(copperpour not_allowed)
			(footprints allowed)
		)
		(placement
			(enabled no)
			(sheetname "")
		)
		(fill yes
			(thermal_gap 0.5)
			(thermal_bridge_width 0.5)
			(island_removal_mode 0)
		)
		(polygon
			(pts
				(arc
					(start 150.242016 -435.160674)
					(mid 150.264334 -435.214556)
					(end 150.318216 -435.236874)
				)
				(arc
					(start 151.258016 -435.236874)
					(mid 151.311898 -435.214556)
					(end 151.334216 -435.160674)
				)
				(arc
					(start 151.334216 -432.61915)
					(mid 151.311898 -432.565268)
					(end 151.258016 -432.54295)
				)
				(arc
					(start 150.318216 -432.54295)
					(mid 150.264334 -432.565268)
					(end 150.242016 -432.61915)
				)
			)
		)
	)
	(zone
		(layers "F.Cu" "In2.Cu" "In4.Cu" "In6.Cu" "In11.Cu" "In13.Cu" "In15.Cu")
		(hatch none 0.5)
		(connect_pads
			(clearance 0)
		)
		(min_thickness 0.25)
		(keepout
			(tracks not_allowed)
			(vias allowed)
			(pads allowed)
			(copperpour not_allowed)
			(footprints allowed)
		)
		(placement
			(enabled no)
			(sheetname "")
		)
		(fill yes
			(thermal_gap 0.5)
			(thermal_bridge_width 0.5)
			(island_removal_mode 0)
		)
		(polygon
			(pts
				(arc
					(start 391.242042 -436.160672)
					(mid 391.26436 -436.214554)
					(end 391.318242 -436.236872)
				)
				(arc
					(start 392.258042 -436.236872)
					(mid 392.311924 -436.214554)
					(end 392.334242 -436.160672)
				)
				(arc
					(start 392.334242 -433.619148)
					(mid 392.311924 -433.565266)
					(end 392.258042 -433.542948)
				)
				(arc
					(start 391.318242 -433.542948)
					(mid 391.26436 -433.565266)
					(end 391.242042 -433.619148)
				)
			)
		)
	)
	(zone
		(layers "F.Cu" "In2.Cu" "In4.Cu" "In6.Cu" "In11.Cu" "In13.Cu" "In15.Cu")
		(hatch none 0.5)
		(connect_pads
			(clearance 0)
		)
		(min_thickness 0.25)
		(keepout
			(tracks not_allowed)
			(vias allowed)
			(pads allowed)
			(copperpour not_allowed)
			(footprints allowed)
		)
		(placement
			(enabled no)
			(sheetname "")
		)
		(fill yes
			(thermal_gap 0.5)
			(thermal_bridge_width 0.5)
			(island_removal_mode 0)
		)
		(polygon
			(pts
				(arc
					(start 148.24202 -432.56073)
					(mid 148.264338 -432.614612)
					(end 148.31822 -432.63693)
				)
				(arc
					(start 149.25802 -432.63693)
					(mid 149.311902 -432.614612)
					(end 149.33422 -432.56073)
				)
				(arc
					(start 149.33422 -430.019206)
					(mid 149.311902 -429.965324)
					(end 149.25802 -429.943006)
				)
				(arc
					(start 148.31822 -429.943006)
					(mid 148.264338 -429.965324)
					(end 148.24202 -430.019206)
				)
			)
		)
	)
	(zone
		(layers "F.Cu" "In2.Cu" "In4.Cu" "In6.Cu" "In11.Cu" "In13.Cu" "In15.Cu")
		(hatch none 0.5)
		(connect_pads
			(clearance 0)
		)
		(min_thickness 0.25)
		(keepout
			(tracks not_allowed)
			(vias allowed)
			(pads allowed)
			(copperpour not_allowed)
			(footprints allowed)
		)
		(placement
			(enabled no)
			(sheetname "")
		)
		(fill yes
			(thermal_gap 0.5)
			(thermal_bridge_width 0.5)
			(island_removal_mode 0)
		)
		(polygon
			(pts
				(arc
					(start 129.242058 -431.560732)
					(mid 129.264376 -431.614614)
					(end 129.318258 -431.636932)
				)
				(arc
					(start 130.258058 -431.636932)
					(mid 130.31194 -431.614614)
					(end 130.334258 -431.560732)
				)
				(arc
					(start 130.334258 -429.019208)
					(mid 130.31194 -428.965326)
					(end 130.258058 -428.943008)
				)
				(arc
					(start 129.318258 -428.943008)
					(mid 129.264376 -428.965326)
					(end 129.242058 -429.019208)
				)
			)
		)
	)
	(zone
		(layers "F.Cu" "In2.Cu" "In4.Cu" "In6.Cu" "In11.Cu" "In13.Cu" "In15.Cu")
		(hatch none 0.5)
		(connect_pads
			(clearance 0)
		)
		(min_thickness 0.25)
		(keepout
			(tracks not_allowed)
			(vias allowed)
			(pads allowed)
			(copperpour not_allowed)
			(footprints allowed)
		)
		(placement
			(enabled no)
			(sheetname "")
		)
		(fill yes
			(thermal_gap 0.5)
			(thermal_bridge_width 0.5)
			(island_removal_mode 0)
		)
		(polygon
			(pts
				(arc
					(start 320.142108 -436.160672)
					(mid 320.164426 -436.214554)
					(end 320.218308 -436.236872)
				)
				(arc
					(start 321.158108 -436.236872)
					(mid 321.21199 -436.214554)
					(end 321.234308 -436.160672)
				)
				(arc
					(start 321.234308 -433.619148)
					(mid 321.21199 -433.565266)
					(end 321.158108 -433.542948)
				)
				(arc
					(start 320.218308 -433.542948)
					(mid 320.164426 -433.565266)
					(end 320.142108 -433.619148)
				)
			)
		)
	)
	(zone
		(layers "F.Cu" "In2.Cu" "In4.Cu" "In6.Cu" "In11.Cu" "In13.Cu" "In15.Cu")
		(hatch none 0.5)
		(connect_pads
			(clearance 0)
		)
		(min_thickness 0.25)
		(keepout
			(tracks not_allowed)
			(vias allowed)
			(pads allowed)
			(copperpour not_allowed)
			(footprints allowed)
		)
		(placement
			(enabled no)
			(sheetname "")
		)
		(fill yes
			(thermal_gap 0.5)
			(thermal_bridge_width 0.5)
			(island_removal_mode 0)
		)
		(polygon
			(pts
				(arc
					(start 60.14212 -436.160672)
					(mid 60.164438 -436.214554)
					(end 60.21832 -436.236872)
				)
				(arc
					(start 61.15812 -436.236872)
					(mid 61.212002 -436.214554)
					(end 61.23432 -436.160672)
				)
				(arc
					(start 61.23432 -433.619148)
					(mid 61.212002 -433.565266)
					(end 61.15812 -433.542948)
				)
				(arc
					(start 60.21832 -433.542948)
					(mid 60.164438 -433.565266)
					(end 60.14212 -433.619148)
				)
			)
		)
	)
	(zone
		(layers "F.Cu" "In2.Cu" "In4.Cu" "In6.Cu" "In11.Cu" "In13.Cu" "In15.Cu")
		(hatch none 0.5)
		(connect_pads
			(clearance 0)
		)
		(min_thickness 0.25)
		(keepout
			(tracks not_allowed)
			(vias allowed)
			(pads allowed)
			(copperpour not_allowed)
			(footprints allowed)
		)
		(placement
			(enabled no)
			(sheetname "")
		)
		(fill yes
			(thermal_gap 0.5)
			(thermal_bridge_width 0.5)
			(island_removal_mode 0)
		)
		(polygon
			(pts
				(arc
					(start 331.142086 -431.560732)
					(mid 331.164404 -431.614614)
					(end 331.218286 -431.636932)
				)
				(arc
					(start 332.158086 -431.636932)
					(mid 332.211968 -431.614614)
					(end 332.234286 -431.560732)
				)
				(arc
					(start 332.234286 -429.019208)
					(mid 332.211968 -428.965326)
					(end 332.158086 -428.943008)
				)
				(arc
					(start 331.218286 -428.943008)
					(mid 331.164404 -428.965326)
					(end 331.142086 -429.019208)
				)
			)
		)
	)
	(zone
		(layers "F.Cu" "In2.Cu" "In4.Cu" "In6.Cu" "In11.Cu" "In13.Cu" "In15.Cu")
		(hatch none 0.5)
		(connect_pads
			(clearance 0)
		)
		(min_thickness 0.25)
		(keepout
			(tracks not_allowed)
			(vias allowed)
			(pads allowed)
			(copperpour not_allowed)
			(footprints allowed)
		)
		(placement
			(enabled no)
			(sheetname "")
		)
		(fill yes
			(thermal_gap 0.5)
			(thermal_bridge_width 0.5)
			(island_removal_mode 0)
		)
		(polygon
			(pts
				(arc
					(start 400.242024 -432.56073)
					(mid 400.264342 -432.614612)
					(end 400.318224 -432.63693)
				)
				(arc
					(start 401.258024 -432.63693)
					(mid 401.311906 -432.614612)
					(end 401.334224 -432.56073)
				)
				(arc
					(start 401.334224 -430.019206)
					(mid 401.311906 -429.965324)
					(end 401.258024 -429.943006)
				)
				(arc
					(start 400.318224 -429.943006)
					(mid 400.264342 -429.965324)
					(end 400.242024 -430.019206)
				)
			)
		)
	)
	(zone
		(layers "F.Cu" "In2.Cu" "In4.Cu" "In6.Cu" "In11.Cu" "In13.Cu" "In15.Cu")
		(hatch none 0.5)
		(connect_pads
			(clearance 0)
		)
		(min_thickness 0.25)
		(keepout
			(tracks not_allowed)
			(vias allowed)
			(pads allowed)
			(copperpour not_allowed)
			(footprints allowed)
		)
		(placement
			(enabled no)
			(sheetname "")
		)
		(fill yes
			(thermal_gap 0.5)
			(thermal_bridge_width 0.5)
			(island_removal_mode 0)
		)
		(polygon
			(pts
				(arc
					(start 343.142062 -435.160674)
					(mid 343.16438 -435.214556)
					(end 343.218262 -435.236874)
				)
				(arc
					(start 344.158062 -435.236874)
					(mid 344.211944 -435.214556)
					(end 344.234262 -435.160674)
				)
				(arc
					(start 344.234262 -432.61915)
					(mid 344.211944 -432.565268)
					(end 344.158062 -432.54295)
				)
				(arc
					(start 343.218262 -432.54295)
					(mid 343.16438 -432.565268)
					(end 343.142062 -432.61915)
				)
			)
		)
	)
	(zone
		(layers "F.Cu" "In2.Cu" "In4.Cu" "In6.Cu" "In11.Cu" "In13.Cu" "In15.Cu")
		(hatch none 0.5)
		(connect_pads
			(clearance 0)
		)
		(min_thickness 0.25)
		(keepout
			(tracks not_allowed)
			(vias allowed)
			(pads allowed)
			(copperpour not_allowed)
			(footprints allowed)
		)
		(placement
			(enabled no)
			(sheetname "")
		)
		(fill yes
			(thermal_gap 0.5)
			(thermal_bridge_width 0.5)
			(island_removal_mode 0)
		)
		(polygon
			(pts
				(arc
					(start 318.142112 -435.160674)
					(mid 318.16443 -435.214556)
					(end 318.218312 -435.236874)
				)
				(arc
					(start 319.158112 -435.236874)
					(mid 319.211994 -435.214556)
					(end 319.234312 -435.160674)
				)
				(arc
					(start 319.234312 -432.61915)
					(mid 319.211994 -432.565268)
					(end 319.158112 -432.54295)
				)
				(arc
					(start 318.218312 -432.54295)
					(mid 318.16443 -432.565268)
					(end 318.142112 -432.61915)
				)
			)
		)
	)
	(zone
		(layers "F.Cu" "In2.Cu" "In4.Cu" "In6.Cu" "In11.Cu" "In13.Cu" "In15.Cu")
		(hatch none 0.5)
		(connect_pads
			(clearance 0)
		)
		(min_thickness 0.25)
		(keepout
			(tracks not_allowed)
			(vias allowed)
			(pads allowed)
			(copperpour not_allowed)
			(footprints allowed)
		)
		(placement
			(enabled no)
			(sheetname "")
		)
		(fill yes
			(thermal_gap 0.5)
			(thermal_bridge_width 0.5)
			(island_removal_mode 0)
		)
		(polygon
			(pts
				(arc
					(start 58.142124 -435.160674)
					(mid 58.164442 -435.214556)
					(end 58.218324 -435.236874)
				)
				(arc
					(start 59.158124 -435.236874)
					(mid 59.212006 -435.214556)
					(end 59.234324 -435.160674)
				)
				(arc
					(start 59.234324 -432.61915)
					(mid 59.212006 -432.565268)
					(end 59.158124 -432.54295)
				)
				(arc
					(start 58.218324 -432.54295)
					(mid 58.164442 -432.565268)
					(end 58.142124 -432.61915)
				)
			)
		)
	)
	(zone
		(layers "F.Cu" "In2.Cu" "In4.Cu" "In6.Cu" "In11.Cu" "In13.Cu" "In15.Cu")
		(hatch none 0.5)
		(connect_pads
			(clearance 0)
		)
		(min_thickness 0.25)
		(keepout
			(tracks not_allowed)
			(vias allowed)
			(pads allowed)
			(copperpour not_allowed)
			(footprints allowed)
		)
		(placement
			(enabled no)
			(sheetname "")
		)
		(fill yes
			(thermal_gap 0.5)
			(thermal_bridge_width 0.5)
			(island_removal_mode 0)
		)
		(polygon
			(pts
				(arc
					(start 75.14209 -435.160674)
					(mid 75.164408 -435.214556)
					(end 75.21829 -435.236874)
				)
				(arc
					(start 76.15809 -435.236874)
					(mid 76.211972 -435.214556)
					(end 76.23429 -435.160674)
				)
				(arc
					(start 76.23429 -432.61915)
					(mid 76.211972 -432.565268)
					(end 76.15809 -432.54295)
				)
				(arc
					(start 75.21829 -432.54295)
					(mid 75.164408 -432.565268)
					(end 75.14209 -432.61915)
				)
			)
		)
	)
	(zone
		(layers "F.Cu" "In2.Cu" "In4.Cu" "In6.Cu" "In11.Cu" "In13.Cu" "In15.Cu")
		(hatch none 0.5)
		(connect_pads
			(clearance 0)
		)
		(min_thickness 0.25)
		(keepout
			(tracks not_allowed)
			(vias allowed)
			(pads allowed)
			(copperpour not_allowed)
			(footprints allowed)
		)
		(placement
			(enabled no)
			(sheetname "")
		)
		(fill yes
			(thermal_gap 0.5)
			(thermal_bridge_width 0.5)
			(island_removal_mode 0)
		)
		(polygon
			(pts
				(arc
					(start 152.242012 -436.160672)
					(mid 152.26433 -436.214554)
					(end 152.318212 -436.236872)
				)
				(arc
					(start 153.258012 -436.236872)
					(mid 153.311894 -436.214554)
					(end 153.334212 -436.160672)
				)
				(arc
					(start 153.334212 -433.619148)
					(mid 153.311894 -433.565266)
					(end 153.258012 -433.542948)
				)
				(arc
					(start 152.318212 -433.542948)
					(mid 152.26433 -433.565266)
					(end 152.242012 -433.619148)
				)
			)
		)
	)
	(zone
		(layers "F.Cu" "In2.Cu" "In4.Cu" "In6.Cu" "In11.Cu" "In13.Cu" "In15.Cu")
		(hatch none 0.5)
		(connect_pads
			(clearance 0)
		)
		(min_thickness 0.25)
		(keepout
			(tracks not_allowed)
			(vias allowed)
			(pads allowed)
			(copperpour not_allowed)
			(footprints allowed)
		)
		(placement
			(enabled no)
			(sheetname "")
		)
		(fill yes
			(thermal_gap 0.5)
			(thermal_bridge_width 0.5)
			(island_removal_mode 0)
		)
		(polygon
			(pts
				(arc
					(start 150.242016 -431.560732)
					(mid 150.264334 -431.614614)
					(end 150.318216 -431.636932)
				)
				(arc
					(start 151.258016 -431.636932)
					(mid 151.311898 -431.614614)
					(end 151.334216 -431.560732)
				)
				(arc
					(start 151.334216 -429.019208)
					(mid 151.311898 -428.965326)
					(end 151.258016 -428.943008)
				)
				(arc
					(start 150.318216 -428.943008)
					(mid 150.264334 -428.965326)
					(end 150.242016 -429.019208)
				)
			)
		)
	)
	(zone
		(layers "F.Cu" "In2.Cu" "In4.Cu" "In6.Cu" "In11.Cu" "In13.Cu" "In15.Cu")
		(hatch none 0.5)
		(connect_pads
			(clearance 0)
		)
		(min_thickness 0.25)
		(keepout
			(tracks not_allowed)
			(vias allowed)
			(pads allowed)
			(copperpour not_allowed)
			(footprints allowed)
		)
		(placement
			(enabled no)
			(sheetname "")
		)
		(fill yes
			(thermal_gap 0.5)
			(thermal_bridge_width 0.5)
			(island_removal_mode 0)
		)
		(polygon
			(pts
				(arc
					(start 385.242054 -435.160674)
					(mid 385.264372 -435.214556)
					(end 385.318254 -435.236874)
				)
				(arc
					(start 386.258054 -435.236874)
					(mid 386.311936 -435.214556)
					(end 386.334254 -435.160674)
				)
				(arc
					(start 386.334254 -432.61915)
					(mid 386.311936 -432.565268)
					(end 386.258054 -432.54295)
				)
				(arc
					(start 385.318254 -432.54295)
					(mid 385.264372 -432.565268)
					(end 385.242054 -432.61915)
				)
			)
		)
	)
	(zone
		(layers "F.Cu" "In2.Cu" "In4.Cu" "In6.Cu" "In11.Cu" "In13.Cu" "In15.Cu")
		(hatch none 0.5)
		(connect_pads
			(clearance 0)
		)
		(min_thickness 0.25)
		(keepout
			(tracks not_allowed)
			(vias allowed)
			(pads allowed)
			(copperpour not_allowed)
			(footprints allowed)
		)
		(placement
			(enabled no)
			(sheetname "")
		)
		(fill yes
			(thermal_gap 0.5)
			(thermal_bridge_width 0.5)
			(island_removal_mode 0)
		)
		(polygon
			(pts
				(arc
					(start 410.242004 -431.560732)
					(mid 410.264322 -431.614614)
					(end 410.318204 -431.636932)
				)
				(arc
					(start 411.258004 -431.636932)
					(mid 411.311886 -431.614614)
					(end 411.334204 -431.560732)
				)
				(arc
					(start 411.334204 -429.019208)
					(mid 411.311886 -428.965326)
					(end 411.258004 -428.943008)
				)
				(arc
					(start 410.318204 -428.943008)
					(mid 410.264322 -428.965326)
					(end 410.242004 -429.019208)
				)
			)
		)
	)
	(zone
		(layers "F.Cu" "In2.Cu" "In4.Cu" "In6.Cu" "In11.Cu" "In13.Cu" "In15.Cu")
		(hatch none 0.5)
		(connect_pads
			(clearance 0)
		)
		(min_thickness 0.25)
		(keepout
			(tracks not_allowed)
			(vias allowed)
			(pads allowed)
			(copperpour not_allowed)
			(footprints allowed)
		)
		(placement
			(enabled no)
			(sheetname "")
		)
		(fill yes
			(thermal_gap 0.5)
			(thermal_bridge_width 0.5)
			(island_removal_mode 0)
		)
		(polygon
			(pts
				(arc
					(start 326.142096 -435.160674)
					(mid 326.164414 -435.214556)
					(end 326.218296 -435.236874)
				)
				(arc
					(start 327.158096 -435.236874)
					(mid 327.211978 -435.214556)
					(end 327.234296 -435.160674)
				)
				(arc
					(start 327.234296 -432.61915)
					(mid 327.211978 -432.565268)
					(end 327.158096 -432.54295)
				)
				(arc
					(start 326.218296 -432.54295)
					(mid 326.164414 -432.565268)
					(end 326.142096 -432.61915)
				)
			)
		)
	)
	(zone
		(layers "F.Cu" "In2.Cu" "In4.Cu" "In6.Cu" "In11.Cu" "In13.Cu" "In15.Cu")
		(hatch none 0.5)
		(connect_pads
			(clearance 0)
		)
		(min_thickness 0.25)
		(keepout
			(tracks not_allowed)
			(vias allowed)
			(pads allowed)
			(copperpour not_allowed)
			(footprints allowed)
		)
		(placement
			(enabled no)
			(sheetname "")
		)
		(fill yes
			(thermal_gap 0.5)
			(thermal_bridge_width 0.5)
			(island_removal_mode 0)
		)
		(polygon
			(pts
				(arc
					(start 343.142062 -431.560732)
					(mid 343.16438 -431.614614)
					(end 343.218262 -431.636932)
				)
				(arc
					(start 344.158062 -431.636932)
					(mid 344.211944 -431.614614)
					(end 344.234262 -431.560732)
				)
				(arc
					(start 344.234262 -429.019208)
					(mid 344.211944 -428.965326)
					(end 344.158062 -428.943008)
				)
				(arc
					(start 343.218262 -428.943008)
					(mid 343.16438 -428.965326)
					(end 343.142062 -429.019208)
				)
			)
		)
	)
	(zone
		(layers "F.Cu" "In2.Cu" "In4.Cu" "In6.Cu" "In11.Cu" "In13.Cu" "In15.Cu")
		(hatch none 0.5)
		(connect_pads
			(clearance 0)
		)
		(min_thickness 0.25)
		(keepout
			(tracks not_allowed)
			(vias allowed)
			(pads allowed)
			(copperpour not_allowed)
			(footprints allowed)
		)
		(placement
			(enabled no)
			(sheetname "")
		)
		(fill yes
			(thermal_gap 0.5)
			(thermal_bridge_width 0.5)
			(island_removal_mode 0)
		)
		(polygon
			(pts
				(arc
					(start 58.142124 -431.560732)
					(mid 58.164442 -431.614614)
					(end 58.218324 -431.636932)
				)
				(arc
					(start 59.158124 -431.636932)
					(mid 59.212006 -431.614614)
					(end 59.234324 -431.560732)
				)
				(arc
					(start 59.234324 -429.019208)
					(mid 59.212006 -428.965326)
					(end 59.158124 -428.943008)
				)
				(arc
					(start 58.218324 -428.943008)
					(mid 58.164442 -428.965326)
					(end 58.142124 -429.019208)
				)
			)
		)
	)
	(zone
		(layers "F.Cu" "In2.Cu" "In4.Cu" "In6.Cu" "In11.Cu" "In13.Cu" "In15.Cu")
		(hatch none 0.5)
		(connect_pads
			(clearance 0)
		)
		(min_thickness 0.25)
		(keepout
			(tracks not_allowed)
			(vias allowed)
			(pads allowed)
			(copperpour not_allowed)
			(footprints allowed)
		)
		(placement
			(enabled no)
			(sheetname "")
		)
		(fill yes
			(thermal_gap 0.5)
			(thermal_bridge_width 0.5)
			(island_removal_mode 0)
		)
		(polygon
			(pts
				(arc
					(start 326.142096 -431.560732)
					(mid 326.164414 -431.614614)
					(end 326.218296 -431.636932)
				)
				(arc
					(start 327.158096 -431.636932)
					(mid 327.211978 -431.614614)
					(end 327.234296 -431.560732)
				)
				(arc
					(start 327.234296 -429.019208)
					(mid 327.211978 -428.965326)
					(end 327.158096 -428.943008)
				)
				(arc
					(start 326.218296 -428.943008)
					(mid 326.164414 -428.965326)
					(end 326.142096 -429.019208)
				)
			)
		)
	)
	(zone
		(layers "F.Cu" "In2.Cu" "In4.Cu" "In6.Cu" "In11.Cu" "In13.Cu" "In15.Cu")
		(hatch none 0.5)
		(connect_pads
			(clearance 0)
		)
		(min_thickness 0.25)
		(keepout
			(tracks not_allowed)
			(vias allowed)
			(pads allowed)
			(copperpour not_allowed)
			(footprints allowed)
		)
		(placement
			(enabled no)
			(sheetname "")
		)
		(fill yes
			(thermal_gap 0.5)
			(thermal_bridge_width 0.5)
			(island_removal_mode 0)
		)
		(polygon
			(pts
				(arc
					(start 68.142104 -436.160672)
					(mid 68.164422 -436.214554)
					(end 68.218304 -436.236872)
				)
				(arc
					(start 69.158104 -436.236872)
					(mid 69.211986 -436.214554)
					(end 69.234304 -436.160672)
				)
				(arc
					(start 69.234304 -433.619148)
					(mid 69.211986 -433.565266)
					(end 69.158104 -433.542948)
				)
				(arc
					(start 68.218304 -433.542948)
					(mid 68.164422 -433.565266)
					(end 68.142104 -433.619148)
				)
			)
		)
	)
	(zone
		(layers "F.Cu" "In2.Cu" "In4.Cu" "In6.Cu" "In11.Cu" "In13.Cu" "In15.Cu")
		(hatch none 0.5)
		(connect_pads
			(clearance 0)
		)
		(min_thickness 0.25)
		(keepout
			(tracks not_allowed)
			(vias allowed)
			(pads allowed)
			(copperpour not_allowed)
			(footprints allowed)
		)
		(placement
			(enabled no)
			(sheetname "")
		)
		(fill yes
			(thermal_gap 0.5)
			(thermal_bridge_width 0.5)
			(island_removal_mode 0)
		)
		(polygon
			(pts
				(arc
					(start 395.242034 -432.56073)
					(mid 395.264352 -432.614612)
					(end 395.318234 -432.63693)
				)
				(arc
					(start 396.258034 -432.63693)
					(mid 396.311916 -432.614612)
					(end 396.334234 -432.56073)
				)
				(arc
					(start 396.334234 -430.019206)
					(mid 396.311916 -429.965324)
					(end 396.258034 -429.943006)
				)
				(arc
					(start 395.318234 -429.943006)
					(mid 395.264352 -429.965324)
					(end 395.242034 -430.019206)
				)
			)
		)
	)
	(zone
		(layers "F.Cu" "In2.Cu" "In4.Cu" "In6.Cu" "In11.Cu" "In13.Cu" "In15.Cu")
		(hatch none 0.5)
		(connect_pads
			(clearance 0)
		)
		(min_thickness 0.25)
		(keepout
			(tracks not_allowed)
			(vias allowed)
			(pads allowed)
			(copperpour not_allowed)
			(footprints allowed)
		)
		(placement
			(enabled no)
			(sheetname "")
		)
		(fill yes
			(thermal_gap 0.5)
			(thermal_bridge_width 0.5)
			(island_removal_mode 0)
		)
		(polygon
			(pts
				(arc
					(start 412.242 -436.160672)
					(mid 412.264318 -436.214554)
					(end 412.3182 -436.236872)
				)
				(arc
					(start 413.258 -436.236872)
					(mid 413.311882 -436.214554)
					(end 413.3342 -436.160672)
				)
				(arc
					(start 413.3342 -433.619148)
					(mid 413.311882 -433.565266)
					(end 413.258 -433.542948)
				)
				(arc
					(start 412.3182 -433.542948)
					(mid 412.264318 -433.565266)
					(end 412.242 -433.619148)
				)
			)
		)
	)
	(zone
		(layers "F.Cu" "In2.Cu" "In4.Cu" "In6.Cu" "In11.Cu" "In13.Cu" "In15.Cu")
		(hatch none 0.5)
		(connect_pads
			(clearance 0)
		)
		(min_thickness 0.25)
		(keepout
			(tracks not_allowed)
			(vias allowed)
			(pads allowed)
			(copperpour not_allowed)
			(footprints allowed)
		)
		(placement
			(enabled no)
			(sheetname "")
		)
		(fill yes
			(thermal_gap 0.5)
			(thermal_bridge_width 0.5)
			(island_removal_mode 0)
		)
		(polygon
			(pts
				(arc
					(start 87.142066 -431.560732)
					(mid 87.164384 -431.614614)
					(end 87.218266 -431.636932)
				)
				(arc
					(start 88.158066 -431.636932)
					(mid 88.211948 -431.614614)
					(end 88.234266 -431.560732)
				)
				(arc
					(start 88.234266 -429.019208)
					(mid 88.211948 -428.965326)
					(end 88.158066 -428.943008)
				)
				(arc
					(start 87.218266 -428.943008)
					(mid 87.164384 -428.965326)
					(end 87.142066 -429.019208)
				)
			)
		)
	)
	(zone
		(layers "F.Cu" "In2.Cu" "In4.Cu" "In6.Cu" "In11.Cu" "In13.Cu" "In15.Cu")
		(hatch none 0.5)
		(connect_pads
			(clearance 0)
		)
		(min_thickness 0.25)
		(keepout
			(tracks not_allowed)
			(vias allowed)
			(pads allowed)
			(copperpour not_allowed)
			(footprints allowed)
		)
		(placement
			(enabled no)
			(sheetname "")
		)
		(fill yes
			(thermal_gap 0.5)
			(thermal_bridge_width 0.5)
			(island_removal_mode 0)
		)
		(polygon
			(pts
				(arc
					(start 137.242042 -435.160674)
					(mid 137.26436 -435.214556)
					(end 137.318242 -435.236874)
				)
				(arc
					(start 138.258042 -435.236874)
					(mid 138.311924 -435.214556)
					(end 138.334242 -435.160674)
				)
				(arc
					(start 138.334242 -432.61915)
					(mid 138.311924 -432.565268)
					(end 138.258042 -432.54295)
				)
				(arc
					(start 137.318242 -432.54295)
					(mid 137.26436 -432.565268)
					(end 137.242042 -432.61915)
				)
			)
		)
	)
	(zone
		(layers "F.Cu" "In2.Cu" "In4.Cu" "In6.Cu" "In11.Cu" "In13.Cu" "In15.Cu")
		(hatch none 0.5)
		(connect_pads
			(clearance 0)
		)
		(min_thickness 0.25)
		(keepout
			(tracks not_allowed)
			(vias allowed)
			(pads allowed)
			(copperpour not_allowed)
			(footprints allowed)
		)
		(placement
			(enabled no)
			(sheetname "")
		)
		(fill yes
			(thermal_gap 0.5)
			(thermal_bridge_width 0.5)
			(island_removal_mode 0)
		)
		(polygon
			(pts
				(arc
					(start 75.14209 -431.560732)
					(mid 75.164408 -431.614614)
					(end 75.21829 -431.636932)
				)
				(arc
					(start 76.15809 -431.636932)
					(mid 76.211972 -431.614614)
					(end 76.23429 -431.560732)
				)
				(arc
					(start 76.23429 -429.019208)
					(mid 76.211972 -428.965326)
					(end 76.15809 -428.943008)
				)
				(arc
					(start 75.21829 -428.943008)
					(mid 75.164408 -428.965326)
					(end 75.14209 -429.019208)
				)
			)
		)
	)
	(zone
		(layers "F.Cu" "In2.Cu" "In4.Cu" "In6.Cu" "In11.Cu" "In13.Cu" "In15.Cu")
		(hatch none 0.5)
		(connect_pads
			(clearance 0)
		)
		(min_thickness 0.25)
		(keepout
			(tracks not_allowed)
			(vias allowed)
			(pads allowed)
			(copperpour not_allowed)
			(footprints allowed)
		)
		(placement
			(enabled no)
			(sheetname "")
		)
		(fill yes
			(thermal_gap 0.5)
			(thermal_bridge_width 0.5)
			(island_removal_mode 0)
		)
		(polygon
			(pts
				(arc
					(start 85.14207 -436.160672)
					(mid 85.164388 -436.214554)
					(end 85.21827 -436.236872)
				)
				(arc
					(start 86.15807 -436.236872)
					(mid 86.211952 -436.214554)
					(end 86.23427 -436.160672)
				)
				(arc
					(start 86.23427 -433.619148)
					(mid 86.211952 -433.565266)
					(end 86.15807 -433.542948)
				)
				(arc
					(start 85.21827 -433.542948)
					(mid 85.164388 -433.565266)
					(end 85.14207 -433.619148)
				)
			)
		)
	)
	(zone
		(layers "F.Cu" "In2.Cu" "In4.Cu" "In6.Cu" "In11.Cu" "In13.Cu" "In15.Cu")
		(hatch none 0.5)
		(connect_pads
			(clearance 0)
		)
		(min_thickness 0.25)
		(keepout
			(tracks not_allowed)
			(vias allowed)
			(pads allowed)
			(copperpour not_allowed)
			(footprints allowed)
		)
		(placement
			(enabled no)
			(sheetname "")
		)
		(fill yes
			(thermal_gap 0.5)
			(thermal_bridge_width 0.5)
			(island_removal_mode 0)
		)
		(polygon
			(pts
				(arc
					(start 324.1421 -432.56073)
					(mid 324.164418 -432.614612)
					(end 324.2183 -432.63693)
				)
				(arc
					(start 325.1581 -432.63693)
					(mid 325.211982 -432.614612)
					(end 325.2343 -432.56073)
				)
				(arc
					(start 325.2343 -430.019206)
					(mid 325.211982 -429.965324)
					(end 325.1581 -429.943006)
				)
				(arc
					(start 324.2183 -429.943006)
					(mid 324.164418 -429.965324)
					(end 324.1421 -430.019206)
				)
			)
		)
	)
	(zone
		(layers "F.Cu" "In2.Cu" "In4.Cu" "In6.Cu" "In11.Cu" "In13.Cu" "In15.Cu")
		(hatch none 0.5)
		(connect_pads
			(clearance 0)
		)
		(min_thickness 0.25)
		(keepout
			(tracks not_allowed)
			(vias allowed)
			(pads allowed)
			(copperpour not_allowed)
			(footprints allowed)
		)
		(placement
			(enabled no)
			(sheetname "")
		)
		(fill yes
			(thermal_gap 0.5)
			(thermal_bridge_width 0.5)
			(island_removal_mode 0)
		)
		(polygon
			(pts
				(arc
					(start 133.24205 -431.560732)
					(mid 133.264368 -431.614614)
					(end 133.31825 -431.636932)
				)
				(arc
					(start 134.25805 -431.636932)
					(mid 134.311932 -431.614614)
					(end 134.33425 -431.560732)
				)
				(arc
					(start 134.33425 -429.019208)
					(mid 134.311932 -428.965326)
					(end 134.25805 -428.943008)
				)
				(arc
					(start 133.31825 -428.943008)
					(mid 133.264368 -428.965326)
					(end 133.24205 -429.019208)
				)
			)
		)
	)
	(zone
		(layers "F.Cu" "In2.Cu" "In4.Cu" "In6.Cu" "In11.Cu" "In13.Cu" "In15.Cu")
		(hatch none 0.5)
		(connect_pads
			(clearance 0)
		)
		(min_thickness 0.25)
		(keepout
			(tracks not_allowed)
			(vias allowed)
			(pads allowed)
			(copperpour not_allowed)
			(footprints allowed)
		)
		(placement
			(enabled no)
			(sheetname "")
		)
		(fill yes
			(thermal_gap 0.5)
			(thermal_bridge_width 0.5)
			(island_removal_mode 0)
		)
		(polygon
			(pts
				(arc
					(start 314.14212 -435.160674)
					(mid 314.164438 -435.214556)
					(end 314.21832 -435.236874)
				)
				(arc
					(start 315.15812 -435.236874)
					(mid 315.212002 -435.214556)
					(end 315.23432 -435.160674)
				)
				(arc
					(start 315.23432 -432.61915)
					(mid 315.212002 -432.565268)
					(end 315.15812 -432.54295)
				)
				(arc
					(start 314.21832 -432.54295)
					(mid 314.164438 -432.565268)
					(end 314.14212 -432.61915)
				)
			)
		)
	)
	(zone
		(layers "F.Cu" "In2.Cu" "In4.Cu" "In6.Cu" "In11.Cu" "In13.Cu" "In15.Cu")
		(hatch none 0.5)
		(connect_pads
			(clearance 0)
		)
		(min_thickness 0.25)
		(keepout
			(tracks not_allowed)
			(vias allowed)
			(pads allowed)
			(copperpour not_allowed)
			(footprints allowed)
		)
		(placement
			(enabled no)
			(sheetname "")
		)
		(fill yes
			(thermal_gap 0.5)
			(thermal_bridge_width 0.5)
			(island_removal_mode 0)
		)
		(polygon
			(pts
				(arc
					(start 83.142074 -431.560732)
					(mid 83.164392 -431.614614)
					(end 83.218274 -431.636932)
				)
				(arc
					(start 84.158074 -431.636932)
					(mid 84.211956 -431.614614)
					(end 84.234274 -431.560732)
				)
				(arc
					(start 84.234274 -429.019208)
					(mid 84.211956 -428.965326)
					(end 84.158074 -428.943008)
				)
				(arc
					(start 83.218274 -428.943008)
					(mid 83.164392 -428.965326)
					(end 83.142074 -429.019208)
				)
			)
		)
	)
	(zone
		(layers "F.Cu" "In2.Cu" "In4.Cu" "In6.Cu" "In11.Cu" "In13.Cu" "In15.Cu")
		(hatch none 0.5)
		(connect_pads
			(clearance 0)
		)
		(min_thickness 0.25)
		(keepout
			(tracks not_allowed)
			(vias allowed)
			(pads allowed)
			(copperpour not_allowed)
			(footprints allowed)
		)
		(placement
			(enabled no)
			(sheetname "")
		)
		(fill yes
			(thermal_gap 0.5)
			(thermal_bridge_width 0.5)
			(island_removal_mode 0)
		)
		(polygon
			(pts
				(arc
					(start 66.142108 -435.160674)
					(mid 66.164426 -435.214556)
					(end 66.218308 -435.236874)
				)
				(arc
					(start 67.158108 -435.236874)
					(mid 67.21199 -435.214556)
					(end 67.234308 -435.160674)
				)
				(arc
					(start 67.234308 -432.61915)
					(mid 67.21199 -432.565268)
					(end 67.158108 -432.54295)
				)
				(arc
					(start 66.218308 -432.54295)
					(mid 66.164426 -432.565268)
					(end 66.142108 -432.61915)
				)
			)
		)
	)
	(zone
		(layers "F.Cu" "In2.Cu" "In4.Cu" "In6.Cu" "In11.Cu" "In13.Cu" "In15.Cu")
		(hatch none 0.5)
		(connect_pads
			(clearance 0)
		)
		(min_thickness 0.25)
		(keepout
			(tracks not_allowed)
			(vias allowed)
			(pads allowed)
			(copperpour not_allowed)
			(footprints allowed)
		)
		(placement
			(enabled no)
			(sheetname "")
		)
		(fill yes
			(thermal_gap 0.5)
			(thermal_bridge_width 0.5)
			(island_removal_mode 0)
		)
		(polygon
			(pts
				(arc
					(start 345.142058 -436.160672)
					(mid 345.164376 -436.214554)
					(end 345.218258 -436.236872)
				)
				(arc
					(start 346.158058 -436.236872)
					(mid 346.21194 -436.214554)
					(end 346.234258 -436.160672)
				)
				(arc
					(start 346.234258 -433.619148)
					(mid 346.21194 -433.565266)
					(end 346.158058 -433.542948)
				)
				(arc
					(start 345.218258 -433.542948)
					(mid 345.164376 -433.565266)
					(end 345.142058 -433.619148)
				)
			)
		)
	)
	(zone
		(layers "F.Cu" "In2.Cu" "In4.Cu" "In6.Cu" "In11.Cu" "In13.Cu" "In15.Cu")
		(hatch none 0.5)
		(connect_pads
			(clearance 0)
		)
		(min_thickness 0.25)
		(keepout
			(tracks not_allowed)
			(vias allowed)
			(pads allowed)
			(copperpour not_allowed)
			(footprints allowed)
		)
		(placement
			(enabled no)
			(sheetname "")
		)
		(fill yes
			(thermal_gap 0.5)
			(thermal_bridge_width 0.5)
			(island_removal_mode 0)
		)
		(polygon
			(pts
				(arc
					(start 66.142108 -431.560732)
					(mid 66.164426 -431.614614)
					(end 66.218308 -431.636932)
				)
				(arc
					(start 67.158108 -431.636932)
					(mid 67.21199 -431.614614)
					(end 67.234308 -431.560732)
				)
				(arc
					(start 67.234308 -429.019208)
					(mid 67.21199 -428.965326)
					(end 67.158108 -428.943008)
				)
				(arc
					(start 66.218308 -428.943008)
					(mid 66.164426 -428.965326)
					(end 66.142108 -429.019208)
				)
			)
		)
	)
	(zone
		(layers "F.Cu" "In2.Cu" "In4.Cu" "In6.Cu" "In11.Cu" "In13.Cu" "In15.Cu")
		(hatch none 0.5)
		(connect_pads
			(clearance 0)
		)
		(min_thickness 0.25)
		(keepout
			(tracks not_allowed)
			(vias allowed)
			(pads allowed)
			(copperpour not_allowed)
			(footprints allowed)
		)
		(placement
			(enabled no)
			(sheetname "")
		)
		(fill yes
			(thermal_gap 0.5)
			(thermal_bridge_width 0.5)
			(island_removal_mode 0)
		)
		(polygon
			(pts
				(arc
					(start 125.242066 -431.560732)
					(mid 125.264384 -431.614614)
					(end 125.318266 -431.636932)
				)
				(arc
					(start 126.258066 -431.636932)
					(mid 126.311948 -431.614614)
					(end 126.334266 -431.560732)
				)
				(arc
					(start 126.334266 -429.019208)
					(mid 126.311948 -428.965326)
					(end 126.258066 -428.943008)
				)
				(arc
					(start 125.318266 -428.943008)
					(mid 125.264384 -428.965326)
					(end 125.242066 -429.019208)
				)
			)
		)
	)
	(zone
		(layers "F.Cu" "In2.Cu" "In4.Cu" "In6.Cu" "In11.Cu" "In13.Cu" "In15.Cu")
		(hatch none 0.5)
		(connect_pads
			(clearance 0)
		)
		(min_thickness 0.25)
		(keepout
			(tracks not_allowed)
			(vias allowed)
			(pads allowed)
			(copperpour not_allowed)
			(footprints allowed)
		)
		(placement
			(enabled no)
			(sheetname "")
		)
		(fill yes
			(thermal_gap 0.5)
			(thermal_bridge_width 0.5)
			(island_removal_mode 0)
		)
		(polygon
			(pts
				(arc
					(start 408.242008 -436.160672)
					(mid 408.264326 -436.214554)
					(end 408.318208 -436.236872)
				)
				(arc
					(start 409.258008 -436.236872)
					(mid 409.31189 -436.214554)
					(end 409.334208 -436.160672)
				)
				(arc
					(start 409.334208 -433.619148)
					(mid 409.31189 -433.565266)
					(end 409.258008 -433.542948)
				)
				(arc
					(start 408.318208 -433.542948)
					(mid 408.264326 -433.565266)
					(end 408.242008 -433.619148)
				)
			)
		)
	)
	(zone
		(layers "F.Cu" "In2.Cu" "In4.Cu" "In6.Cu" "In11.Cu" "In13.Cu" "In15.Cu")
		(hatch none 0.5)
		(connect_pads
			(clearance 0)
		)
		(min_thickness 0.25)
		(keepout
			(tracks not_allowed)
			(vias allowed)
			(pads allowed)
			(copperpour not_allowed)
			(footprints allowed)
		)
		(placement
			(enabled no)
			(sheetname "")
		)
		(fill yes
			(thermal_gap 0.5)
			(thermal_bridge_width 0.5)
			(island_removal_mode 0)
		)
		(polygon
			(pts
				(arc
					(start 389.242046 -435.160674)
					(mid 389.264364 -435.214556)
					(end 389.318246 -435.236874)
				)
				(arc
					(start 390.258046 -435.236874)
					(mid 390.311928 -435.214556)
					(end 390.334246 -435.160674)
				)
				(arc
					(start 390.334246 -432.61915)
					(mid 390.311928 -432.565268)
					(end 390.258046 -432.54295)
				)
				(arc
					(start 389.318246 -432.54295)
					(mid 389.264364 -432.565268)
					(end 389.242046 -432.61915)
				)
			)
		)
	)
	(zone
		(layers "F.Cu" "In2.Cu" "In4.Cu" "In6.Cu" "In11.Cu" "In13.Cu" "In15.Cu")
		(hatch none 0.5)
		(connect_pads
			(clearance 0)
		)
		(min_thickness 0.25)
		(keepout
			(tracks not_allowed)
			(vias allowed)
			(pads allowed)
			(copperpour not_allowed)
			(footprints allowed)
		)
		(placement
			(enabled no)
			(sheetname "")
		)
		(fill yes
			(thermal_gap 0.5)
			(thermal_bridge_width 0.5)
			(island_removal_mode 0)
		)
		(polygon
			(pts
				(arc
					(start 333.142082 -432.56073)
					(mid 333.1644 -432.614612)
					(end 333.218282 -432.63693)
				)
				(arc
					(start 334.158082 -432.63693)
					(mid 334.211964 -432.614612)
					(end 334.234282 -432.56073)
				)
				(arc
					(start 334.234282 -430.019206)
					(mid 334.211964 -429.965324)
					(end 334.158082 -429.943006)
				)
				(arc
					(start 333.218282 -429.943006)
					(mid 333.1644 -429.965324)
					(end 333.142082 -430.019206)
				)
			)
		)
	)
	(zone
		(layers "F.Cu" "In2.Cu" "In4.Cu" "In6.Cu" "In11.Cu" "In13.Cu" "In15.Cu")
		(hatch none 0.5)
		(connect_pads
			(clearance 0)
		)
		(min_thickness 0.25)
		(keepout
			(tracks not_allowed)
			(vias allowed)
			(pads allowed)
			(copperpour not_allowed)
			(footprints allowed)
		)
		(placement
			(enabled no)
			(sheetname "")
		)
		(fill yes
			(thermal_gap 0.5)
			(thermal_bridge_width 0.5)
			(island_removal_mode 0)
		)
		(polygon
			(pts
				(arc
					(start 337.142074 -432.56073)
					(mid 337.164392 -432.614612)
					(end 337.218274 -432.63693)
				)
				(arc
					(start 338.158074 -432.63693)
					(mid 338.211956 -432.614612)
					(end 338.234274 -432.56073)
				)
				(arc
					(start 338.234274 -430.019206)
					(mid 338.211956 -429.965324)
					(end 338.158074 -429.943006)
				)
				(arc
					(start 337.218274 -429.943006)
					(mid 337.164392 -429.965324)
					(end 337.142074 -430.019206)
				)
			)
		)
	)
	(zone
		(layers "F.Cu" "In2.Cu" "In4.Cu" "In6.Cu" "In11.Cu" "In13.Cu" "In15.Cu")
		(hatch none 0.5)
		(connect_pads
			(clearance 0)
		)
		(min_thickness 0.25)
		(keepout
			(tracks not_allowed)
			(vias allowed)
			(pads allowed)
			(copperpour not_allowed)
			(footprints allowed)
		)
		(placement
			(enabled no)
			(sheetname "")
		)
		(fill yes
			(thermal_gap 0.5)
			(thermal_bridge_width 0.5)
			(island_removal_mode 0)
		)
		(polygon
			(pts
				(arc
					(start 137.242042 -431.560732)
					(mid 137.26436 -431.614614)
					(end 137.318242 -431.636932)
				)
				(arc
					(start 138.258042 -431.636932)
					(mid 138.311924 -431.614614)
					(end 138.334242 -431.560732)
				)
				(arc
					(start 138.334242 -429.019208)
					(mid 138.311924 -428.965326)
					(end 138.258042 -428.943008)
				)
				(arc
					(start 137.318242 -428.943008)
					(mid 137.26436 -428.965326)
					(end 137.242042 -429.019208)
				)
			)
		)
	)
	(zone
		(layers "F.Cu" "In2.Cu" "In4.Cu" "In6.Cu" "In11.Cu" "In13.Cu" "In15.Cu")
		(hatch none 0.5)
		(connect_pads
			(clearance 0)
		)
		(min_thickness 0.25)
		(keepout
			(tracks not_allowed)
			(vias allowed)
			(pads allowed)
			(copperpour not_allowed)
			(footprints allowed)
		)
		(placement
			(enabled no)
			(sheetname "")
		)
		(fill yes
			(thermal_gap 0.5)
			(thermal_bridge_width 0.5)
			(island_removal_mode 0)
		)
		(polygon
			(pts
				(arc
					(start 77.142086 -436.160672)
					(mid 77.164404 -436.214554)
					(end 77.218286 -436.236872)
				)
				(arc
					(start 78.158086 -436.236872)
					(mid 78.211968 -436.214554)
					(end 78.234286 -436.160672)
				)
				(arc
					(start 78.234286 -433.619148)
					(mid 78.211968 -433.565266)
					(end 78.158086 -433.542948)
				)
				(arc
					(start 77.218286 -433.542948)
					(mid 77.164404 -433.565266)
					(end 77.142086 -433.619148)
				)
			)
		)
	)
	(zone
		(layers "F.Cu" "In2.Cu" "In4.Cu" "In6.Cu" "In11.Cu" "In13.Cu" "In15.Cu")
		(hatch none 0.5)
		(connect_pads
			(clearance 0)
		)
		(min_thickness 0.25)
		(keepout
			(tracks not_allowed)
			(vias allowed)
			(pads allowed)
			(copperpour not_allowed)
			(footprints allowed)
		)
		(placement
			(enabled no)
			(sheetname "")
		)
		(fill yes
			(thermal_gap 0.5)
			(thermal_bridge_width 0.5)
			(island_removal_mode 0)
		)
		(polygon
			(pts
				(arc
					(start 60.14212 -432.56073)
					(mid 60.164438 -432.614612)
					(end 60.21832 -432.63693)
				)
				(arc
					(start 61.15812 -432.63693)
					(mid 61.212002 -432.614612)
					(end 61.23432 -432.56073)
				)
				(arc
					(start 61.23432 -430.019206)
					(mid 61.212002 -429.965324)
					(end 61.15812 -429.943006)
				)
				(arc
					(start 60.21832 -429.943006)
					(mid 60.164438 -429.965324)
					(end 60.14212 -430.019206)
				)
			)
		)
	)
	(zone
		(layers "F.Cu" "In2.Cu" "In4.Cu" "In6.Cu" "In11.Cu" "In13.Cu" "In15.Cu")
		(hatch none 0.5)
		(connect_pads
			(clearance 0)
		)
		(min_thickness 0.25)
		(keepout
			(tracks not_allowed)
			(vias allowed)
			(pads allowed)
			(copperpour not_allowed)
			(footprints allowed)
		)
		(placement
			(enabled no)
			(sheetname "")
		)
		(fill yes
			(thermal_gap 0.5)
			(thermal_bridge_width 0.5)
			(island_removal_mode 0)
		)
		(polygon
			(pts
				(arc
					(start 146.242024 -431.560732)
					(mid 146.264342 -431.614614)
					(end 146.318224 -431.636932)
				)
				(arc
					(start 147.258024 -431.636932)
					(mid 147.311906 -431.614614)
					(end 147.334224 -431.560732)
				)
				(arc
					(start 147.334224 -429.019208)
					(mid 147.311906 -428.965326)
					(end 147.258024 -428.943008)
				)
				(arc
					(start 146.318224 -428.943008)
					(mid 146.264342 -428.965326)
					(end 146.242024 -429.019208)
				)
			)
		)
	)
	(zone
		(layers "F.Cu" "In2.Cu" "In4.Cu" "In6.Cu" "In11.Cu" "In13.Cu" "In15.Cu")
		(hatch none 0.5)
		(connect_pads
			(clearance 0)
		)
		(min_thickness 0.25)
		(keepout
			(tracks not_allowed)
			(vias allowed)
			(pads allowed)
			(copperpour not_allowed)
			(footprints allowed)
		)
		(placement
			(enabled no)
			(sheetname "")
		)
		(fill yes
			(thermal_gap 0.5)
			(thermal_bridge_width 0.5)
			(island_removal_mode 0)
		)
		(polygon
			(pts
				(arc
					(start 381.242062 -435.160674)
					(mid 381.26438 -435.214556)
					(end 381.318262 -435.236874)
				)
				(arc
					(start 382.258062 -435.236874)
					(mid 382.311944 -435.214556)
					(end 382.334262 -435.160674)
				)
				(arc
					(start 382.334262 -432.61915)
					(mid 382.311944 -432.565268)
					(end 382.258062 -432.54295)
				)
				(arc
					(start 381.318262 -432.54295)
					(mid 381.26438 -432.565268)
					(end 381.242062 -432.61915)
				)
			)
		)
	)
	(zone
		(layers "F.Cu" "In2.Cu" "In4.Cu" "In6.Cu" "In11.Cu" "In13.Cu" "In15.Cu")
		(hatch none 0.5)
		(connect_pads
			(clearance 0)
		)
		(min_thickness 0.25)
		(keepout
			(tracks not_allowed)
			(vias allowed)
			(pads allowed)
			(copperpour not_allowed)
			(footprints allowed)
		)
		(placement
			(enabled no)
			(sheetname "")
		)
		(fill yes
			(thermal_gap 0.5)
			(thermal_bridge_width 0.5)
			(island_removal_mode 0)
		)
		(polygon
			(pts
				(arc
					(start 393.242038 -431.560732)
					(mid 393.264356 -431.614614)
					(end 393.318238 -431.636932)
				)
				(arc
					(start 394.258038 -431.636932)
					(mid 394.31192 -431.614614)
					(end 394.334238 -431.560732)
				)
				(arc
					(start 394.334238 -429.019208)
					(mid 394.31192 -428.965326)
					(end 394.258038 -428.943008)
				)
				(arc
					(start 393.318238 -428.943008)
					(mid 393.264356 -428.965326)
					(end 393.242038 -429.019208)
				)
			)
		)
	)
	(zone
		(layers "F.Cu" "In2.Cu" "In4.Cu" "In6.Cu" "In11.Cu" "In13.Cu" "In15.Cu")
		(hatch none 0.5)
		(connect_pads
			(clearance 0)
		)
		(min_thickness 0.25)
		(keepout
			(tracks not_allowed)
			(vias allowed)
			(pads allowed)
			(copperpour not_allowed)
			(footprints allowed)
		)
		(placement
			(enabled no)
			(sheetname "")
		)
		(fill yes
			(thermal_gap 0.5)
			(thermal_bridge_width 0.5)
			(island_removal_mode 0)
		)
		(polygon
			(pts
				(arc
					(start 385.242054 -431.560732)
					(mid 385.264372 -431.614614)
					(end 385.318254 -431.636932)
				)
				(arc
					(start 386.258054 -431.636932)
					(mid 386.311936 -431.614614)
					(end 386.334254 -431.560732)
				)
				(arc
					(start 386.334254 -429.019208)
					(mid 386.311936 -428.965326)
					(end 386.258054 -428.943008)
				)
				(arc
					(start 385.318254 -428.943008)
					(mid 385.264372 -428.965326)
					(end 385.242054 -429.019208)
				)
			)
		)
	)
	(zone
		(layers "F.Cu" "In2.Cu" "In4.Cu" "In6.Cu" "In11.Cu" "In13.Cu" "In15.Cu")
		(hatch none 0.5)
		(connect_pads
			(clearance 0)
		)
		(min_thickness 0.25)
		(keepout
			(tracks not_allowed)
			(vias allowed)
			(pads allowed)
			(copperpour not_allowed)
			(footprints allowed)
		)
		(placement
			(enabled no)
			(sheetname "")
		)
		(fill yes
			(thermal_gap 0.5)
			(thermal_bridge_width 0.5)
			(island_removal_mode 0)
		)
		(polygon
			(pts
				(arc
					(start 410.242004 -435.160674)
					(mid 410.264322 -435.214556)
					(end 410.318204 -435.236874)
				)
				(arc
					(start 411.258004 -435.236874)
					(mid 411.311886 -435.214556)
					(end 411.334204 -435.160674)
				)
				(arc
					(start 411.334204 -432.61915)
					(mid 411.311886 -432.565268)
					(end 411.258004 -432.54295)
				)
				(arc
					(start 410.318204 -432.54295)
					(mid 410.264322 -432.565268)
					(end 410.242004 -432.61915)
				)
			)
		)
	)
	(zone
		(layers "F.Cu" "In2.Cu" "In4.Cu" "In6.Cu" "In11.Cu" "In13.Cu" "In15.Cu")
		(hatch none 0.5)
		(connect_pads
			(clearance 0)
		)
		(min_thickness 0.25)
		(keepout
			(tracks not_allowed)
			(vias allowed)
			(pads allowed)
			(copperpour not_allowed)
			(footprints allowed)
		)
		(placement
			(enabled no)
			(sheetname "")
		)
		(fill yes
			(thermal_gap 0.5)
			(thermal_bridge_width 0.5)
			(island_removal_mode 0)
		)
		(polygon
			(pts
				(arc
					(start 322.142104 -435.160674)
					(mid 322.164422 -435.214556)
					(end 322.218304 -435.236874)
				)
				(arc
					(start 323.158104 -435.236874)
					(mid 323.211986 -435.214556)
					(end 323.234304 -435.160674)
				)
				(arc
					(start 323.234304 -432.61915)
					(mid 323.211986 -432.565268)
					(end 323.158104 -432.54295)
				)
				(arc
					(start 322.218304 -432.54295)
					(mid 322.164422 -432.565268)
					(end 322.142104 -432.61915)
				)
			)
		)
	)
	(zone
		(layers "F.Cu" "In2.Cu" "In4.Cu" "In6.Cu" "In11.Cu" "In13.Cu" "In15.Cu")
		(hatch none 0.5)
		(connect_pads
			(clearance 0)
		)
		(min_thickness 0.25)
		(keepout
			(tracks not_allowed)
			(vias allowed)
			(pads allowed)
			(copperpour not_allowed)
			(footprints allowed)
		)
		(placement
			(enabled no)
			(sheetname "")
		)
		(fill yes
			(thermal_gap 0.5)
			(thermal_bridge_width 0.5)
			(island_removal_mode 0)
		)
		(polygon
			(pts
				(arc
					(start 383.242058 -436.160672)
					(mid 383.264376 -436.214554)
					(end 383.318258 -436.236872)
				)
				(arc
					(start 384.258058 -436.236872)
					(mid 384.31194 -436.214554)
					(end 384.334258 -436.160672)
				)
				(arc
					(start 384.334258 -433.619148)
					(mid 384.31194 -433.565266)
					(end 384.258058 -433.542948)
				)
				(arc
					(start 383.318258 -433.542948)
					(mid 383.264376 -433.565266)
					(end 383.242058 -433.619148)
				)
			)
		)
	)
	(zone
		(layers "F.Cu" "In2.Cu" "In4.Cu" "In6.Cu" "In11.Cu" "In13.Cu" "In15.Cu")
		(hatch none 0.5)
		(connect_pads
			(clearance 0)
		)
		(min_thickness 0.25)
		(keepout
			(tracks not_allowed)
			(vias allowed)
			(pads allowed)
			(copperpour not_allowed)
			(footprints allowed)
		)
		(placement
			(enabled no)
			(sheetname "")
		)
		(fill yes
			(thermal_gap 0.5)
			(thermal_bridge_width 0.5)
			(island_removal_mode 0)
		)
		(polygon
			(pts
				(arc
					(start 68.142104 -432.56073)
					(mid 68.164422 -432.614612)
					(end 68.218304 -432.63693)
				)
				(arc
					(start 69.158104 -432.63693)
					(mid 69.211986 -432.614612)
					(end 69.234304 -432.56073)
				)
				(arc
					(start 69.234304 -430.019206)
					(mid 69.211986 -429.965324)
					(end 69.158104 -429.943006)
				)
				(arc
					(start 68.218304 -429.943006)
					(mid 68.164422 -429.965324)
					(end 68.142104 -430.019206)
				)
			)
		)
	)
	(zone
		(layers "F.Cu" "In2.Cu" "In4.Cu" "In6.Cu" "In11.Cu" "In13.Cu" "In15.Cu")
		(hatch none 0.5)
		(connect_pads
			(clearance 0)
		)
		(min_thickness 0.25)
		(keepout
			(tracks not_allowed)
			(vias allowed)
			(pads allowed)
			(copperpour not_allowed)
			(footprints allowed)
		)
		(placement
			(enabled no)
			(sheetname "")
		)
		(fill yes
			(thermal_gap 0.5)
			(thermal_bridge_width 0.5)
			(island_removal_mode 0)
		)
		(polygon
			(pts
				(arc
					(start 70.1421 -431.560732)
					(mid 70.164418 -431.614614)
					(end 70.2183 -431.636932)
				)
				(arc
					(start 71.1581 -431.636932)
					(mid 71.211982 -431.614614)
					(end 71.2343 -431.560732)
				)
				(arc
					(start 71.2343 -429.019208)
					(mid 71.211982 -428.965326)
					(end 71.1581 -428.943008)
				)
				(arc
					(start 70.2183 -428.943008)
					(mid 70.164418 -428.965326)
					(end 70.1421 -429.019208)
				)
			)
		)
	)
	(zone
		(layers "F.Cu" "In2.Cu" "In4.Cu" "In6.Cu" "In11.Cu" "In13.Cu" "In15.Cu")
		(hatch none 0.5)
		(connect_pads
			(clearance 0)
		)
		(min_thickness 0.25)
		(keepout
			(tracks not_allowed)
			(vias allowed)
			(pads allowed)
			(copperpour not_allowed)
			(footprints allowed)
		)
		(placement
			(enabled no)
			(sheetname "")
		)
		(fill yes
			(thermal_gap 0.5)
			(thermal_bridge_width 0.5)
			(island_removal_mode 0)
		)
		(polygon
			(pts
				(arc
					(start 70.1421 -435.160674)
					(mid 70.164418 -435.214556)
					(end 70.2183 -435.236874)
				)
				(arc
					(start 71.1581 -435.236874)
					(mid 71.211982 -435.214556)
					(end 71.2343 -435.160674)
				)
				(arc
					(start 71.2343 -432.61915)
					(mid 71.211982 -432.565268)
					(end 71.1581 -432.54295)
				)
				(arc
					(start 70.2183 -432.54295)
					(mid 70.164418 -432.565268)
					(end 70.1421 -432.61915)
				)
			)
		)
	)
	(zone
		(layers "F.Cu" "In2.Cu" "In4.Cu" "In6.Cu" "In11.Cu" "In13.Cu" "In15.Cu")
		(hatch none 0.5)
		(connect_pads
			(clearance 0)
		)
		(min_thickness 0.25)
		(keepout
			(tracks not_allowed)
			(vias allowed)
			(pads allowed)
			(copperpour not_allowed)
			(footprints allowed)
		)
		(placement
			(enabled no)
			(sheetname "")
		)
		(fill yes
			(thermal_gap 0.5)
			(thermal_bridge_width 0.5)
			(island_removal_mode 0)
		)
		(polygon
			(pts
				(arc
					(start 64.142112 -436.160672)
					(mid 64.16443 -436.214554)
					(end 64.218312 -436.236872)
				)
				(arc
					(start 65.158112 -436.236872)
					(mid 65.211994 -436.214554)
					(end 65.234312 -436.160672)
				)
				(arc
					(start 65.234312 -433.619148)
					(mid 65.211994 -433.565266)
					(end 65.158112 -433.542948)
				)
				(arc
					(start 64.218312 -433.542948)
					(mid 64.16443 -433.565266)
					(end 64.142112 -433.619148)
				)
			)
		)
	)
	(zone
		(layers "F.Cu" "In2.Cu" "In4.Cu" "In6.Cu" "In11.Cu" "In13.Cu" "In15.Cu")
		(hatch none 0.5)
		(connect_pads
			(clearance 0)
		)
		(min_thickness 0.25)
		(keepout
			(tracks not_allowed)
			(vias allowed)
			(pads allowed)
			(copperpour not_allowed)
			(footprints allowed)
		)
		(placement
			(enabled no)
			(sheetname "")
		)
		(fill yes
			(thermal_gap 0.5)
			(thermal_bridge_width 0.5)
			(island_removal_mode 0)
		)
		(polygon
			(pts
				(arc
					(start 72.142096 -432.56073)
					(mid 72.164414 -432.614612)
					(end 72.218296 -432.63693)
				)
				(arc
					(start 73.158096 -432.63693)
					(mid 73.211978 -432.614612)
					(end 73.234296 -432.56073)
				)
				(arc
					(start 73.234296 -430.019206)
					(mid 73.211978 -429.965324)
					(end 73.158096 -429.943006)
				)
				(arc
					(start 72.218296 -429.943006)
					(mid 72.164414 -429.965324)
					(end 72.142096 -430.019206)
				)
			)
		)
	)
	(zone
		(layers "F.Cu" "In2.Cu" "In4.Cu" "In6.Cu" "In11.Cu" "In13.Cu" "In15.Cu")
		(hatch none 0.5)
		(connect_pads
			(clearance 0)
		)
		(min_thickness 0.25)
		(keepout
			(tracks not_allowed)
			(vias allowed)
			(pads allowed)
			(copperpour not_allowed)
			(footprints allowed)
		)
		(placement
			(enabled no)
			(sheetname "")
		)
		(fill yes
			(thermal_gap 0.5)
			(thermal_bridge_width 0.5)
			(island_removal_mode 0)
		)
		(polygon
			(pts
				(arc
					(start 318.142112 -431.560732)
					(mid 318.16443 -431.614614)
					(end 318.218312 -431.636932)
				)
				(arc
					(start 319.158112 -431.636932)
					(mid 319.211994 -431.614614)
					(end 319.234312 -431.560732)
				)
				(arc
					(start 319.234312 -429.019208)
					(mid 319.211994 -428.965326)
					(end 319.158112 -428.943008)
				)
				(arc
					(start 318.218312 -428.943008)
					(mid 318.16443 -428.965326)
					(end 318.142112 -429.019208)
				)
			)
		)
	)
	(zone
		(layers "F.Cu" "In2.Cu" "In4.Cu" "In6.Cu" "In11.Cu" "In13.Cu" "In15.Cu")
		(hatch none 0.5)
		(connect_pads
			(clearance 0)
		)
		(min_thickness 0.25)
		(keepout
			(tracks not_allowed)
			(vias allowed)
			(pads allowed)
			(copperpour not_allowed)
			(footprints allowed)
		)
		(placement
			(enabled no)
			(sheetname "")
		)
		(fill yes
			(thermal_gap 0.5)
			(thermal_bridge_width 0.5)
			(island_removal_mode 0)
		)
		(polygon
			(pts
				(arc
					(start 331.142086 -435.160674)
					(mid 331.164404 -435.214556)
					(end 331.218286 -435.236874)
				)
				(arc
					(start 332.158086 -435.236874)
					(mid 332.211968 -435.214556)
					(end 332.234286 -435.160674)
				)
				(arc
					(start 332.234286 -432.61915)
					(mid 332.211968 -432.565268)
					(end 332.158086 -432.54295)
				)
				(arc
					(start 331.218286 -432.54295)
					(mid 331.164404 -432.565268)
					(end 331.142086 -432.61915)
				)
			)
		)
	)
	(zone
		(layers "F.Cu" "In2.Cu" "In4.Cu" "In6.Cu" "In11.Cu" "In13.Cu" "In15.Cu")
		(hatch none 0.5)
		(connect_pads
			(clearance 0)
		)
		(min_thickness 0.25)
		(keepout
			(tracks not_allowed)
			(vias allowed)
			(pads allowed)
			(copperpour not_allowed)
			(footprints allowed)
		)
		(placement
			(enabled no)
			(sheetname "")
		)
		(fill yes
			(thermal_gap 0.5)
			(thermal_bridge_width 0.5)
			(island_removal_mode 0)
		)
		(polygon
			(pts
				(arc
					(start 139.242038 -436.160672)
					(mid 139.264356 -436.214554)
					(end 139.318238 -436.236872)
				)
				(arc
					(start 140.258038 -436.236872)
					(mid 140.31192 -436.214554)
					(end 140.334238 -436.160672)
				)
				(arc
					(start 140.334238 -433.619148)
					(mid 140.31192 -433.565266)
					(end 140.258038 -433.542948)
				)
				(arc
					(start 139.318238 -433.542948)
					(mid 139.264356 -433.565266)
					(end 139.242038 -433.619148)
				)
			)
		)
	)
	(zone
		(layers "F.Cu" "In2.Cu" "In4.Cu" "In6.Cu" "In11.Cu" "In13.Cu" "In15.Cu")
		(hatch none 0.5)
		(connect_pads
			(clearance 0)
		)
		(min_thickness 0.25)
		(keepout
			(tracks not_allowed)
			(vias allowed)
			(pads allowed)
			(copperpour not_allowed)
			(footprints allowed)
		)
		(placement
			(enabled no)
			(sheetname "")
		)
		(fill yes
			(thermal_gap 0.5)
			(thermal_bridge_width 0.5)
			(island_removal_mode 0)
		)
		(polygon
			(pts
				(arc
					(start 316.142116 -432.56073)
					(mid 316.164434 -432.614612)
					(end 316.218316 -432.63693)
				)
				(arc
					(start 317.158116 -432.63693)
					(mid 317.211998 -432.614612)
					(end 317.234316 -432.56073)
				)
				(arc
					(start 317.234316 -430.019206)
					(mid 317.211998 -429.965324)
					(end 317.158116 -429.943006)
				)
				(arc
					(start 316.218316 -429.943006)
					(mid 316.164434 -429.965324)
					(end 316.142116 -430.019206)
				)
			)
		)
	)
	(zone
		(layers "F.Cu" "In2.Cu" "In4.Cu" "In6.Cu" "In11.Cu" "In13.Cu" "In15.Cu")
		(hatch none 0.5)
		(connect_pads
			(clearance 0)
		)
		(min_thickness 0.25)
		(keepout
			(tracks not_allowed)
			(vias allowed)
			(pads allowed)
			(copperpour not_allowed)
			(footprints allowed)
		)
		(placement
			(enabled no)
			(sheetname "")
		)
		(fill yes
			(thermal_gap 0.5)
			(thermal_bridge_width 0.5)
			(island_removal_mode 0)
		)
		(polygon
			(pts
				(arc
					(start 81.142078 -436.160672)
					(mid 81.164396 -436.214554)
					(end 81.218278 -436.236872)
				)
				(arc
					(start 82.158078 -436.236872)
					(mid 82.21196 -436.214554)
					(end 82.234278 -436.160672)
				)
				(arc
					(start 82.234278 -433.619148)
					(mid 82.21196 -433.565266)
					(end 82.158078 -433.542948)
				)
				(arc
					(start 81.218278 -433.542948)
					(mid 81.164396 -433.565266)
					(end 81.142078 -433.619148)
				)
			)
		)
	)
	(zone
		(layers "F.Cu" "In2.Cu" "In4.Cu" "In6.Cu" "In11.Cu" "In13.Cu" "In15.Cu")
		(hatch none 0.5)
		(connect_pads
			(clearance 0)
		)
		(min_thickness 0.25)
		(keepout
			(tracks not_allowed)
			(vias allowed)
			(pads allowed)
			(copperpour not_allowed)
			(footprints allowed)
		)
		(placement
			(enabled no)
			(sheetname "")
		)
		(fill yes
			(thermal_gap 0.5)
			(thermal_bridge_width 0.5)
			(island_removal_mode 0)
		)
		(polygon
			(pts
				(arc
					(start 398.242028 -431.560732)
					(mid 398.264346 -431.614614)
					(end 398.318228 -431.636932)
				)
				(arc
					(start 399.258028 -431.636932)
					(mid 399.31191 -431.614614)
					(end 399.334228 -431.560732)
				)
				(arc
					(start 399.334228 -429.019208)
					(mid 399.31191 -428.965326)
					(end 399.258028 -428.943008)
				)
				(arc
					(start 398.318228 -428.943008)
					(mid 398.264346 -428.965326)
					(end 398.242028 -429.019208)
				)
			)
		)
	)
	(zone
		(layers "F.Cu" "In2.Cu" "In4.Cu" "In6.Cu" "In11.Cu" "In13.Cu" "In15.Cu")
		(hatch none 0.5)
		(connect_pads
			(clearance 0)
		)
		(min_thickness 0.25)
		(keepout
			(tracks not_allowed)
			(vias allowed)
			(pads allowed)
			(copperpour not_allowed)
			(footprints allowed)
		)
		(placement
			(enabled no)
			(sheetname "")
		)
		(fill yes
			(thermal_gap 0.5)
			(thermal_bridge_width 0.5)
			(island_removal_mode 0)
		)
		(polygon
			(pts
				(arc
					(start 320.142108 -432.56073)
					(mid 320.164426 -432.614612)
					(end 320.218308 -432.63693)
				)
				(arc
					(start 321.158108 -432.63693)
					(mid 321.21199 -432.614612)
					(end 321.234308 -432.56073)
				)
				(arc
					(start 321.234308 -430.019206)
					(mid 321.21199 -429.965324)
					(end 321.158108 -429.943006)
				)
				(arc
					(start 320.218308 -429.943006)
					(mid 320.164426 -429.965324)
					(end 320.142108 -430.019206)
				)
			)
		)
	)
	(zone
		(layers "F.Cu" "In2.Cu" "In4.Cu" "In6.Cu" "In11.Cu" "In13.Cu" "In15.Cu")
		(hatch none 0.5)
		(connect_pads
			(clearance 0)
		)
		(min_thickness 0.25)
		(keepout
			(tracks not_allowed)
			(vias allowed)
			(pads allowed)
			(copperpour not_allowed)
			(footprints allowed)
		)
		(placement
			(enabled no)
			(sheetname "")
		)
		(fill yes
			(thermal_gap 0.5)
			(thermal_bridge_width 0.5)
			(island_removal_mode 0)
		)
		(polygon
			(pts
				(arc
					(start 333.142082 -436.160672)
					(mid 333.1644 -436.214554)
					(end 333.218282 -436.236872)
				)
				(arc
					(start 334.158082 -436.236872)
					(mid 334.211964 -436.214554)
					(end 334.234282 -436.160672)
				)
				(arc
					(start 334.234282 -433.619148)
					(mid 334.211964 -433.565266)
					(end 334.158082 -433.542948)
				)
				(arc
					(start 333.218282 -433.542948)
					(mid 333.1644 -433.565266)
					(end 333.142082 -433.619148)
				)
			)
		)
	)
	(zone
		(layers "F.Cu" "In2.Cu" "In4.Cu" "In6.Cu" "In11.Cu" "In13.Cu" "In15.Cu")
		(hatch none 0.5)
		(connect_pads
			(clearance 0)
		)
		(min_thickness 0.25)
		(keepout
			(tracks not_allowed)
			(vias allowed)
			(pads allowed)
			(copperpour not_allowed)
			(footprints allowed)
		)
		(placement
			(enabled no)
			(sheetname "")
		)
		(fill yes
			(thermal_gap 0.5)
			(thermal_bridge_width 0.5)
			(island_removal_mode 0)
		)
		(polygon
			(pts
				(arc
					(start 337.142074 -436.160672)
					(mid 337.164392 -436.214554)
					(end 337.218274 -436.236872)
				)
				(arc
					(start 338.158074 -436.236872)
					(mid 338.211956 -436.214554)
					(end 338.234274 -436.160672)
				)
				(arc
					(start 338.234274 -433.619148)
					(mid 338.211956 -433.565266)
					(end 338.158074 -433.542948)
				)
				(arc
					(start 337.218274 -433.542948)
					(mid 337.164392 -433.565266)
					(end 337.142074 -433.619148)
				)
			)
		)
	)
	(zone
		(layers "F.Cu" "In2.Cu" "In4.Cu" "In6.Cu" "In11.Cu" "In13.Cu" "In15.Cu")
		(hatch none 0.5)
		(connect_pads
			(clearance 0)
		)
		(min_thickness 0.25)
		(keepout
			(tracks not_allowed)
			(vias allowed)
			(pads allowed)
			(copperpour not_allowed)
			(footprints allowed)
		)
		(placement
			(enabled no)
			(sheetname "")
		)
		(fill yes
			(thermal_gap 0.5)
			(thermal_bridge_width 0.5)
			(island_removal_mode 0)
		)
		(polygon
			(pts
				(arc
					(start 339.14207 -435.160674)
					(mid 339.164388 -435.214556)
					(end 339.21827 -435.236874)
				)
				(arc
					(start 340.15807 -435.236874)
					(mid 340.211952 -435.214556)
					(end 340.23427 -435.160674)
				)
				(arc
					(start 340.23427 -432.61915)
					(mid 340.211952 -432.565268)
					(end 340.15807 -432.54295)
				)
				(arc
					(start 339.21827 -432.54295)
					(mid 339.164388 -432.565268)
					(end 339.14207 -432.61915)
				)
			)
		)
	)
	(zone
		(layers "F.Cu" "In2.Cu" "In4.Cu" "In6.Cu" "In11.Cu" "In13.Cu" "In15.Cu")
		(hatch none 0.5)
		(connect_pads
			(clearance 0)
		)
		(min_thickness 0.25)
		(keepout
			(tracks not_allowed)
			(vias allowed)
			(pads allowed)
			(copperpour not_allowed)
			(footprints allowed)
		)
		(placement
			(enabled no)
			(sheetname "")
		)
		(fill yes
			(thermal_gap 0.5)
			(thermal_bridge_width 0.5)
			(island_removal_mode 0)
		)
		(polygon
			(pts
				(arc
					(start 77.142086 -432.56073)
					(mid 77.164404 -432.614612)
					(end 77.218286 -432.63693)
				)
				(arc
					(start 78.158086 -432.63693)
					(mid 78.211968 -432.614612)
					(end 78.234286 -432.56073)
				)
				(arc
					(start 78.234286 -430.019206)
					(mid 78.211968 -429.965324)
					(end 78.158086 -429.943006)
				)
				(arc
					(start 77.218286 -429.943006)
					(mid 77.164404 -429.965324)
					(end 77.142086 -430.019206)
				)
			)
		)
	)
	(zone
		(layers "F.Cu" "In2.Cu" "In4.Cu" "In6.Cu" "In11.Cu" "In13.Cu" "In15.Cu")
		(hatch none 0.5)
		(connect_pads
			(clearance 0)
		)
		(min_thickness 0.25)
		(keepout
			(tracks not_allowed)
			(vias allowed)
			(pads allowed)
			(copperpour not_allowed)
			(footprints allowed)
		)
		(placement
			(enabled no)
			(sheetname "")
		)
		(fill yes
			(thermal_gap 0.5)
			(thermal_bridge_width 0.5)
			(island_removal_mode 0)
		)
		(polygon
			(pts
				(arc
					(start 89.142062 -436.160672)
					(mid 89.16438 -436.214554)
					(end 89.218262 -436.236872)
				)
				(arc
					(start 90.158062 -436.236872)
					(mid 90.211944 -436.214554)
					(end 90.234262 -436.160672)
				)
				(arc
					(start 90.234262 -433.619148)
					(mid 90.211944 -433.565266)
					(end 90.158062 -433.542948)
				)
				(arc
					(start 89.218262 -433.542948)
					(mid 89.16438 -433.565266)
					(end 89.142062 -433.619148)
				)
			)
		)
	)
	(zone
		(layers "F.Cu" "In2.Cu" "In4.Cu" "In6.Cu" "In11.Cu" "In13.Cu" "In15.Cu")
		(hatch none 0.5)
		(connect_pads
			(clearance 0)
		)
		(min_thickness 0.25)
		(keepout
			(tracks not_allowed)
			(vias allowed)
			(pads allowed)
			(copperpour not_allowed)
			(footprints allowed)
		)
		(placement
			(enabled no)
			(sheetname "")
		)
		(fill yes
			(thermal_gap 0.5)
			(thermal_bridge_width 0.5)
			(island_removal_mode 0)
		)
		(polygon
			(pts
				(arc
					(start 142.242032 -431.560732)
					(mid 142.26435 -431.614614)
					(end 142.318232 -431.636932)
				)
				(arc
					(start 143.258032 -431.636932)
					(mid 143.311914 -431.614614)
					(end 143.334232 -431.560732)
				)
				(arc
					(start 143.334232 -429.019208)
					(mid 143.311914 -428.965326)
					(end 143.258032 -428.943008)
				)
				(arc
					(start 142.318232 -428.943008)
					(mid 142.26435 -428.965326)
					(end 142.242032 -429.019208)
				)
			)
		)
	)
	(zone
		(layers "F.Cu" "In2.Cu" "In4.Cu" "In6.Cu" "In11.Cu" "In13.Cu" "In15.Cu")
		(hatch none 0.5)
		(connect_pads
			(clearance 0)
		)
		(min_thickness 0.25)
		(keepout
			(tracks not_allowed)
			(vias allowed)
			(pads allowed)
			(copperpour not_allowed)
			(footprints allowed)
		)
		(placement
			(enabled no)
			(sheetname "")
		)
		(fill yes
			(thermal_gap 0.5)
			(thermal_bridge_width 0.5)
			(island_removal_mode 0)
		)
		(polygon
			(pts
				(arc
					(start 129.242058 -435.160674)
					(mid 129.264376 -435.214556)
					(end 129.318258 -435.236874)
				)
				(arc
					(start 130.258058 -435.236874)
					(mid 130.31194 -435.214556)
					(end 130.334258 -435.160674)
				)
				(arc
					(start 130.334258 -432.61915)
					(mid 130.31194 -432.565268)
					(end 130.258058 -432.54295)
				)
				(arc
					(start 129.318258 -432.54295)
					(mid 129.264376 -432.565268)
					(end 129.242058 -432.61915)
				)
			)
		)
	)
	(zone
		(layers "F.Cu" "In2.Cu" "In4.Cu" "In6.Cu" "In11.Cu" "In13.Cu" "In15.Cu")
		(hatch none 0.5)
		(connect_pads
			(clearance 0)
		)
		(min_thickness 0.25)
		(keepout
			(tracks not_allowed)
			(vias allowed)
			(pads allowed)
			(copperpour not_allowed)
			(footprints allowed)
		)
		(placement
			(enabled no)
			(sheetname "")
		)
		(fill yes
			(thermal_gap 0.5)
			(thermal_bridge_width 0.5)
			(island_removal_mode 0)
		)
		(polygon
			(pts
				(arc
					(start 328.142092 -432.56073)
					(mid 328.16441 -432.614612)
					(end 328.218292 -432.63693)
				)
				(arc
					(start 329.158092 -432.63693)
					(mid 329.211974 -432.614612)
					(end 329.234292 -432.56073)
				)
				(arc
					(start 329.234292 -430.019206)
					(mid 329.211974 -429.965324)
					(end 329.158092 -429.943006)
				)
				(arc
					(start 328.218292 -429.943006)
					(mid 328.16441 -429.965324)
					(end 328.142092 -430.019206)
				)
			)
		)
	)
	(zone
		(layers "F.Cu" "In2.Cu" "In4.Cu" "In6.Cu" "In11.Cu" "In13.Cu" "In15.Cu")
		(hatch none 0.5)
		(connect_pads
			(clearance 0)
		)
		(min_thickness 0.25)
		(keepout
			(tracks not_allowed)
			(vias allowed)
			(pads allowed)
			(copperpour not_allowed)
			(footprints allowed)
		)
		(placement
			(enabled no)
			(sheetname "")
		)
		(fill yes
			(thermal_gap 0.5)
			(thermal_bridge_width 0.5)
			(island_removal_mode 0)
		)
		(polygon
			(pts
				(arc
					(start 135.242046 -436.160672)
					(mid 135.264364 -436.214554)
					(end 135.318246 -436.236872)
				)
				(arc
					(start 136.258046 -436.236872)
					(mid 136.311928 -436.214554)
					(end 136.334246 -436.160672)
				)
				(arc
					(start 136.334246 -433.619148)
					(mid 136.311928 -433.565266)
					(end 136.258046 -433.542948)
				)
				(arc
					(start 135.318246 -433.542948)
					(mid 135.264364 -433.565266)
					(end 135.242046 -433.619148)
				)
			)
		)
	)
	(zone
		(layers "F.Cu" "In2.Cu" "In4.Cu" "In6.Cu" "In11.Cu" "In13.Cu" "In15.Cu")
		(hatch none 0.5)
		(connect_pads
			(clearance 0)
		)
		(min_thickness 0.25)
		(keepout
			(tracks not_allowed)
			(vias allowed)
			(pads allowed)
			(copperpour not_allowed)
			(footprints allowed)
		)
		(placement
			(enabled no)
			(sheetname "")
		)
		(fill yes
			(thermal_gap 0.5)
			(thermal_bridge_width 0.5)
			(island_removal_mode 0)
		)
		(polygon
			(pts
				(arc
					(start 341.142066 -436.160672)
					(mid 341.164384 -436.214554)
					(end 341.218266 -436.236872)
				)
				(arc
					(start 342.158066 -436.236872)
					(mid 342.211948 -436.214554)
					(end 342.234266 -436.160672)
				)
				(arc
					(start 342.234266 -433.619148)
					(mid 342.211948 -433.565266)
					(end 342.158066 -433.542948)
				)
				(arc
					(start 341.218266 -433.542948)
					(mid 341.164384 -433.565266)
					(end 341.142066 -433.619148)
				)
			)
		)
	)
	(zone
		(layers "F.Cu" "In2.Cu" "In4.Cu" "In6.Cu" "In11.Cu" "In13.Cu" "In15.Cu")
		(hatch none 0.5)
		(connect_pads
			(clearance 0)
		)
		(min_thickness 0.25)
		(keepout
			(tracks not_allowed)
			(vias allowed)
			(pads allowed)
			(copperpour not_allowed)
			(footprints allowed)
		)
		(placement
			(enabled no)
			(sheetname "")
		)
		(fill yes
			(thermal_gap 0.5)
			(thermal_bridge_width 0.5)
			(island_removal_mode 0)
		)
		(polygon
			(pts
				(arc
					(start 404.242016 -432.56073)
					(mid 404.264334 -432.614612)
					(end 404.318216 -432.63693)
				)
				(arc
					(start 405.258016 -432.63693)
					(mid 405.311898 -432.614612)
					(end 405.334216 -432.56073)
				)
				(arc
					(start 405.334216 -430.019206)
					(mid 405.311898 -429.965324)
					(end 405.258016 -429.943006)
				)
				(arc
					(start 404.318216 -429.943006)
					(mid 404.264334 -429.965324)
					(end 404.242016 -430.019206)
				)
			)
		)
	)
	(zone
		(layers "F.Cu" "In2.Cu" "In4.Cu" "In6.Cu" "In11.Cu" "In13.Cu" "In15.Cu")
		(hatch none 0.5)
		(connect_pads
			(clearance 0)
		)
		(min_thickness 0.25)
		(keepout
			(tracks not_allowed)
			(vias allowed)
			(pads allowed)
			(copperpour not_allowed)
			(footprints allowed)
		)
		(placement
			(enabled no)
			(sheetname "")
		)
		(fill yes
			(thermal_gap 0.5)
			(thermal_bridge_width 0.5)
			(island_removal_mode 0)
		)
		(polygon
			(pts
				(arc
					(start 89.142062 -432.56073)
					(mid 89.16438 -432.614612)
					(end 89.218262 -432.63693)
				)
				(arc
					(start 90.158062 -432.63693)
					(mid 90.211944 -432.614612)
					(end 90.234262 -432.56073)
				)
				(arc
					(start 90.234262 -430.019206)
					(mid 90.211944 -429.965324)
					(end 90.158062 -429.943006)
				)
				(arc
					(start 89.218262 -429.943006)
					(mid 89.16438 -429.965324)
					(end 89.142062 -430.019206)
				)
			)
		)
	)
	(zone
		(layers "F.Cu" "In2.Cu" "In4.Cu" "In6.Cu" "In11.Cu" "In13.Cu" "In15.Cu")
		(hatch none 0.5)
		(connect_pads
			(clearance 0)
		)
		(min_thickness 0.25)
		(keepout
			(tracks not_allowed)
			(vias allowed)
			(pads allowed)
			(copperpour not_allowed)
			(footprints allowed)
		)
		(placement
			(enabled no)
			(sheetname "")
		)
		(fill yes
			(thermal_gap 0.5)
			(thermal_bridge_width 0.5)
			(island_removal_mode 0)
		)
		(polygon
			(pts
				(arc
					(start 412.242 -432.56073)
					(mid 412.264318 -432.614612)
					(end 412.3182 -432.63693)
				)
				(arc
					(start 413.258 -432.63693)
					(mid 413.311882 -432.614612)
					(end 413.3342 -432.56073)
				)
				(arc
					(start 413.3342 -430.019206)
					(mid 413.311882 -429.965324)
					(end 413.258 -429.943006)
				)
				(arc
					(start 412.3182 -429.943006)
					(mid 412.264318 -429.965324)
					(end 412.242 -430.019206)
				)
			)
		)
	)
	(zone
		(layers "F.Cu" "In2.Cu" "In4.Cu" "In6.Cu" "In11.Cu" "In13.Cu" "In15.Cu")
		(hatch none 0.5)
		(connect_pads
			(clearance 0)
		)
		(min_thickness 0.25)
		(keepout
			(tracks not_allowed)
			(vias allowed)
			(pads allowed)
			(copperpour not_allowed)
			(footprints allowed)
		)
		(placement
			(enabled no)
			(sheetname "")
		)
		(fill yes
			(thermal_gap 0.5)
			(thermal_bridge_width 0.5)
			(island_removal_mode 0)
		)
		(polygon
			(pts
				(arc
					(start 142.242032 -435.160674)
					(mid 142.26435 -435.214556)
					(end 142.318232 -435.236874)
				)
				(arc
					(start 143.258032 -435.236874)
					(mid 143.311914 -435.214556)
					(end 143.334232 -435.160674)
				)
				(arc
					(start 143.334232 -432.61915)
					(mid 143.311914 -432.565268)
					(end 143.258032 -432.54295)
				)
				(arc
					(start 142.318232 -432.54295)
					(mid 142.26435 -432.565268)
					(end 142.242032 -432.61915)
				)
			)
		)
	)
	(zone
		(layers "F.Cu" "In2.Cu" "In4.Cu" "In6.Cu" "In11.Cu" "In13.Cu" "In15.Cu")
		(hatch none 0.5)
		(connect_pads
			(clearance 0)
		)
		(min_thickness 0.25)
		(keepout
			(tracks not_allowed)
			(vias allowed)
			(pads allowed)
			(copperpour not_allowed)
			(footprints allowed)
		)
		(placement
			(enabled no)
			(sheetname "")
		)
		(fill yes
			(thermal_gap 0.5)
			(thermal_bridge_width 0.5)
			(island_removal_mode 0)
		)
		(polygon
			(pts
				(arc
					(start 316.142116 -436.160672)
					(mid 316.164434 -436.214554)
					(end 316.218316 -436.236872)
				)
				(arc
					(start 317.158116 -436.236872)
					(mid 317.211998 -436.214554)
					(end 317.234316 -436.160672)
				)
				(arc
					(start 317.234316 -433.619148)
					(mid 317.211998 -433.565266)
					(end 317.158116 -433.542948)
				)
				(arc
					(start 316.218316 -433.542948)
					(mid 316.164434 -433.565266)
					(end 316.142116 -433.619148)
				)
			)
		)
	)
	(zone
		(layers "F.Cu" "In2.Cu" "In4.Cu" "In6.Cu" "In11.Cu" "In13.Cu" "In15.Cu")
		(hatch none 0.5)
		(connect_pads
			(clearance 0)
		)
		(min_thickness 0.25)
		(keepout
			(tracks not_allowed)
			(vias allowed)
			(pads allowed)
			(copperpour not_allowed)
			(footprints allowed)
		)
		(placement
			(enabled no)
			(sheetname "")
		)
		(fill yes
			(thermal_gap 0.5)
			(thermal_bridge_width 0.5)
			(island_removal_mode 0)
		)
		(polygon
			(pts
				(arc
					(start 148.24202 -436.160672)
					(mid 148.264338 -436.214554)
					(end 148.31822 -436.236872)
				)
				(arc
					(start 149.25802 -436.236872)
					(mid 149.311902 -436.214554)
					(end 149.33422 -436.160672)
				)
				(arc
					(start 149.33422 -433.619148)
					(mid 149.311902 -433.565266)
					(end 149.25802 -433.542948)
				)
				(arc
					(start 148.31822 -433.542948)
					(mid 148.264338 -433.565266)
					(end 148.24202 -433.619148)
				)
			)
		)
	)
	(zone
		(layers "F.Cu" "In2.Cu" "In4.Cu" "In6.Cu" "In11.Cu" "In13.Cu" "In15.Cu")
		(hatch none 0.5)
		(connect_pads
			(clearance 0)
		)
		(min_thickness 0.25)
		(keepout
			(tracks not_allowed)
			(vias allowed)
			(pads allowed)
			(copperpour not_allowed)
			(footprints allowed)
		)
		(placement
			(enabled no)
			(sheetname "")
		)
		(fill yes
			(thermal_gap 0.5)
			(thermal_bridge_width 0.5)
			(island_removal_mode 0)
		)
		(polygon
			(pts
				(arc
					(start 389.242046 -431.560732)
					(mid 389.264364 -431.614614)
					(end 389.318246 -431.636932)
				)
				(arc
					(start 390.258046 -431.636932)
					(mid 390.311928 -431.614614)
					(end 390.334246 -431.560732)
				)
				(arc
					(start 390.334246 -429.019208)
					(mid 390.311928 -428.965326)
					(end 390.258046 -428.943008)
				)
				(arc
					(start 389.318246 -428.943008)
					(mid 389.264364 -428.965326)
					(end 389.242046 -429.019208)
				)
			)
		)
	)
	(zone
		(layers "F.Cu" "In2.Cu" "In4.Cu" "In6.Cu" "In11.Cu" "In13.Cu" "In15.Cu")
		(hatch none 0.5)
		(connect_pads
			(clearance 0)
		)
		(min_thickness 0.25)
		(keepout
			(tracks not_allowed)
			(vias allowed)
			(pads allowed)
			(copperpour not_allowed)
			(footprints allowed)
		)
		(placement
			(enabled no)
			(sheetname "")
		)
		(fill yes
			(thermal_gap 0.5)
			(thermal_bridge_width 0.5)
			(island_removal_mode 0)
		)
		(polygon
			(pts
				(arc
					(start 404.242016 -436.160672)
					(mid 404.264334 -436.214554)
					(end 404.318216 -436.236872)
				)
				(arc
					(start 405.258016 -436.236872)
					(mid 405.311898 -436.214554)
					(end 405.334216 -436.160672)
				)
				(arc
					(start 405.334216 -433.619148)
					(mid 405.311898 -433.565266)
					(end 405.258016 -433.542948)
				)
				(arc
					(start 404.318216 -433.542948)
					(mid 404.264334 -433.565266)
					(end 404.242016 -433.619148)
				)
			)
		)
	)
	(zone
		(layers "F.Cu" "In2.Cu" "In4.Cu" "In6.Cu" "In11.Cu" "In13.Cu" "In15.Cu")
		(hatch none 0.5)
		(connect_pads
			(clearance 0)
		)
		(min_thickness 0.25)
		(keepout
			(tracks not_allowed)
			(vias allowed)
			(pads allowed)
			(copperpour not_allowed)
			(footprints allowed)
		)
		(placement
			(enabled no)
			(sheetname "")
		)
		(fill yes
			(thermal_gap 0.5)
			(thermal_bridge_width 0.5)
			(island_removal_mode 0)
		)
		(polygon
			(pts
				(arc
					(start 144.242028 -436.160672)
					(mid 144.264346 -436.214554)
					(end 144.318228 -436.236872)
				)
				(arc
					(start 145.258028 -436.236872)
					(mid 145.31191 -436.214554)
					(end 145.334228 -436.160672)
				)
				(arc
					(start 145.334228 -433.619148)
					(mid 145.31191 -433.565266)
					(end 145.258028 -433.542948)
				)
				(arc
					(start 144.318228 -433.542948)
					(mid 144.264346 -433.565266)
					(end 144.242028 -433.619148)
				)
			)
		)
	)
	(zone
		(layers "F.Cu" "In2.Cu" "In4.Cu" "In6.Cu" "In11.Cu" "In13.Cu" "In15.Cu")
		(hatch none 0.5)
		(connect_pads
			(clearance 0)
		)
		(min_thickness 0.25)
		(keepout
			(tracks not_allowed)
			(vias allowed)
			(pads allowed)
			(copperpour not_allowed)
			(footprints allowed)
		)
		(placement
			(enabled no)
			(sheetname "")
		)
		(fill yes
			(thermal_gap 0.5)
			(thermal_bridge_width 0.5)
			(island_removal_mode 0)
		)
		(polygon
			(pts
				(arc
					(start 127.242062 -432.56073)
					(mid 127.26438 -432.614612)
					(end 127.318262 -432.63693)
				)
				(arc
					(start 128.258062 -432.63693)
					(mid 128.311944 -432.614612)
					(end 128.334262 -432.56073)
				)
				(arc
					(start 128.334262 -430.019206)
					(mid 128.311944 -429.965324)
					(end 128.258062 -429.943006)
				)
				(arc
					(start 127.318262 -429.943006)
					(mid 127.26438 -429.965324)
					(end 127.242062 -430.019206)
				)
			)
		)
	)
	(zone
		(layers "F.Cu" "In2.Cu" "In4.Cu" "In6.Cu" "In11.Cu" "In13.Cu" "In15.Cu")
		(hatch none 0.5)
		(connect_pads
			(clearance 0)
		)
		(min_thickness 0.25)
		(keepout
			(tracks not_allowed)
			(vias allowed)
			(pads allowed)
			(copperpour not_allowed)
			(footprints allowed)
		)
		(placement
			(enabled no)
			(sheetname "")
		)
		(fill yes
			(thermal_gap 0.5)
			(thermal_bridge_width 0.5)
			(island_removal_mode 0)
		)
		(polygon
			(pts
				(arc
					(start 131.242054 -436.160672)
					(mid 131.264372 -436.214554)
					(end 131.318254 -436.236872)
				)
				(arc
					(start 132.258054 -436.236872)
					(mid 132.311936 -436.214554)
					(end 132.334254 -436.160672)
				)
				(arc
					(start 132.334254 -433.619148)
					(mid 132.311936 -433.565266)
					(end 132.258054 -433.542948)
				)
				(arc
					(start 131.318254 -433.542948)
					(mid 131.264372 -433.565266)
					(end 131.242054 -433.619148)
				)
			)
		)
	)
	(zone
		(layers "F.Cu" "In2.Cu" "In4.Cu" "In6.Cu" "In11.Cu" "In13.Cu" "In15.Cu")
		(hatch none 0.5)
		(connect_pads
			(clearance 0)
		)
		(min_thickness 0.25)
		(keepout
			(tracks not_allowed)
			(vias allowed)
			(pads allowed)
			(copperpour not_allowed)
			(footprints allowed)
		)
		(placement
			(enabled no)
			(sheetname "")
		)
		(fill yes
			(thermal_gap 0.5)
			(thermal_bridge_width 0.5)
			(island_removal_mode 0)
		)
		(polygon
			(pts
				(arc
					(start 387.24205 -436.160672)
					(mid 387.264368 -436.214554)
					(end 387.31825 -436.236872)
				)
				(arc
					(start 388.25805 -436.236872)
					(mid 388.311932 -436.214554)
					(end 388.33425 -436.160672)
				)
				(arc
					(start 388.33425 -433.619148)
					(mid 388.311932 -433.565266)
					(end 388.25805 -433.542948)
				)
				(arc
					(start 387.31825 -433.542948)
					(mid 387.264368 -433.565266)
					(end 387.24205 -433.619148)
				)
			)
		)
	)
	(zone
		(layers "F.Cu" "In2.Cu" "In4.Cu" "In6.Cu" "In11.Cu" "In13.Cu" "In15.Cu")
		(hatch none 0.5)
		(connect_pads
			(clearance 0)
		)
		(min_thickness 0.25)
		(keepout
			(tracks not_allowed)
			(vias allowed)
			(pads allowed)
			(copperpour not_allowed)
			(footprints allowed)
		)
		(placement
			(enabled no)
			(sheetname "")
		)
		(fill yes
			(thermal_gap 0.5)
			(thermal_bridge_width 0.5)
			(island_removal_mode 0)
		)
		(polygon
			(pts
				(arc
					(start 314.14212 -431.560732)
					(mid 314.164438 -431.614614)
					(end 314.21832 -431.636932)
				)
				(arc
					(start 315.15812 -431.636932)
					(mid 315.212002 -431.614614)
					(end 315.23432 -431.560732)
				)
				(arc
					(start 315.23432 -429.019208)
					(mid 315.212002 -428.965326)
					(end 315.15812 -428.943008)
				)
				(arc
					(start 314.21832 -428.943008)
					(mid 314.164438 -428.965326)
					(end 314.14212 -429.019208)
				)
			)
		)
	)
	(zone
		(layers "F.Cu" "In2.Cu" "In4.Cu" "In6.Cu" "In11.Cu" "In13.Cu" "In15.Cu")
		(hatch none 0.5)
		(connect_pads
			(clearance 0)
		)
		(min_thickness 0.25)
		(keepout
			(tracks not_allowed)
			(vias allowed)
			(pads allowed)
			(copperpour not_allowed)
			(footprints allowed)
		)
		(placement
			(enabled no)
			(sheetname "")
		)
		(fill yes
			(thermal_gap 0.5)
			(thermal_bridge_width 0.5)
			(island_removal_mode 0)
		)
		(polygon
			(pts
				(arc
					(start 87.142066 -435.160674)
					(mid 87.164384 -435.214556)
					(end 87.218266 -435.236874)
				)
				(arc
					(start 88.158066 -435.236874)
					(mid 88.211948 -435.214556)
					(end 88.234266 -435.160674)
				)
				(arc
					(start 88.234266 -432.61915)
					(mid 88.211948 -432.565268)
					(end 88.158066 -432.54295)
				)
				(arc
					(start 87.218266 -432.54295)
					(mid 87.164384 -432.565268)
					(end 87.142066 -432.61915)
				)
			)
		)
	)
	(zone
		(layers "F.Cu" "In2.Cu" "In4.Cu" "In6.Cu" "In11.Cu" "In13.Cu" "In15.Cu")
		(hatch none 0.5)
		(connect_pads
			(clearance 0)
		)
		(min_thickness 0.25)
		(keepout
			(tracks not_allowed)
			(vias allowed)
			(pads allowed)
			(copperpour not_allowed)
			(footprints allowed)
		)
		(placement
			(enabled no)
			(sheetname "")
		)
		(fill yes
			(thermal_gap 0.5)
			(thermal_bridge_width 0.5)
			(island_removal_mode 0)
		)
		(polygon
			(pts
				(arc
					(start 125.242066 -435.160674)
					(mid 125.264384 -435.214556)
					(end 125.318266 -435.236874)
				)
				(arc
					(start 126.258066 -435.236874)
					(mid 126.311948 -435.214556)
					(end 126.334266 -435.160674)
				)
				(arc
					(start 126.334266 -432.61915)
					(mid 126.311948 -432.565268)
					(end 126.258066 -432.54295)
				)
				(arc
					(start 125.318266 -432.54295)
					(mid 125.264384 -432.565268)
					(end 125.242066 -432.61915)
				)
			)
		)
	)
	(zone
		(layers "F.Cu" "In2.Cu" "In4.Cu" "In6.Cu" "In11.Cu" "In13.Cu" "In15.Cu")
		(hatch none 0.5)
		(connect_pads
			(clearance 0)
		)
		(min_thickness 0.25)
		(keepout
			(tracks not_allowed)
			(vias allowed)
			(pads allowed)
			(copperpour not_allowed)
			(footprints allowed)
		)
		(placement
			(enabled no)
			(sheetname "")
		)
		(fill yes
			(thermal_gap 0.5)
			(thermal_bridge_width 0.5)
			(island_removal_mode 0)
		)
		(polygon
			(pts
				(arc
					(start 402.24202 -431.560732)
					(mid 402.264338 -431.614614)
					(end 402.31822 -431.636932)
				)
				(arc
					(start 403.25802 -431.636932)
					(mid 403.311902 -431.614614)
					(end 403.33422 -431.560732)
				)
				(arc
					(start 403.33422 -429.019208)
					(mid 403.311902 -428.965326)
					(end 403.25802 -428.943008)
				)
				(arc
					(start 402.31822 -428.943008)
					(mid 402.264338 -428.965326)
					(end 402.24202 -429.019208)
				)
			)
		)
	)
	(zone
		(layers "F.Cu" "In2.Cu" "In4.Cu" "In6.Cu" "In11.Cu" "In13.Cu" "In15.Cu")
		(hatch none 0.5)
		(connect_pads
			(clearance 0)
		)
		(min_thickness 0.25)
		(keepout
			(tracks not_allowed)
			(vias allowed)
			(pads allowed)
			(copperpour not_allowed)
			(footprints allowed)
		)
		(placement
			(enabled no)
			(sheetname "")
		)
		(fill yes
			(thermal_gap 0.5)
			(thermal_bridge_width 0.5)
			(island_removal_mode 0)
		)
		(polygon
			(pts
				(arc
					(start 345.142058 -432.56073)
					(mid 345.164376 -432.614612)
					(end 345.218258 -432.63693)
				)
				(arc
					(start 346.158058 -432.63693)
					(mid 346.21194 -432.614612)
					(end 346.234258 -432.56073)
				)
				(arc
					(start 346.234258 -430.019206)
					(mid 346.21194 -429.965324)
					(end 346.158058 -429.943006)
				)
				(arc
					(start 345.218258 -429.943006)
					(mid 345.164376 -429.965324)
					(end 345.142058 -430.019206)
				)
			)
		)
	)
	(zone
		(layers "F.Cu" "In2.Cu" "In4.Cu" "In6.Cu" "In11.Cu" "In13.Cu" "In15.Cu")
		(hatch none 0.5)
		(connect_pads
			(clearance 0)
		)
		(min_thickness 0.25)
		(keepout
			(tracks not_allowed)
			(vias allowed)
			(pads allowed)
			(copperpour not_allowed)
			(footprints allowed)
		)
		(placement
			(enabled no)
			(sheetname "")
		)
		(fill yes
			(thermal_gap 0.5)
			(thermal_bridge_width 0.5)
			(island_removal_mode 0)
		)
		(polygon
			(pts
				(arc
					(start 83.142074 -435.160674)
					(mid 83.164392 -435.214556)
					(end 83.218274 -435.236874)
				)
				(arc
					(start 84.158074 -435.236874)
					(mid 84.211956 -435.214556)
					(end 84.234274 -435.160674)
				)
				(arc
					(start 84.234274 -432.61915)
					(mid 84.211956 -432.565268)
					(end 84.158074 -432.54295)
				)
				(arc
					(start 83.218274 -432.54295)
					(mid 83.164392 -432.565268)
					(end 83.142074 -432.61915)
				)
			)
		)
	)
	(zone
		(layers "F.Cu" "In2.Cu" "In4.Cu" "In6.Cu" "In11.Cu" "In13.Cu" "In15.Cu")
		(hatch none 0.5)
		(connect_pads
			(clearance 0)
		)
		(min_thickness 0.25)
		(keepout
			(tracks not_allowed)
			(vias allowed)
			(pads allowed)
			(copperpour not_allowed)
			(footprints allowed)
		)
		(placement
			(enabled no)
			(sheetname "")
		)
		(fill yes
			(thermal_gap 0.5)
			(thermal_bridge_width 0.5)
			(island_removal_mode 0)
		)
		(polygon
			(pts
				(arc
					(start 144.242028 -432.56073)
					(mid 144.264346 -432.614612)
					(end 144.318228 -432.63693)
				)
				(arc
					(start 145.258028 -432.63693)
					(mid 145.31191 -432.614612)
					(end 145.334228 -432.56073)
				)
				(arc
					(start 145.334228 -430.019206)
					(mid 145.31191 -429.965324)
					(end 145.258028 -429.943006)
				)
				(arc
					(start 144.318228 -429.943006)
					(mid 144.264346 -429.965324)
					(end 144.242028 -430.019206)
				)
			)
		)
	)
	(zone
		(layers "F.Cu" "In2.Cu" "In4.Cu" "In6.Cu" "In11.Cu" "In13.Cu" "In15.Cu")
		(hatch none 0.5)
		(connect_pads
			(clearance 0)
		)
		(min_thickness 0.25)
		(keepout
			(tracks not_allowed)
			(vias allowed)
			(pads allowed)
			(copperpour not_allowed)
			(footprints allowed)
		)
		(placement
			(enabled no)
			(sheetname "")
		)
		(fill yes
			(thermal_gap 0.5)
			(thermal_bridge_width 0.5)
			(island_removal_mode 0)
		)
		(polygon
			(pts
				(arc
					(start 64.142112 -432.56073)
					(mid 64.16443 -432.614612)
					(end 64.218312 -432.63693)
				)
				(arc
					(start 65.158112 -432.63693)
					(mid 65.211994 -432.614612)
					(end 65.234312 -432.56073)
				)
				(arc
					(start 65.234312 -430.019206)
					(mid 65.211994 -429.965324)
					(end 65.158112 -429.943006)
				)
				(arc
					(start 64.218312 -429.943006)
					(mid 64.16443 -429.965324)
					(end 64.142112 -430.019206)
				)
			)
		)
	)
	(zone
		(layers "F.Cu" "In2.Cu" "In4.Cu" "In6.Cu" "In11.Cu" "In13.Cu" "In15.Cu")
		(hatch none 0.5)
		(connect_pads
			(clearance 0)
		)
		(min_thickness 0.25)
		(keepout
			(tracks not_allowed)
			(vias allowed)
			(pads allowed)
			(copperpour not_allowed)
			(footprints allowed)
		)
		(placement
			(enabled no)
			(sheetname "")
		)
		(fill yes
			(thermal_gap 0.5)
			(thermal_bridge_width 0.5)
			(island_removal_mode 0)
		)
		(polygon
			(pts
				(arc
					(start 406.242012 -435.160674)
					(mid 406.26433 -435.214556)
					(end 406.318212 -435.236874)
				)
				(arc
					(start 407.258012 -435.236874)
					(mid 407.311894 -435.214556)
					(end 407.334212 -435.160674)
				)
				(arc
					(start 407.334212 -432.61915)
					(mid 407.311894 -432.565268)
					(end 407.258012 -432.54295)
				)
				(arc
					(start 406.318212 -432.54295)
					(mid 406.26433 -432.565268)
					(end 406.242012 -432.61915)
				)
			)
		)
	)
	(zone
		(layers "F.Cu" "In2.Cu" "In4.Cu" "In6.Cu" "In11.Cu" "In13.Cu" "In15.Cu")
		(hatch none 0.5)
		(connect_pads
			(clearance 0)
		)
		(min_thickness 0.25)
		(keepout
			(tracks not_allowed)
			(vias allowed)
			(pads allowed)
			(copperpour not_allowed)
			(footprints allowed)
		)
		(placement
			(enabled no)
			(sheetname "")
		)
		(fill yes
			(thermal_gap 0.5)
			(thermal_bridge_width 0.5)
			(island_removal_mode 0)
		)
		(polygon
			(pts
				(arc
					(start 62.142116 -431.560732)
					(mid 62.164434 -431.614614)
					(end 62.218316 -431.636932)
				)
				(arc
					(start 63.158116 -431.636932)
					(mid 63.211998 -431.614614)
					(end 63.234316 -431.560732)
				)
				(arc
					(start 63.234316 -429.019208)
					(mid 63.211998 -428.965326)
					(end 63.158116 -428.943008)
				)
				(arc
					(start 62.218316 -428.943008)
					(mid 62.164434 -428.965326)
					(end 62.142116 -429.019208)
				)
			)
		)
	)
	(zone
		(layers "F.Cu" "In2.Cu" "In4.Cu" "In6.Cu" "In11.Cu" "In13.Cu" "In15.Cu")
		(hatch none 0.5)
		(connect_pads
			(clearance 0)
		)
		(min_thickness 0.25)
		(keepout
			(tracks not_allowed)
			(vias allowed)
			(pads allowed)
			(copperpour not_allowed)
			(footprints allowed)
		)
		(placement
			(enabled no)
			(sheetname "")
		)
		(fill yes
			(thermal_gap 0.5)
			(thermal_bridge_width 0.5)
			(island_removal_mode 0)
		)
		(polygon
			(pts
				(arc
					(start 339.14207 -431.560732)
					(mid 339.164388 -431.614614)
					(end 339.21827 -431.636932)
				)
				(arc
					(start 340.15807 -431.636932)
					(mid 340.211952 -431.614614)
					(end 340.23427 -431.560732)
				)
				(arc
					(start 340.23427 -429.019208)
					(mid 340.211952 -428.965326)
					(end 340.15807 -428.943008)
				)
				(arc
					(start 339.21827 -428.943008)
					(mid 339.164388 -428.965326)
					(end 339.14207 -429.019208)
				)
			)
		)
	)
	(zone
		(layers "F.Cu" "In2.Cu" "In4.Cu" "In6.Cu" "In11.Cu" "In13.Cu" "In15.Cu")
		(hatch none 0.5)
		(connect_pads
			(clearance 0)
		)
		(min_thickness 0.25)
		(keepout
			(tracks not_allowed)
			(vias allowed)
			(pads allowed)
			(copperpour not_allowed)
			(footprints allowed)
		)
		(placement
			(enabled no)
			(sheetname "")
		)
		(fill yes
			(thermal_gap 0.5)
			(thermal_bridge_width 0.5)
			(island_removal_mode 0)
		)
		(polygon
			(pts
				(arc
					(start 391.242042 -432.56073)
					(mid 391.26436 -432.614612)
					(end 391.318242 -432.63693)
				)
				(arc
					(start 392.258042 -432.63693)
					(mid 392.311924 -432.614612)
					(end 392.334242 -432.56073)
				)
				(arc
					(start 392.334242 -430.019206)
					(mid 392.311924 -429.965324)
					(end 392.258042 -429.943006)
				)
				(arc
					(start 391.318242 -429.943006)
					(mid 391.26436 -429.965324)
					(end 391.242042 -430.019206)
				)
			)
		)
	)
	(zone
		(layers "F.Cu" "In2.Cu" "In4.Cu" "In6.Cu" "In11.Cu" "In13.Cu" "In15.Cu")
		(hatch none 0.5)
		(connect_pads
			(clearance 0)
		)
		(min_thickness 0.25)
		(keepout
			(tracks not_allowed)
			(vias allowed)
			(pads allowed)
			(copperpour not_allowed)
			(footprints allowed)
		)
		(placement
			(enabled no)
			(sheetname "")
		)
		(fill yes
			(thermal_gap 0.5)
			(thermal_bridge_width 0.5)
			(island_removal_mode 0)
		)
		(polygon
			(pts
				(arc
					(start 72.142096 -436.160672)
					(mid 72.164414 -436.214554)
					(end 72.218296 -436.236872)
				)
				(arc
					(start 73.158096 -436.236872)
					(mid 73.211978 -436.214554)
					(end 73.234296 -436.160672)
				)
				(arc
					(start 73.234296 -433.619148)
					(mid 73.211978 -433.565266)
					(end 73.158096 -433.542948)
				)
				(arc
					(start 72.218296 -433.542948)
					(mid 72.164414 -433.565266)
					(end 72.142096 -433.619148)
				)
			)
		)
	)
	(zone
		(layers "F.Cu" "In2.Cu" "In4.Cu" "In6.Cu" "In11.Cu" "In13.Cu" "In15.Cu")
		(hatch none 0.5)
		(connect_pads
			(clearance 0)
		)
		(min_thickness 0.25)
		(keepout
			(tracks not_allowed)
			(vias allowed)
			(pads allowed)
			(copperpour not_allowed)
			(footprints allowed)
		)
		(placement
			(enabled no)
			(sheetname "")
		)
		(fill yes
			(thermal_gap 0.5)
			(thermal_bridge_width 0.5)
			(island_removal_mode 0)
		)
		(polygon
			(pts
				(arc
					(start 139.242038 -432.56073)
					(mid 139.264356 -432.614612)
					(end 139.318238 -432.63693)
				)
				(arc
					(start 140.258038 -432.63693)
					(mid 140.31192 -432.614612)
					(end 140.334238 -432.56073)
				)
				(arc
					(start 140.334238 -430.019206)
					(mid 140.31192 -429.965324)
					(end 140.258038 -429.943006)
				)
				(arc
					(start 139.318238 -429.943006)
					(mid 139.264356 -429.965324)
					(end 139.242038 -430.019206)
				)
			)
		)
	)
	(zone
		(layers "F.Cu" "In2.Cu" "In4.Cu" "In6.Cu" "In11.Cu" "In13.Cu" "In15.Cu")
		(hatch none 0.5)
		(connect_pads
			(clearance 0)
		)
		(min_thickness 0.25)
		(keepout
			(tracks not_allowed)
			(vias allowed)
			(pads allowed)
			(copperpour not_allowed)
			(footprints allowed)
		)
		(placement
			(enabled no)
			(sheetname "")
		)
		(fill yes
			(thermal_gap 0.5)
			(thermal_bridge_width 0.5)
			(island_removal_mode 0)
		)
		(polygon
			(pts
				(arc
					(start 381.242062 -431.560732)
					(mid 381.26438 -431.614614)
					(end 381.318262 -431.636932)
				)
				(arc
					(start 382.258062 -431.636932)
					(mid 382.311944 -431.614614)
					(end 382.334262 -431.560732)
				)
				(arc
					(start 382.334262 -429.019208)
					(mid 382.311944 -428.965326)
					(end 382.258062 -428.943008)
				)
				(arc
					(start 381.318262 -428.943008)
					(mid 381.26438 -428.965326)
					(end 381.242062 -429.019208)
				)
			)
		)
	)
	(zone
		(layers "F.Cu" "In2.Cu" "In4.Cu" "In6.Cu" "In11.Cu" "In13.Cu" "In15.Cu")
		(hatch none 0.5)
		(connect_pads
			(clearance 0)
		)
		(min_thickness 0.25)
		(keepout
			(tracks not_allowed)
			(vias allowed)
			(pads allowed)
			(copperpour not_allowed)
			(footprints allowed)
		)
		(placement
			(enabled no)
			(sheetname "")
		)
		(fill yes
			(thermal_gap 0.5)
			(thermal_bridge_width 0.5)
			(island_removal_mode 0)
		)
		(polygon
			(pts
				(arc
					(start 406.242012 -431.560732)
					(mid 406.26433 -431.614614)
					(end 406.318212 -431.636932)
				)
				(arc
					(start 407.258012 -431.636932)
					(mid 407.311894 -431.614614)
					(end 407.334212 -431.560732)
				)
				(arc
					(start 407.334212 -429.019208)
					(mid 407.311894 -428.965326)
					(end 407.258012 -428.943008)
				)
				(arc
					(start 406.318212 -428.943008)
					(mid 406.26433 -428.965326)
					(end 406.242012 -429.019208)
				)
			)
		)
	)
	(zone
		(layers "F.Cu" "In2.Cu" "In4.Cu" "In6.Cu" "In11.Cu" "In13.Cu" "In15.Cu")
		(hatch none 0.5)
		(connect_pads
			(clearance 0)
		)
		(min_thickness 0.25)
		(keepout
			(tracks not_allowed)
			(vias allowed)
			(pads allowed)
			(copperpour not_allowed)
			(footprints allowed)
		)
		(placement
			(enabled no)
			(sheetname "")
		)
		(fill yes
			(thermal_gap 0.5)
			(thermal_bridge_width 0.5)
			(island_removal_mode 0)
		)
		(polygon
			(pts
				(arc
					(start 328.142092 -436.160672)
					(mid 328.16441 -436.214554)
					(end 328.218292 -436.236872)
				)
				(arc
					(start 329.158092 -436.236872)
					(mid 329.211974 -436.214554)
					(end 329.234292 -436.160672)
				)
				(arc
					(start 329.234292 -433.619148)
					(mid 329.211974 -433.565266)
					(end 329.158092 -433.542948)
				)
				(arc
					(start 328.218292 -433.542948)
					(mid 328.16441 -433.565266)
					(end 328.142092 -433.619148)
				)
			)
		)
	)
	(zone
		(layers "F.Cu" "In2.Cu" "In4.Cu" "In6.Cu" "In11.Cu" "In13.Cu" "In15.Cu")
		(hatch none 0.5)
		(connect_pads
			(clearance 0)
		)
		(min_thickness 0.25)
		(keepout
			(tracks not_allowed)
			(vias allowed)
			(pads allowed)
			(copperpour not_allowed)
			(footprints allowed)
		)
		(placement
			(enabled no)
			(sheetname "")
		)
		(fill yes
			(thermal_gap 0.5)
			(thermal_bridge_width 0.5)
			(island_removal_mode 0)
		)
		(polygon
			(pts
				(arc
					(start 400.242024 -436.160672)
					(mid 400.264342 -436.214554)
					(end 400.318224 -436.236872)
				)
				(arc
					(start 401.258024 -436.236872)
					(mid 401.311906 -436.214554)
					(end 401.334224 -436.160672)
				)
				(arc
					(start 401.334224 -433.619148)
					(mid 401.311906 -433.565266)
					(end 401.258024 -433.542948)
				)
				(arc
					(start 400.318224 -433.542948)
					(mid 400.264342 -433.565266)
					(end 400.242024 -433.619148)
				)
			)
		)
	)
	(zone
		(layers "F.Cu" "In2.Cu" "In4.Cu" "In6.Cu" "In11.Cu" "In13.Cu" "In15.Cu")
		(hatch none 0.5)
		(connect_pads
			(clearance 0)
		)
		(min_thickness 0.25)
		(keepout
			(tracks not_allowed)
			(vias allowed)
			(pads allowed)
			(copperpour not_allowed)
			(footprints allowed)
		)
		(placement
			(enabled no)
			(sheetname "")
		)
		(fill yes
			(thermal_gap 0.5)
			(thermal_bridge_width 0.5)
			(island_removal_mode 0)
		)
		(polygon
			(pts
				(arc
					(start 62.142116 -435.160674)
					(mid 62.164434 -435.214556)
					(end 62.218316 -435.236874)
				)
				(arc
					(start 63.158116 -435.236874)
					(mid 63.211998 -435.214556)
					(end 63.234316 -435.160674)
				)
				(arc
					(start 63.234316 -432.61915)
					(mid 63.211998 -432.565268)
					(end 63.158116 -432.54295)
				)
				(arc
					(start 62.218316 -432.54295)
					(mid 62.164434 -432.565268)
					(end 62.142116 -432.61915)
				)
			)
		)
	)
	(zone
		(layers "F.Cu" "In2.Cu" "In4.Cu" "In6.Cu" "In11.Cu" "In13.Cu" "In15.Cu")
		(hatch none 0.5)
		(connect_pads
			(clearance 0)
		)
		(min_thickness 0.25)
		(keepout
			(tracks not_allowed)
			(vias allowed)
			(pads allowed)
			(copperpour not_allowed)
			(footprints allowed)
		)
		(placement
			(enabled no)
			(sheetname "")
		)
		(fill yes
			(thermal_gap 0.5)
			(thermal_bridge_width 0.5)
			(island_removal_mode 0)
		)
		(polygon
			(pts
				(arc
					(start 393.242038 -435.160674)
					(mid 393.264356 -435.214556)
					(end 393.318238 -435.236874)
				)
				(arc
					(start 394.258038 -435.236874)
					(mid 394.31192 -435.214556)
					(end 394.334238 -435.160674)
				)
				(arc
					(start 394.334238 -432.61915)
					(mid 394.31192 -432.565268)
					(end 394.258038 -432.54295)
				)
				(arc
					(start 393.318238 -432.54295)
					(mid 393.264356 -432.565268)
					(end 393.242038 -432.61915)
				)
			)
		)
	)
	(zone
		(layers "F.Cu" "In2.Cu" "In4.Cu" "In6.Cu" "In11.Cu" "In13.Cu" "In15.Cu")
		(hatch none 0.5)
		(connect_pads
			(clearance 0)
		)
		(min_thickness 0.25)
		(keepout
			(tracks not_allowed)
			(vias allowed)
			(pads allowed)
			(copperpour not_allowed)
			(footprints allowed)
		)
		(placement
			(enabled no)
			(sheetname "")
		)
		(fill yes
			(thermal_gap 0.5)
			(thermal_bridge_width 0.5)
			(island_removal_mode 0)
		)
		(polygon
			(pts
				(arc
					(start 341.142066 -432.56073)
					(mid 341.164384 -432.614612)
					(end 341.218266 -432.63693)
				)
				(arc
					(start 342.158066 -432.63693)
					(mid 342.211948 -432.614612)
					(end 342.234266 -432.56073)
				)
				(arc
					(start 342.234266 -430.019206)
					(mid 342.211948 -429.965324)
					(end 342.158066 -429.943006)
				)
				(arc
					(start 341.218266 -429.943006)
					(mid 341.164384 -429.965324)
					(end 341.142066 -430.019206)
				)
			)
		)
	)
	(zone
		(layers "F.Cu" "In2.Cu" "In4.Cu" "In6.Cu" "In11.Cu" "In15.Cu")
		(hatch none 0.5)
		(connect_pads
			(clearance 0)
		)
		(min_thickness 0.25)
		(keepout
			(tracks not_allowed)
			(vias allowed)
			(pads allowed)
			(copperpour not_allowed)
			(footprints allowed)
		)
		(placement
			(enabled no)
			(sheetname "")
		)
		(fill yes
			(thermal_gap 0.5)
			(thermal_bridge_width 0.5)
			(island_removal_mode 0)
		)
		(polygon
			(pts
				(arc
					(start 137.242042 -427.96079)
					(mid 137.26436 -428.014672)
					(end 137.318242 -428.03699)
				)
				(arc
					(start 138.258042 -428.03699)
					(mid 138.311924 -428.014672)
					(end 138.334242 -427.96079)
				)
				(arc
					(start 138.334242 -425.419266)
					(mid 138.311924 -425.365384)
					(end 138.258042 -425.343066)
				)
				(arc
					(start 137.318242 -425.343066)
					(mid 137.26436 -425.365384)
					(end 137.242042 -425.419266)
				)
			)
		)
	)
	(zone
		(layers "F.Cu" "In2.Cu" "In4.Cu" "In6.Cu" "In11.Cu" "In15.Cu")
		(hatch none 0.5)
		(connect_pads
			(clearance 0)
		)
		(min_thickness 0.25)
		(keepout
			(tracks not_allowed)
			(vias allowed)
			(pads allowed)
			(copperpour not_allowed)
			(footprints allowed)
		)
		(placement
			(enabled no)
			(sheetname "")
		)
		(fill yes
			(thermal_gap 0.5)
			(thermal_bridge_width 0.5)
			(island_removal_mode 0)
		)
		(polygon
			(pts
				(arc
					(start 385.242054 -427.96079)
					(mid 385.264372 -428.014672)
					(end 385.318254 -428.03699)
				)
				(arc
					(start 386.258054 -428.03699)
					(mid 386.311936 -428.014672)
					(end 386.334254 -427.96079)
				)
				(arc
					(start 386.334254 -425.419266)
					(mid 386.311936 -425.365384)
					(end 386.258054 -425.343066)
				)
				(arc
					(start 385.318254 -425.343066)
					(mid 385.264372 -425.365384)
					(end 385.242054 -425.419266)
				)
			)
		)
	)
	(zone
		(layers "F.Cu" "In2.Cu" "In4.Cu" "In6.Cu" "In11.Cu" "In15.Cu")
		(hatch none 0.5)
		(connect_pads
			(clearance 0)
		)
		(min_thickness 0.25)
		(keepout
			(tracks not_allowed)
			(vias allowed)
			(pads allowed)
			(copperpour not_allowed)
			(footprints allowed)
		)
		(placement
			(enabled no)
			(sheetname "")
		)
		(fill yes
			(thermal_gap 0.5)
			(thermal_bridge_width 0.5)
			(island_removal_mode 0)
		)
		(polygon
			(pts
				(arc
					(start 75.14209 -427.96079)
					(mid 75.164408 -428.014672)
					(end 75.21829 -428.03699)
				)
				(arc
					(start 76.15809 -428.03699)
					(mid 76.211972 -428.014672)
					(end 76.23429 -427.96079)
				)
				(arc
					(start 76.23429 -425.419266)
					(mid 76.211972 -425.365384)
					(end 76.15809 -425.343066)
				)
				(arc
					(start 75.21829 -425.343066)
					(mid 75.164408 -425.365384)
					(end 75.14209 -425.419266)
				)
			)
		)
	)
	(zone
		(layers "F.Cu" "In2.Cu" "In4.Cu" "In6.Cu" "In11.Cu" "In15.Cu")
		(hatch none 0.5)
		(connect_pads
			(clearance 0)
		)
		(min_thickness 0.25)
		(keepout
			(tracks not_allowed)
			(vias allowed)
			(pads allowed)
			(copperpour not_allowed)
			(footprints allowed)
		)
		(placement
			(enabled no)
			(sheetname "")
		)
		(fill yes
			(thermal_gap 0.5)
			(thermal_bridge_width 0.5)
			(island_removal_mode 0)
		)
		(polygon
			(pts
				(arc
					(start 142.242032 -427.96079)
					(mid 142.26435 -428.014672)
					(end 142.318232 -428.03699)
				)
				(arc
					(start 143.258032 -428.03699)
					(mid 143.311914 -428.014672)
					(end 143.334232 -427.96079)
				)
				(arc
					(start 143.334232 -425.419266)
					(mid 143.311914 -425.365384)
					(end 143.258032 -425.343066)
				)
				(arc
					(start 142.318232 -425.343066)
					(mid 142.26435 -425.365384)
					(end 142.242032 -425.419266)
				)
			)
		)
	)
	(zone
		(layers "F.Cu" "In2.Cu" "In4.Cu" "In6.Cu" "In11.Cu" "In15.Cu")
		(hatch none 0.5)
		(connect_pads
			(clearance 0)
		)
		(min_thickness 0.25)
		(keepout
			(tracks not_allowed)
			(vias allowed)
			(pads allowed)
			(copperpour not_allowed)
			(footprints allowed)
		)
		(placement
			(enabled no)
			(sheetname "")
		)
		(fill yes
			(thermal_gap 0.5)
			(thermal_bridge_width 0.5)
			(island_removal_mode 0)
		)
		(polygon
			(pts
				(arc
					(start 79.142082 -427.96079)
					(mid 79.1644 -428.014672)
					(end 79.218282 -428.03699)
				)
				(arc
					(start 80.158082 -428.03699)
					(mid 80.211964 -428.014672)
					(end 80.234282 -427.96079)
				)
				(arc
					(start 80.234282 -425.419266)
					(mid 80.211964 -425.365384)
					(end 80.158082 -425.343066)
				)
				(arc
					(start 79.218282 -425.343066)
					(mid 79.1644 -425.365384)
					(end 79.142082 -425.419266)
				)
			)
		)
	)
	(zone
		(layers "F.Cu" "In2.Cu" "In4.Cu" "In6.Cu" "In11.Cu" "In15.Cu")
		(hatch none 0.5)
		(connect_pads
			(clearance 0)
		)
		(min_thickness 0.25)
		(keepout
			(tracks not_allowed)
			(vias allowed)
			(pads allowed)
			(copperpour not_allowed)
			(footprints allowed)
		)
		(placement
			(enabled no)
			(sheetname "")
		)
		(fill yes
			(thermal_gap 0.5)
			(thermal_bridge_width 0.5)
			(island_removal_mode 0)
		)
		(polygon
			(pts
				(arc
					(start 326.142096 -427.96079)
					(mid 326.164414 -428.014672)
					(end 326.218296 -428.03699)
				)
				(arc
					(start 327.158096 -428.03699)
					(mid 327.211978 -428.014672)
					(end 327.234296 -427.96079)
				)
				(arc
					(start 327.234296 -425.419266)
					(mid 327.211978 -425.365384)
					(end 327.158096 -425.343066)
				)
				(arc
					(start 326.218296 -425.343066)
					(mid 326.164414 -425.365384)
					(end 326.142096 -425.419266)
				)
			)
		)
	)
	(zone
		(layers "F.Cu" "In2.Cu" "In4.Cu" "In6.Cu" "In11.Cu" "In15.Cu")
		(hatch none 0.5)
		(connect_pads
			(clearance 0)
		)
		(min_thickness 0.25)
		(keepout
			(tracks not_allowed)
			(vias allowed)
			(pads allowed)
			(copperpour not_allowed)
			(footprints allowed)
		)
		(placement
			(enabled no)
			(sheetname "")
		)
		(fill yes
			(thermal_gap 0.5)
			(thermal_bridge_width 0.5)
			(island_removal_mode 0)
		)
		(polygon
			(pts
				(arc
					(start 318.142112 -427.96079)
					(mid 318.16443 -428.014672)
					(end 318.218312 -428.03699)
				)
				(arc
					(start 319.158112 -428.03699)
					(mid 319.211994 -428.014672)
					(end 319.234312 -427.96079)
				)
				(arc
					(start 319.234312 -425.419266)
					(mid 319.211994 -425.365384)
					(end 319.158112 -425.343066)
				)
				(arc
					(start 318.218312 -425.343066)
					(mid 318.16443 -425.365384)
					(end 318.142112 -425.419266)
				)
			)
		)
	)
	(zone
		(layers "F.Cu" "In2.Cu" "In4.Cu" "In6.Cu" "In11.Cu" "In15.Cu")
		(hatch none 0.5)
		(connect_pads
			(clearance 0)
		)
		(min_thickness 0.25)
		(keepout
			(tracks not_allowed)
			(vias allowed)
			(pads allowed)
			(copperpour not_allowed)
			(footprints allowed)
		)
		(placement
			(enabled no)
			(sheetname "")
		)
		(fill yes
			(thermal_gap 0.5)
			(thermal_bridge_width 0.5)
			(island_removal_mode 0)
		)
		(polygon
			(pts
				(arc
					(start 70.1421 -427.96079)
					(mid 70.164418 -428.014672)
					(end 70.2183 -428.03699)
				)
				(arc
					(start 71.1581 -428.03699)
					(mid 71.211982 -428.014672)
					(end 71.2343 -427.96079)
				)
				(arc
					(start 71.2343 -425.419266)
					(mid 71.211982 -425.365384)
					(end 71.1581 -425.343066)
				)
				(arc
					(start 70.2183 -425.343066)
					(mid 70.164418 -425.365384)
					(end 70.1421 -425.419266)
				)
			)
		)
	)
	(zone
		(layers "F.Cu" "In2.Cu" "In4.Cu" "In6.Cu" "In11.Cu" "In15.Cu")
		(hatch none 0.5)
		(connect_pads
			(clearance 0)
		)
		(min_thickness 0.25)
		(keepout
			(tracks not_allowed)
			(vias allowed)
			(pads allowed)
			(copperpour not_allowed)
			(footprints allowed)
		)
		(placement
			(enabled no)
			(sheetname "")
		)
		(fill yes
			(thermal_gap 0.5)
			(thermal_bridge_width 0.5)
			(island_removal_mode 0)
		)
		(polygon
			(pts
				(arc
					(start 343.142062 -427.96079)
					(mid 343.16438 -428.014672)
					(end 343.218262 -428.03699)
				)
				(arc
					(start 344.158062 -428.03699)
					(mid 344.211944 -428.014672)
					(end 344.234262 -427.96079)
				)
				(arc
					(start 344.234262 -425.419266)
					(mid 344.211944 -425.365384)
					(end 344.158062 -425.343066)
				)
				(arc
					(start 343.218262 -425.343066)
					(mid 343.16438 -425.365384)
					(end 343.142062 -425.419266)
				)
			)
		)
	)
	(zone
		(layers "F.Cu" "In2.Cu" "In4.Cu" "In6.Cu" "In11.Cu" "In15.Cu")
		(hatch none 0.5)
		(connect_pads
			(clearance 0)
		)
		(min_thickness 0.25)
		(keepout
			(tracks not_allowed)
			(vias allowed)
			(pads allowed)
			(copperpour not_allowed)
			(footprints allowed)
		)
		(placement
			(enabled no)
			(sheetname "")
		)
		(fill yes
			(thermal_gap 0.5)
			(thermal_bridge_width 0.5)
			(island_removal_mode 0)
		)
		(polygon
			(pts
				(arc
					(start 335.142078 -427.96079)
					(mid 335.164396 -428.014672)
					(end 335.218278 -428.03699)
				)
				(arc
					(start 336.158078 -428.03699)
					(mid 336.21196 -428.014672)
					(end 336.234278 -427.96079)
				)
				(arc
					(start 336.234278 -425.419266)
					(mid 336.21196 -425.365384)
					(end 336.158078 -425.343066)
				)
				(arc
					(start 335.218278 -425.343066)
					(mid 335.164396 -425.365384)
					(end 335.142078 -425.419266)
				)
			)
		)
	)
	(zone
		(layers "F.Cu" "In2.Cu" "In4.Cu" "In6.Cu" "In11.Cu" "In15.Cu")
		(hatch none 0.5)
		(connect_pads
			(clearance 0)
		)
		(min_thickness 0.25)
		(keepout
			(tracks not_allowed)
			(vias allowed)
			(pads allowed)
			(copperpour not_allowed)
			(footprints allowed)
		)
		(placement
			(enabled no)
			(sheetname "")
		)
		(fill yes
			(thermal_gap 0.5)
			(thermal_bridge_width 0.5)
			(island_removal_mode 0)
		)
		(polygon
			(pts
				(arc
					(start 389.242046 -427.96079)
					(mid 389.264364 -428.014672)
					(end 389.318246 -428.03699)
				)
				(arc
					(start 390.258046 -428.03699)
					(mid 390.311928 -428.014672)
					(end 390.334246 -427.96079)
				)
				(arc
					(start 390.334246 -425.419266)
					(mid 390.311928 -425.365384)
					(end 390.258046 -425.343066)
				)
				(arc
					(start 389.318246 -425.343066)
					(mid 389.264364 -425.365384)
					(end 389.242046 -425.419266)
				)
			)
		)
	)
	(zone
		(layers "F.Cu" "In2.Cu" "In4.Cu" "In6.Cu" "In11.Cu" "In15.Cu")
		(hatch none 0.5)
		(connect_pads
			(clearance 0)
		)
		(min_thickness 0.25)
		(keepout
			(tracks not_allowed)
			(vias allowed)
			(pads allowed)
			(copperpour not_allowed)
			(footprints allowed)
		)
		(placement
			(enabled no)
			(sheetname "")
		)
		(fill yes
			(thermal_gap 0.5)
			(thermal_bridge_width 0.5)
			(island_removal_mode 0)
		)
		(polygon
			(pts
				(arc
					(start 66.142108 -427.96079)
					(mid 66.164426 -428.014672)
					(end 66.218308 -428.03699)
				)
				(arc
					(start 67.158108 -428.03699)
					(mid 67.21199 -428.014672)
					(end 67.234308 -427.96079)
				)
				(arc
					(start 67.234308 -425.419266)
					(mid 67.21199 -425.365384)
					(end 67.158108 -425.343066)
				)
				(arc
					(start 66.218308 -425.343066)
					(mid 66.164426 -425.365384)
					(end 66.142108 -425.419266)
				)
			)
		)
	)
	(zone
		(layers "F.Cu" "In2.Cu" "In4.Cu" "In6.Cu" "In11.Cu" "In15.Cu")
		(hatch none 0.5)
		(connect_pads
			(clearance 0)
		)
		(min_thickness 0.25)
		(keepout
			(tracks not_allowed)
			(vias allowed)
			(pads allowed)
			(copperpour not_allowed)
			(footprints allowed)
		)
		(placement
			(enabled no)
			(sheetname "")
		)
		(fill yes
			(thermal_gap 0.5)
			(thermal_bridge_width 0.5)
			(island_removal_mode 0)
		)
		(polygon
			(pts
				(arc
					(start 393.242038 -427.96079)
					(mid 393.264356 -428.014672)
					(end 393.318238 -428.03699)
				)
				(arc
					(start 394.258038 -428.03699)
					(mid 394.31192 -428.014672)
					(end 394.334238 -427.96079)
				)
				(arc
					(start 394.334238 -425.419266)
					(mid 394.31192 -425.365384)
					(end 394.258038 -425.343066)
				)
				(arc
					(start 393.318238 -425.343066)
					(mid 393.264356 -425.365384)
					(end 393.242038 -425.419266)
				)
			)
		)
	)
	(zone
		(layers "F.Cu" "In2.Cu" "In4.Cu" "In6.Cu" "In11.Cu" "In15.Cu")
		(hatch none 0.5)
		(connect_pads
			(clearance 0)
		)
		(min_thickness 0.25)
		(keepout
			(tracks not_allowed)
			(vias allowed)
			(pads allowed)
			(copperpour not_allowed)
			(footprints allowed)
		)
		(placement
			(enabled no)
			(sheetname "")
		)
		(fill yes
			(thermal_gap 0.5)
			(thermal_bridge_width 0.5)
			(island_removal_mode 0)
		)
		(polygon
			(pts
				(arc
					(start 125.242066 -427.96079)
					(mid 125.264384 -428.014672)
					(end 125.318266 -428.03699)
				)
				(arc
					(start 126.258066 -428.03699)
					(mid 126.311948 -428.014672)
					(end 126.334266 -427.96079)
				)
				(arc
					(start 126.334266 -425.419266)
					(mid 126.311948 -425.365384)
					(end 126.258066 -425.343066)
				)
				(arc
					(start 125.318266 -425.343066)
					(mid 125.264384 -425.365384)
					(end 125.242066 -425.419266)
				)
			)
		)
	)
	(zone
		(layers "F.Cu" "In2.Cu" "In4.Cu" "In6.Cu" "In11.Cu" "In15.Cu")
		(hatch none 0.5)
		(connect_pads
			(clearance 0)
		)
		(min_thickness 0.25)
		(keepout
			(tracks not_allowed)
			(vias allowed)
			(pads allowed)
			(copperpour not_allowed)
			(footprints allowed)
		)
		(placement
			(enabled no)
			(sheetname "")
		)
		(fill yes
			(thermal_gap 0.5)
			(thermal_bridge_width 0.5)
			(island_removal_mode 0)
		)
		(polygon
			(pts
				(arc
					(start 133.24205 -427.96079)
					(mid 133.264368 -428.014672)
					(end 133.31825 -428.03699)
				)
				(arc
					(start 134.25805 -428.03699)
					(mid 134.311932 -428.014672)
					(end 134.33425 -427.96079)
				)
				(arc
					(start 134.33425 -425.419266)
					(mid 134.311932 -425.365384)
					(end 134.25805 -425.343066)
				)
				(arc
					(start 133.31825 -425.343066)
					(mid 133.264368 -425.365384)
					(end 133.24205 -425.419266)
				)
			)
		)
	)
	(zone
		(layers "F.Cu" "In2.Cu" "In4.Cu" "In6.Cu" "In11.Cu" "In15.Cu")
		(hatch none 0.5)
		(connect_pads
			(clearance 0)
		)
		(min_thickness 0.25)
		(keepout
			(tracks not_allowed)
			(vias allowed)
			(pads allowed)
			(copperpour not_allowed)
			(footprints allowed)
		)
		(placement
			(enabled no)
			(sheetname "")
		)
		(fill yes
			(thermal_gap 0.5)
			(thermal_bridge_width 0.5)
			(island_removal_mode 0)
		)
		(polygon
			(pts
				(arc
					(start 314.14212 -427.96079)
					(mid 314.164438 -428.014672)
					(end 314.21832 -428.03699)
				)
				(arc
					(start 315.15812 -428.03699)
					(mid 315.212002 -428.014672)
					(end 315.23432 -427.96079)
				)
				(arc
					(start 315.23432 -425.419266)
					(mid 315.212002 -425.365384)
					(end 315.15812 -425.343066)
				)
				(arc
					(start 314.21832 -425.343066)
					(mid 314.164438 -425.365384)
					(end 314.14212 -425.419266)
				)
			)
		)
	)
	(zone
		(layers "F.Cu" "In2.Cu" "In4.Cu" "In6.Cu" "In11.Cu" "In15.Cu")
		(hatch none 0.5)
		(connect_pads
			(clearance 0)
		)
		(min_thickness 0.25)
		(keepout
			(tracks not_allowed)
			(vias allowed)
			(pads allowed)
			(copperpour not_allowed)
			(footprints allowed)
		)
		(placement
			(enabled no)
			(sheetname "")
		)
		(fill yes
			(thermal_gap 0.5)
			(thermal_bridge_width 0.5)
			(island_removal_mode 0)
		)
		(polygon
			(pts
				(arc
					(start 62.142116 -427.96079)
					(mid 62.164434 -428.014672)
					(end 62.218316 -428.03699)
				)
				(arc
					(start 63.158116 -428.03699)
					(mid 63.211998 -428.014672)
					(end 63.234316 -427.96079)
				)
				(arc
					(start 63.234316 -425.419266)
					(mid 63.211998 -425.365384)
					(end 63.158116 -425.343066)
				)
				(arc
					(start 62.218316 -425.343066)
					(mid 62.164434 -425.365384)
					(end 62.142116 -425.419266)
				)
			)
		)
	)
	(zone
		(layers "F.Cu" "In2.Cu" "In4.Cu" "In6.Cu" "In11.Cu" "In15.Cu")
		(hatch none 0.5)
		(connect_pads
			(clearance 0)
		)
		(min_thickness 0.25)
		(keepout
			(tracks not_allowed)
			(vias allowed)
			(pads allowed)
			(copperpour not_allowed)
			(footprints allowed)
		)
		(placement
			(enabled no)
			(sheetname "")
		)
		(fill yes
			(thermal_gap 0.5)
			(thermal_bridge_width 0.5)
			(island_removal_mode 0)
		)
		(polygon
			(pts
				(arc
					(start 146.242024 -427.96079)
					(mid 146.264342 -428.014672)
					(end 146.318224 -428.03699)
				)
				(arc
					(start 147.258024 -428.03699)
					(mid 147.311906 -428.014672)
					(end 147.334224 -427.96079)
				)
				(arc
					(start 147.334224 -425.419266)
					(mid 147.311906 -425.365384)
					(end 147.258024 -425.343066)
				)
				(arc
					(start 146.318224 -425.343066)
					(mid 146.264342 -425.365384)
					(end 146.242024 -425.419266)
				)
			)
		)
	)
	(zone
		(layers "F.Cu" "In2.Cu" "In4.Cu" "In6.Cu" "In11.Cu" "In15.Cu")
		(hatch none 0.5)
		(connect_pads
			(clearance 0)
		)
		(min_thickness 0.25)
		(keepout
			(tracks not_allowed)
			(vias allowed)
			(pads allowed)
			(copperpour not_allowed)
			(footprints allowed)
		)
		(placement
			(enabled no)
			(sheetname "")
		)
		(fill yes
			(thermal_gap 0.5)
			(thermal_bridge_width 0.5)
			(island_removal_mode 0)
		)
		(polygon
			(pts
				(arc
					(start 322.142104 -427.96079)
					(mid 322.164422 -428.014672)
					(end 322.218304 -428.03699)
				)
				(arc
					(start 323.158104 -428.03699)
					(mid 323.211986 -428.014672)
					(end 323.234304 -427.96079)
				)
				(arc
					(start 323.234304 -425.419266)
					(mid 323.211986 -425.365384)
					(end 323.158104 -425.343066)
				)
				(arc
					(start 322.218304 -425.343066)
					(mid 322.164422 -425.365384)
					(end 322.142104 -425.419266)
				)
			)
		)
	)
	(zone
		(layers "F.Cu" "In2.Cu" "In4.Cu" "In6.Cu" "In11.Cu" "In15.Cu")
		(hatch none 0.5)
		(connect_pads
			(clearance 0)
		)
		(min_thickness 0.25)
		(keepout
			(tracks not_allowed)
			(vias allowed)
			(pads allowed)
			(copperpour not_allowed)
			(footprints allowed)
		)
		(placement
			(enabled no)
			(sheetname "")
		)
		(fill yes
			(thermal_gap 0.5)
			(thermal_bridge_width 0.5)
			(island_removal_mode 0)
		)
		(polygon
			(pts
				(arc
					(start 398.242028 -427.96079)
					(mid 398.264346 -428.014672)
					(end 398.318228 -428.03699)
				)
				(arc
					(start 399.258028 -428.03699)
					(mid 399.31191 -428.014672)
					(end 399.334228 -427.96079)
				)
				(arc
					(start 399.334228 -425.419266)
					(mid 399.31191 -425.365384)
					(end 399.258028 -425.343066)
				)
				(arc
					(start 398.318228 -425.343066)
					(mid 398.264346 -425.365384)
					(end 398.242028 -425.419266)
				)
			)
		)
	)
	(zone
		(layers "F.Cu" "In2.Cu" "In4.Cu" "In6.Cu" "In11.Cu" "In15.Cu")
		(hatch none 0.5)
		(connect_pads
			(clearance 0)
		)
		(min_thickness 0.25)
		(keepout
			(tracks not_allowed)
			(vias allowed)
			(pads allowed)
			(copperpour not_allowed)
			(footprints allowed)
		)
		(placement
			(enabled no)
			(sheetname "")
		)
		(fill yes
			(thermal_gap 0.5)
			(thermal_bridge_width 0.5)
			(island_removal_mode 0)
		)
		(polygon
			(pts
				(arc
					(start 87.142066 -427.96079)
					(mid 87.164384 -428.014672)
					(end 87.218266 -428.03699)
				)
				(arc
					(start 88.158066 -428.03699)
					(mid 88.211948 -428.014672)
					(end 88.234266 -427.96079)
				)
				(arc
					(start 88.234266 -425.419266)
					(mid 88.211948 -425.365384)
					(end 88.158066 -425.343066)
				)
				(arc
					(start 87.218266 -425.343066)
					(mid 87.164384 -425.365384)
					(end 87.142066 -425.419266)
				)
			)
		)
	)
	(zone
		(layers "F.Cu" "In2.Cu" "In4.Cu" "In6.Cu" "In11.Cu" "In15.Cu")
		(hatch none 0.5)
		(connect_pads
			(clearance 0)
		)
		(min_thickness 0.25)
		(keepout
			(tracks not_allowed)
			(vias allowed)
			(pads allowed)
			(copperpour not_allowed)
			(footprints allowed)
		)
		(placement
			(enabled no)
			(sheetname "")
		)
		(fill yes
			(thermal_gap 0.5)
			(thermal_bridge_width 0.5)
			(island_removal_mode 0)
		)
		(polygon
			(pts
				(arc
					(start 58.142124 -427.96079)
					(mid 58.164442 -428.014672)
					(end 58.218324 -428.03699)
				)
				(arc
					(start 59.158124 -428.03699)
					(mid 59.212006 -428.014672)
					(end 59.234324 -427.96079)
				)
				(arc
					(start 59.234324 -425.419266)
					(mid 59.212006 -425.365384)
					(end 59.158124 -425.343066)
				)
				(arc
					(start 58.218324 -425.343066)
					(mid 58.164442 -425.365384)
					(end 58.142124 -425.419266)
				)
			)
		)
	)
	(zone
		(layers "F.Cu" "In2.Cu" "In4.Cu" "In6.Cu" "In11.Cu" "In15.Cu")
		(hatch none 0.5)
		(connect_pads
			(clearance 0)
		)
		(min_thickness 0.25)
		(keepout
			(tracks not_allowed)
			(vias allowed)
			(pads allowed)
			(copperpour not_allowed)
			(footprints allowed)
		)
		(placement
			(enabled no)
			(sheetname "")
		)
		(fill yes
			(thermal_gap 0.5)
			(thermal_bridge_width 0.5)
			(island_removal_mode 0)
		)
		(polygon
			(pts
				(arc
					(start 381.242062 -427.96079)
					(mid 381.26438 -428.014672)
					(end 381.318262 -428.03699)
				)
				(arc
					(start 382.258062 -428.03699)
					(mid 382.311944 -428.014672)
					(end 382.334262 -427.96079)
				)
				(arc
					(start 382.334262 -425.419266)
					(mid 382.311944 -425.365384)
					(end 382.258062 -425.343066)
				)
				(arc
					(start 381.318262 -425.343066)
					(mid 381.26438 -425.365384)
					(end 381.242062 -425.419266)
				)
			)
		)
	)
	(zone
		(layers "F.Cu" "In2.Cu" "In4.Cu" "In6.Cu" "In11.Cu" "In15.Cu")
		(hatch none 0.5)
		(connect_pads
			(clearance 0)
		)
		(min_thickness 0.25)
		(keepout
			(tracks not_allowed)
			(vias allowed)
			(pads allowed)
			(copperpour not_allowed)
			(footprints allowed)
		)
		(placement
			(enabled no)
			(sheetname "")
		)
		(fill yes
			(thermal_gap 0.5)
			(thermal_bridge_width 0.5)
			(island_removal_mode 0)
		)
		(polygon
			(pts
				(arc
					(start 129.242058 -427.96079)
					(mid 129.264376 -428.014672)
					(end 129.318258 -428.03699)
				)
				(arc
					(start 130.258058 -428.03699)
					(mid 130.31194 -428.014672)
					(end 130.334258 -427.96079)
				)
				(arc
					(start 130.334258 -425.419266)
					(mid 130.31194 -425.365384)
					(end 130.258058 -425.343066)
				)
				(arc
					(start 129.318258 -425.343066)
					(mid 129.264376 -425.365384)
					(end 129.242058 -425.419266)
				)
			)
		)
	)
	(zone
		(layers "F.Cu" "In2.Cu" "In4.Cu" "In6.Cu" "In11.Cu" "In15.Cu")
		(hatch none 0.5)
		(connect_pads
			(clearance 0)
		)
		(min_thickness 0.25)
		(keepout
			(tracks not_allowed)
			(vias allowed)
			(pads allowed)
			(copperpour not_allowed)
			(footprints allowed)
		)
		(placement
			(enabled no)
			(sheetname "")
		)
		(fill yes
			(thermal_gap 0.5)
			(thermal_bridge_width 0.5)
			(island_removal_mode 0)
		)
		(polygon
			(pts
				(arc
					(start 339.14207 -427.96079)
					(mid 339.164388 -428.014672)
					(end 339.21827 -428.03699)
				)
				(arc
					(start 340.15807 -428.03699)
					(mid 340.211952 -428.014672)
					(end 340.23427 -427.96079)
				)
				(arc
					(start 340.23427 -425.419266)
					(mid 340.211952 -425.365384)
					(end 340.15807 -425.343066)
				)
				(arc
					(start 339.21827 -425.343066)
					(mid 339.164388 -425.365384)
					(end 339.14207 -425.419266)
				)
			)
		)
	)
	(zone
		(layers "F.Cu" "In2.Cu" "In4.Cu" "In6.Cu" "In11.Cu" "In15.Cu")
		(hatch none 0.5)
		(connect_pads
			(clearance 0)
		)
		(min_thickness 0.25)
		(keepout
			(tracks not_allowed)
			(vias allowed)
			(pads allowed)
			(copperpour not_allowed)
			(footprints allowed)
		)
		(placement
			(enabled no)
			(sheetname "")
		)
		(fill yes
			(thermal_gap 0.5)
			(thermal_bridge_width 0.5)
			(island_removal_mode 0)
		)
		(polygon
			(pts
				(arc
					(start 83.142074 -427.96079)
					(mid 83.164392 -428.014672)
					(end 83.218274 -428.03699)
				)
				(arc
					(start 84.158074 -428.03699)
					(mid 84.211956 -428.014672)
					(end 84.234274 -427.96079)
				)
				(arc
					(start 84.234274 -425.419266)
					(mid 84.211956 -425.365384)
					(end 84.158074 -425.343066)
				)
				(arc
					(start 83.218274 -425.343066)
					(mid 83.164392 -425.365384)
					(end 83.142074 -425.419266)
				)
			)
		)
	)
	(zone
		(layers "F.Cu" "In2.Cu" "In4.Cu" "In6.Cu" "In11.Cu" "In15.Cu")
		(hatch none 0.5)
		(connect_pads
			(clearance 0)
		)
		(min_thickness 0.25)
		(keepout
			(tracks not_allowed)
			(vias allowed)
			(pads allowed)
			(copperpour not_allowed)
			(footprints allowed)
		)
		(placement
			(enabled no)
			(sheetname "")
		)
		(fill yes
			(thermal_gap 0.5)
			(thermal_bridge_width 0.5)
			(island_removal_mode 0)
		)
		(polygon
			(pts
				(arc
					(start 410.242004 -427.96079)
					(mid 410.264322 -428.014672)
					(end 410.318204 -428.03699)
				)
				(arc
					(start 411.258004 -428.03699)
					(mid 411.311886 -428.014672)
					(end 411.334204 -427.96079)
				)
				(arc
					(start 411.334204 -425.419266)
					(mid 411.311886 -425.365384)
					(end 411.258004 -425.343066)
				)
				(arc
					(start 410.318204 -425.343066)
					(mid 410.264322 -425.365384)
					(end 410.242004 -425.419266)
				)
			)
		)
	)
	(zone
		(layers "F.Cu" "In2.Cu" "In4.Cu" "In6.Cu" "In11.Cu" "In15.Cu")
		(hatch none 0.5)
		(connect_pads
			(clearance 0)
		)
		(min_thickness 0.25)
		(keepout
			(tracks not_allowed)
			(vias allowed)
			(pads allowed)
			(copperpour not_allowed)
			(footprints allowed)
		)
		(placement
			(enabled no)
			(sheetname "")
		)
		(fill yes
			(thermal_gap 0.5)
			(thermal_bridge_width 0.5)
			(island_removal_mode 0)
		)
		(polygon
			(pts
				(arc
					(start 406.242012 -427.96079)
					(mid 406.26433 -428.014672)
					(end 406.318212 -428.03699)
				)
				(arc
					(start 407.258012 -428.03699)
					(mid 407.311894 -428.014672)
					(end 407.334212 -427.96079)
				)
				(arc
					(start 407.334212 -425.419266)
					(mid 407.311894 -425.365384)
					(end 407.258012 -425.343066)
				)
				(arc
					(start 406.318212 -425.343066)
					(mid 406.26433 -425.365384)
					(end 406.242012 -425.419266)
				)
			)
		)
	)
	(zone
		(layers "F.Cu" "In2.Cu" "In4.Cu" "In6.Cu" "In11.Cu" "In15.Cu")
		(hatch none 0.5)
		(connect_pads
			(clearance 0)
		)
		(min_thickness 0.25)
		(keepout
			(tracks not_allowed)
			(vias allowed)
			(pads allowed)
			(copperpour not_allowed)
			(footprints allowed)
		)
		(placement
			(enabled no)
			(sheetname "")
		)
		(fill yes
			(thermal_gap 0.5)
			(thermal_bridge_width 0.5)
			(island_removal_mode 0)
		)
		(polygon
			(pts
				(arc
					(start 402.24202 -427.96079)
					(mid 402.264338 -428.014672)
					(end 402.31822 -428.03699)
				)
				(arc
					(start 403.25802 -428.03699)
					(mid 403.311902 -428.014672)
					(end 403.33422 -427.96079)
				)
				(arc
					(start 403.33422 -425.419266)
					(mid 403.311902 -425.365384)
					(end 403.25802 -425.343066)
				)
				(arc
					(start 402.31822 -425.343066)
					(mid 402.264338 -425.365384)
					(end 402.24202 -425.419266)
				)
			)
		)
	)
	(zone
		(layers "F.Cu" "In2.Cu" "In4.Cu" "In6.Cu" "In11.Cu" "In15.Cu")
		(hatch none 0.5)
		(connect_pads
			(clearance 0)
		)
		(min_thickness 0.25)
		(keepout
			(tracks not_allowed)
			(vias allowed)
			(pads allowed)
			(copperpour not_allowed)
			(footprints allowed)
		)
		(placement
			(enabled no)
			(sheetname "")
		)
		(fill yes
			(thermal_gap 0.5)
			(thermal_bridge_width 0.5)
			(island_removal_mode 0)
		)
		(polygon
			(pts
				(arc
					(start 331.142086 -427.96079)
					(mid 331.164404 -428.014672)
					(end 331.218286 -428.03699)
				)
				(arc
					(start 332.158086 -428.03699)
					(mid 332.211968 -428.014672)
					(end 332.234286 -427.96079)
				)
				(arc
					(start 332.234286 -425.419266)
					(mid 332.211968 -425.365384)
					(end 332.158086 -425.343066)
				)
				(arc
					(start 331.218286 -425.343066)
					(mid 331.164404 -425.365384)
					(end 331.142086 -425.419266)
				)
			)
		)
	)
	(zone
		(layers "F.Cu" "In2.Cu" "In4.Cu" "In6.Cu" "In11.Cu" "In15.Cu")
		(hatch none 0.5)
		(connect_pads
			(clearance 0)
		)
		(min_thickness 0.25)
		(keepout
			(tracks not_allowed)
			(vias allowed)
			(pads allowed)
			(copperpour not_allowed)
			(footprints allowed)
		)
		(placement
			(enabled no)
			(sheetname "")
		)
		(fill yes
			(thermal_gap 0.5)
			(thermal_bridge_width 0.5)
			(island_removal_mode 0)
		)
		(polygon
			(pts
				(arc
					(start 150.242016 -427.96079)
					(mid 150.264334 -428.014672)
					(end 150.318216 -428.03699)
				)
				(arc
					(start 151.258016 -428.03699)
					(mid 151.311898 -428.014672)
					(end 151.334216 -427.96079)
				)
				(arc
					(start 151.334216 -425.419266)
					(mid 151.311898 -425.365384)
					(end 151.258016 -425.343066)
				)
				(arc
					(start 150.318216 -425.343066)
					(mid 150.264334 -425.365384)
					(end 150.242016 -425.419266)
				)
			)
		)
	)
	(zone
		(layers "F.Cu" "In4.Cu" "In6.Cu" "In11.Cu" "In13.Cu" "In15.Cu")
		(hatch none 0.5)
		(connect_pads
			(clearance 0)
		)
		(min_thickness 0.25)
		(keepout
			(tracks not_allowed)
			(vias allowed)
			(pads allowed)
			(copperpour not_allowed)
			(footprints allowed)
		)
		(placement
			(enabled no)
			(sheetname "")
		)
		(fill yes
			(thermal_gap 0.5)
			(thermal_bridge_width 0.5)
			(island_removal_mode 0)
		)
		(polygon
			(pts
				(arc
					(start 154.242008 -431.560732)
					(mid 154.264326 -431.614614)
					(end 154.318208 -431.636932)
				)
				(arc
					(start 155.258008 -431.636932)
					(mid 155.31189 -431.614614)
					(end 155.334208 -431.560732)
				)
				(arc
					(start 155.334208 -429.019208)
					(mid 155.31189 -428.965326)
					(end 155.258008 -428.943008)
				)
				(arc
					(start 154.318208 -428.943008)
					(mid 154.264326 -428.965326)
					(end 154.242008 -429.019208)
				)
			)
		)
	)
	(zone
		(layers "F.Cu" "In4.Cu" "In6.Cu" "In11.Cu" "In13.Cu" "In15.Cu")
		(hatch none 0.5)
		(connect_pads
			(clearance 0)
		)
		(min_thickness 0.25)
		(keepout
			(tracks not_allowed)
			(vias allowed)
			(pads allowed)
			(copperpour not_allowed)
			(footprints allowed)
		)
		(placement
			(enabled no)
			(sheetname "")
		)
		(fill yes
			(thermal_gap 0.5)
			(thermal_bridge_width 0.5)
			(island_removal_mode 0)
		)
		(polygon
			(pts
				(arc
					(start 156.242004 -432.56073)
					(mid 156.264322 -432.614612)
					(end 156.318204 -432.63693)
				)
				(arc
					(start 157.258004 -432.63693)
					(mid 157.311886 -432.614612)
					(end 157.334204 -432.56073)
				)
				(arc
					(start 157.334204 -430.019206)
					(mid 157.311886 -429.965324)
					(end 157.258004 -429.943006)
				)
				(arc
					(start 156.318204 -429.943006)
					(mid 156.264322 -429.965324)
					(end 156.242004 -430.019206)
				)
			)
		)
	)
	(zone
		(layers "F.Cu" "In4.Cu" "In6.Cu" "In11.Cu" "In13.Cu" "In15.Cu")
		(hatch none 0.5)
		(connect_pads
			(clearance 0)
		)
		(min_thickness 0.25)
		(keepout
			(tracks not_allowed)
			(vias allowed)
			(pads allowed)
			(copperpour not_allowed)
			(footprints allowed)
		)
		(placement
			(enabled no)
			(sheetname "")
		)
		(fill yes
			(thermal_gap 0.5)
			(thermal_bridge_width 0.5)
			(island_removal_mode 0)
		)
		(polygon
			(pts
				(arc
					(start 156.242004 -436.160672)
					(mid 156.264322 -436.214554)
					(end 156.318204 -436.236872)
				)
				(arc
					(start 157.258004 -436.236872)
					(mid 157.311886 -436.214554)
					(end 157.334204 -436.160672)
				)
				(arc
					(start 157.334204 -433.619148)
					(mid 157.311886 -433.565266)
					(end 157.258004 -433.542948)
				)
				(arc
					(start 156.318204 -433.542948)
					(mid 156.264322 -433.565266)
					(end 156.242004 -433.619148)
				)
			)
		)
	)
	(zone
		(layers "F.Cu" "In4.Cu" "In6.Cu" "In11.Cu" "In13.Cu" "In15.Cu")
		(hatch none 0.5)
		(connect_pads
			(clearance 0)
		)
		(min_thickness 0.25)
		(keepout
			(tracks not_allowed)
			(vias allowed)
			(pads allowed)
			(copperpour not_allowed)
			(footprints allowed)
		)
		(placement
			(enabled no)
			(sheetname "")
		)
		(fill yes
			(thermal_gap 0.5)
			(thermal_bridge_width 0.5)
			(island_removal_mode 0)
		)
		(polygon
			(pts
				(arc
					(start 154.242008 -435.160674)
					(mid 154.264326 -435.214556)
					(end 154.318208 -435.236874)
				)
				(arc
					(start 155.258008 -435.236874)
					(mid 155.31189 -435.214556)
					(end 155.334208 -435.160674)
				)
				(arc
					(start 155.334208 -432.61915)
					(mid 155.31189 -432.565268)
					(end 155.258008 -432.54295)
				)
				(arc
					(start 154.318208 -432.54295)
					(mid 154.264326 -432.565268)
					(end 154.242008 -432.61915)
				)
			)
		)
	)
	(zone
		(layers "F.Cu" "In4.Cu" "In6.Cu" "In11.Cu" "In15.Cu")
		(hatch none 0.5)
		(connect_pads
			(clearance 0)
		)
		(min_thickness 0.25)
		(keepout
			(tracks not_allowed)
			(vias allowed)
			(pads allowed)
			(copperpour not_allowed)
			(footprints allowed)
		)
		(placement
			(enabled no)
			(sheetname "")
		)
		(fill yes
			(thermal_gap 0.5)
			(thermal_bridge_width 0.5)
			(island_removal_mode 0)
		)
		(polygon
			(pts
				(arc
					(start 154.242008 -427.96079)
					(mid 154.264326 -428.014672)
					(end 154.318208 -428.03699)
				)
				(arc
					(start 155.258008 -428.03699)
					(mid 155.31189 -428.014672)
					(end 155.334208 -427.96079)
				)
				(arc
					(start 155.334208 -425.419266)
					(mid 155.31189 -425.365384)
					(end 155.258008 -425.343066)
				)
				(arc
					(start 154.318208 -425.343066)
					(mid 154.264326 -425.365384)
					(end 154.242008 -425.419266)
				)
			)
		)
	)
	(zone
		(layer "B.Cu")
		(hatch none 0.5)
		(connect_pads
			(clearance 0)
		)
		(min_thickness 0.25)
		(keepout
			(tracks not_allowed)
			(vias allowed)
			(pads allowed)
			(copperpour not_allowed)
			(footprints allowed)
		)
		(placement
			(enabled no)
			(sheetname "")
		)
		(fill
			(thermal_gap 0.5)
			(thermal_bridge_width 0.5)
			(island_removal_mode 0)
		)
		(polygon
			(pts
				(arc
					(start 10.199878 -435.600094)
					(mid 12.999974 -438.40019)
					(end 15.80007 -435.600094)
				)
				(arc
					(start 15.80007 -435.600094)
					(mid 12.999974 -432.799998)
					(end 10.199878 -435.600094)
				)
			)
		)
	)
	(zone
		(layer "B.Cu")
		(hatch none 0.5)
		(connect_pads
			(clearance 0)
		)
		(min_thickness 0.25)
		(keepout
			(tracks not_allowed)
			(vias allowed)
			(pads allowed)
			(copperpour not_allowed)
			(footprints allowed)
		)
		(placement
			(enabled no)
			(sheetname "")
		)
		(fill
			(thermal_gap 0.5)
			(thermal_bridge_width 0.5)
			(island_removal_mode 0)
		)
		(polygon
			(pts
				(arc
					(start 313.99988 -68.449952)
					(mid 316.900052 -71.350124)
					(end 319.79997 -68.449952)
				)
				(arc
					(start 319.79997 -68.449952)
					(mid 316.900052 -65.550034)
					(end 313.99988 -68.449952)
				)
			)
		)
	)
	(zone
		(layer "B.Cu")
		(hatch none 0.5)
		(connect_pads
			(clearance 0)
		)
		(min_thickness 0.25)
		(keepout
			(tracks allowed)
			(vias allowed)
			(pads allowed)
			(copperpour allowed)
			(footprints not_allowed)
		)
		(placement
			(enabled no)
			(sheetname "")
		)
		(fill
			(thermal_gap 0.5)
			(thermal_bridge_width 0.5)
			(island_removal_mode 0)
		)
		(polygon
			(pts
				(arc
					(start 33.344358 -70.411086)
					(mid 45.0632 -87.2612)
					(end 56.7817 -70.411086)
				)
				(arc
					(start 56.7817 -70.411086)
					(mid 45.0632 -53.56121)
					(end 33.344358 -70.411086)
				)
			)
		)
	)
	(zone
		(layer "B.Cu")
		(hatch none 0.5)
		(connect_pads
			(clearance 0)
		)
		(min_thickness 0.25)
		(keepout
			(tracks allowed)
			(vias allowed)
			(pads allowed)
			(copperpour allowed)
			(footprints allowed)
		)
		(placement
			(enabled no)
			(sheetname "")
		)
		(fill
			(thermal_gap 0.5)
			(thermal_bridge_width 0.5)
			(island_removal_mode 0)
		)
		(polygon
			(pts
				(xy 37.24656 -192.860168) (xy 37.24656 -192.187068) (xy 38.2778 -192.187068) (xy 38.2778 -192.860168)
			)
		)
	)
	(zone
		(layer "B.Cu")
		(hatch none 0.5)
		(connect_pads
			(clearance 0)
		)
		(min_thickness 0.25)
		(keepout
			(tracks allowed)
			(vias allowed)
			(pads allowed)
			(copperpour allowed)
			(footprints allowed)
		)
		(placement
			(enabled no)
			(sheetname "")
		)
		(fill
			(thermal_gap 0.5)
			(thermal_bridge_width 0.5)
			(island_removal_mode 0)
		)
		(polygon
			(pts
				(xy 167.095424 -47.47133) (xy 168.050464 -47.47133) (xy 168.050464 -49.352454) (xy 167.095424 -49.352454)
			)
		)
	)
	(zone
		(layer "B.Cu")
		(hatch none 0.5)
		(connect_pads
			(clearance 0)
		)
		(min_thickness 0.25)
		(keepout
			(tracks allowed)
			(vias allowed)
			(pads allowed)
			(copperpour allowed)
			(footprints not_allowed)
		)
		(placement
			(enabled no)
			(sheetname "")
		)
		(fill
			(thermal_gap 0.5)
			(thermal_bridge_width 0.5)
			(island_removal_mode 0)
		)
		(polygon
			(pts
				(xy 407.640028 -239.860074) (xy 462.639918 -239.860074) (xy 462.639918 -202.360022) (xy 407.640028 -202.360022)
			)
		)
	)
	(zone
		(layer "B.Cu")
		(hatch none 0.5)
		(connect_pads
			(clearance 0)
		)
		(min_thickness 0.25)
		(keepout
			(tracks not_allowed)
			(vias allowed)
			(pads allowed)
			(copperpour not_allowed)
			(footprints allowed)
		)
		(placement
			(enabled no)
			(sheetname "")
		)
		(fill
			(thermal_gap 0.5)
			(thermal_bridge_width 0.5)
			(island_removal_mode 0)
		)
		(polygon
			(pts
				(arc
					(start 377.9012 -400.858228)
					(mid 377.19762 -400.858228)
					(end 377.9012 -400.858228)
				)
			)
		)
	)
	(zone
		(layer "B.Cu")
		(hatch none 0.5)
		(connect_pads
			(clearance 0)
		)
		(min_thickness 0.25)
		(keepout
			(tracks allowed)
			(vias allowed)
			(pads allowed)
			(copperpour allowed)
			(footprints not_allowed)
		)
		(placement
			(enabled no)
			(sheetname "")
		)
		(fill
			(thermal_gap 0.5)
			(thermal_bridge_width 0.5)
			(island_removal_mode 0)
		)
		(polygon
			(pts
				(arc
					(start 215.674956 -360.764074)
					(mid 213.67496 -358.764078)
					(end 211.674964 -360.764074)
				)
				(arc
					(start 211.674964 -360.764074)
					(mid 213.67496 -362.76407)
					(end 215.674956 -360.764074)
				)
			)
		)
	)
	(zone
		(layer "B.Cu")
		(hatch none 0.5)
		(connect_pads
			(clearance 0)
		)
		(min_thickness 0.25)
		(keepout
			(tracks not_allowed)
			(vias allowed)
			(pads allowed)
			(copperpour not_allowed)
			(footprints allowed)
		)
		(placement
			(enabled no)
			(sheetname "")
		)
		(fill
			(thermal_gap 0.5)
			(thermal_bridge_width 0.5)
			(island_removal_mode 0)
		)
		(polygon
			(pts
				(arc
					(start 334.110838 -407.00452)
					(mid 333.407258 -407.00452)
					(end 334.110838 -407.00452)
				)
			)
		)
	)
	(zone
		(layer "B.Cu")
		(hatch none 0.5)
		(connect_pads
			(clearance 0)
		)
		(min_thickness 0.25)
		(keepout
			(tracks not_allowed)
			(vias allowed)
			(pads allowed)
			(copperpour not_allowed)
			(footprints allowed)
		)
		(placement
			(enabled no)
			(sheetname "")
		)
		(fill
			(thermal_gap 0.5)
			(thermal_bridge_width 0.5)
			(island_removal_mode 0)
		)
		(polygon
			(pts
				(arc
					(start 94.110556 -224.389442)
					(mid 93.457776 -224.389442)
					(end 94.110556 -224.389442)
				)
			)
		)
	)
	(zone
		(layer "B.Cu")
		(hatch none 0.5)
		(connect_pads
			(clearance 0)
		)
		(min_thickness 0.25)
		(keepout
			(tracks not_allowed)
			(vias allowed)
			(pads allowed)
			(copperpour not_allowed)
			(footprints allowed)
		)
		(placement
			(enabled no)
			(sheetname "")
		)
		(fill
			(thermal_gap 0.5)
			(thermal_bridge_width 0.5)
			(island_removal_mode 0)
		)
		(polygon
			(pts
				(arc
					(start 102.098602 -223.575626)
					(mid 101.445822 -223.575626)
					(end 102.098602 -223.575626)
				)
			)
		)
	)
	(zone
		(layer "B.Cu")
		(hatch none 0.5)
		(connect_pads
			(clearance 0)
		)
		(min_thickness 0.25)
		(keepout
			(tracks allowed)
			(vias allowed)
			(pads allowed)
			(copperpour allowed)
			(footprints not_allowed)
		)
		(placement
			(enabled no)
			(sheetname "")
		)
		(fill
			(thermal_gap 0.5)
			(thermal_bridge_width 0.5)
			(island_removal_mode 0)
		)
		(polygon
			(pts
				(xy 7.500112 -96.19996) (xy 2.999994 -96.19996)
				(arc
					(start 2.999994 -157.318202)
					(mid 4.815159 -154.714185)
					(end 7.500112 -153.02103)
				)
			)
		)
	)
	(zone
		(layer "B.Cu")
		(hatch none 0.5)
		(connect_pads
			(clearance 0)
		)
		(min_thickness 0.25)
		(keepout
			(tracks allowed)
			(vias allowed)
			(pads allowed)
			(copperpour allowed)
			(footprints not_allowed)
		)
		(placement
			(enabled no)
			(sheetname "")
		)
		(fill
			(thermal_gap 0.5)
			(thermal_bridge_width 0.5)
			(island_removal_mode 0)
		)
		(polygon
			(pts
				(arc
					(start 456.460098 -347.700092)
					(mid 461.460088 -352.700082)
					(end 466.460078 -347.700092)
				)
				(arc
					(start 466.460078 -347.700092)
					(mid 461.460088 -342.700102)
					(end 456.460098 -347.700092)
				)
			)
		)
	)
	(zone
		(layer "B.Cu")
		(hatch none 0.5)
		(connect_pads
			(clearance 0)
		)
		(min_thickness 0.25)
		(keepout
			(tracks not_allowed)
			(vias allowed)
			(pads allowed)
			(copperpour not_allowed)
			(footprints allowed)
		)
		(placement
			(enabled no)
			(sheetname "")
		)
		(fill
			(thermal_gap 0.5)
			(thermal_bridge_width 0.5)
			(island_removal_mode 0)
		)
		(polygon
			(pts
				(arc
					(start 127.943356 -224.389442)
					(mid 127.290576 -224.389442)
					(end 127.943356 -224.389442)
				)
			)
		)
	)
	(zone
		(layer "B.Cu")
		(hatch none 0.5)
		(connect_pads
			(clearance 0)
		)
		(min_thickness 0.25)
		(keepout
			(tracks allowed)
			(vias allowed)
			(pads allowed)
			(copperpour allowed)
			(footprints allowed)
		)
		(placement
			(enabled no)
			(sheetname "")
		)
		(fill
			(thermal_gap 0.5)
			(thermal_bridge_width 0.5)
			(island_removal_mode 0)
		)
		(polygon
			(pts
				(xy 186.113674 -21.60016) (xy 186.113674 -20.9423) (xy 187.731654 -20.9423) (xy 187.731654 -21.60016)
			)
		)
	)
	(zone
		(layer "B.Cu")
		(hatch none 0.5)
		(connect_pads
			(clearance 0)
		)
		(min_thickness 0.25)
		(keepout
			(tracks allowed)
			(vias allowed)
			(pads allowed)
			(copperpour allowed)
			(footprints allowed)
		)
		(placement
			(enabled no)
			(sheetname "")
		)
		(fill
			(thermal_gap 0.5)
			(thermal_bridge_width 0.5)
			(island_removal_mode 0)
		)
		(polygon
			(pts
				(xy 359.633266 -361.924092) (xy 359.633266 -354.911152) (xy 362.724446 -354.911152) (xy 362.724446 -361.924092)
			)
		)
	)
	(zone
		(layer "B.Cu")
		(hatch none 0.5)
		(connect_pads
			(clearance 0)
		)
		(min_thickness 0.25)
		(keepout
			(tracks allowed)
			(vias allowed)
			(pads allowed)
			(copperpour allowed)
			(footprints allowed)
		)
		(placement
			(enabled no)
			(sheetname "")
		)
		(fill
			(thermal_gap 0.5)
			(thermal_bridge_width 0.5)
			(island_removal_mode 0)
		)
		(polygon
			(pts
				(xy 180.85308 -51.8287) (xy 180.85308 -50.93208) (xy 183.0197 -50.93208) (xy 183.0197 -51.8287)
			)
		)
	)
	(zone
		(layer "B.Cu")
		(hatch none 0.5)
		(connect_pads
			(clearance 0)
		)
		(min_thickness 0.25)
		(keepout
			(tracks not_allowed)
			(vias allowed)
			(pads allowed)
			(copperpour not_allowed)
			(footprints allowed)
		)
		(placement
			(enabled no)
			(sheetname "")
		)
		(fill
			(thermal_gap 0.5)
			(thermal_bridge_width 0.5)
			(island_removal_mode 0)
		)
		(polygon
			(pts
				(arc
					(start 358.041956 -46.802802)
					(mid 357.338376 -46.802802)
					(end 358.041956 -46.802802)
				)
			)
		)
	)
	(zone
		(layer "B.Cu")
		(hatch none 0.5)
		(connect_pads
			(clearance 0)
		)
		(min_thickness 0.25)
		(keepout
			(tracks allowed)
			(vias allowed)
			(pads allowed)
			(copperpour allowed)
			(footprints not_allowed)
		)
		(placement
			(enabled no)
			(sheetname "")
		)
		(fill
			(thermal_gap 0.5)
			(thermal_bridge_width 0.5)
			(island_removal_mode 0)
		)
		(polygon
			(pts
				(arc
					(start 7.53999 -160.50006)
					(mid 10.340086 -163.300156)
					(end 13.139928 -160.50006)
				)
				(arc
					(start 13.139928 -160.50006)
					(mid 10.340086 -157.700218)
					(end 7.53999 -160.50006)
				)
			)
		)
	)
	(zone
		(layer "B.Cu")
		(hatch none 0.5)
		(connect_pads
			(clearance 0)
		)
		(min_thickness 0.25)
		(keepout
			(tracks allowed)
			(vias allowed)
			(pads allowed)
			(copperpour allowed)
			(footprints allowed)
		)
		(placement
			(enabled no)
			(sheetname "")
		)
		(fill
			(thermal_gap 0.5)
			(thermal_bridge_width 0.5)
			(island_removal_mode 0)
		)
		(polygon
			(pts
				(xy 158.32836 -45.58538) (xy 158.32836 -43.14952) (xy 159.92602 -43.14952) (xy 159.92602 -45.58538)
			)
		)
	)
	(zone
		(layer "B.Cu")
		(hatch none 0.5)
		(connect_pads
			(clearance 0)
		)
		(min_thickness 0.25)
		(keepout
			(tracks not_allowed)
			(vias allowed)
			(pads allowed)
			(copperpour not_allowed)
			(footprints allowed)
		)
		(placement
			(enabled no)
			(sheetname "")
		)
		(fill
			(thermal_gap 0.5)
			(thermal_bridge_width 0.5)
			(island_removal_mode 0)
		)
		(polygon
			(pts
				(arc
					(start 399.34388 -400.858228)
					(mid 398.6403 -400.858228)
					(end 399.34388 -400.858228)
				)
			)
		)
	)
	(zone
		(layer "B.Cu")
		(hatch none 0.5)
		(connect_pads
			(clearance 0)
		)
		(min_thickness 0.25)
		(keepout
			(tracks allowed)
			(vias allowed)
			(pads allowed)
			(copperpour allowed)
			(footprints not_allowed)
		)
		(placement
			(enabled no)
			(sheetname "")
		)
		(fill
			(thermal_gap 0.5)
			(thermal_bridge_width 0.5)
			(island_removal_mode 0)
		)
		(polygon
			(pts
				(xy 462.639918 -273.02206) (xy 407.640028 -273.02206) (xy 407.640028 -310.522112) (xy 462.639918 -310.522112)
			)
		)
	)
	(zone
		(layer "B.Cu")
		(hatch none 0.5)
		(connect_pads
			(clearance 0)
		)
		(min_thickness 0.25)
		(keepout
			(tracks allowed)
			(vias allowed)
			(pads allowed)
			(copperpour allowed)
			(footprints allowed)
		)
		(placement
			(enabled no)
			(sheetname "")
		)
		(fill
			(thermal_gap 0.5)
			(thermal_bridge_width 0.5)
			(island_removal_mode 0)
		)
		(polygon
			(pts
				(xy 416.85464 -366.591088) (xy 416.85464 -363.492288) (xy 412.48838 -363.492288) (xy 412.48838 -366.591088)
			)
		)
	)
	(zone
		(layer "B.Cu")
		(hatch none 0.5)
		(connect_pads
			(clearance 0)
		)
		(min_thickness 0.25)
		(keepout
			(tracks not_allowed)
			(vias allowed)
			(pads allowed)
			(copperpour not_allowed)
			(footprints allowed)
		)
		(placement
			(enabled no)
			(sheetname "")
		)
		(fill
			(thermal_gap 0.5)
			(thermal_bridge_width 0.5)
			(island_removal_mode 0)
		)
		(polygon
			(pts
				(arc
					(start 68.482972 -47.049944)
					(mid 70.382892 -48.949864)
					(end 72.282812 -47.049944)
				)
				(arc
					(start 72.282812 -47.049944)
					(mid 70.382892 -45.150024)
					(end 68.482972 -47.049944)
				)
			)
		)
	)
	(zone
		(layer "B.Cu")
		(hatch none 0.5)
		(connect_pads
			(clearance 0)
		)
		(min_thickness 0.25)
		(keepout
			(tracks not_allowed)
			(vias allowed)
			(pads allowed)
			(copperpour not_allowed)
			(footprints allowed)
		)
		(placement
			(enabled no)
			(sheetname "")
		)
		(fill
			(thermal_gap 0.5)
			(thermal_bridge_width 0.5)
			(island_removal_mode 0)
		)
		(polygon
			(pts
				(arc
					(start 124.184156 -224.389442)
					(mid 123.531376 -224.389442)
					(end 124.184156 -224.389442)
				)
			)
		)
	)
	(zone
		(layer "B.Cu")
		(hatch none 0.5)
		(connect_pads
			(clearance 0)
		)
		(min_thickness 0.25)
		(keepout
			(tracks not_allowed)
			(vias allowed)
			(pads allowed)
			(copperpour not_allowed)
			(footprints allowed)
		)
		(placement
			(enabled no)
			(sheetname "")
		)
		(fill
			(thermal_gap 0.5)
			(thermal_bridge_width 0.5)
			(island_removal_mode 0)
		)
		(polygon
			(pts
				(arc
					(start 97.399602 -225.203258)
					(mid 96.746822 -225.203258)
					(end 97.399602 -225.203258)
				)
			)
		)
	)
	(zone
		(layer "B.Cu")
		(hatch none 0.5)
		(connect_pads
			(clearance 0)
		)
		(min_thickness 0.25)
		(keepout
			(tracks not_allowed)
			(vias allowed)
			(pads allowed)
			(copperpour not_allowed)
			(footprints allowed)
		)
		(placement
			(enabled no)
			(sheetname "")
		)
		(fill
			(thermal_gap 0.5)
			(thermal_bridge_width 0.5)
			(island_removal_mode 0)
		)
		(polygon
			(pts
				(arc
					(start 73.054972 -419.88994)
					(mid 72.24522 -419.88994)
					(end 73.054972 -419.88994)
				)
			)
		)
	)
	(zone
		(layer "B.Cu")
		(hatch none 0.5)
		(connect_pads
			(clearance 0)
		)
		(min_thickness 0.25)
		(keepout
			(tracks not_allowed)
			(vias allowed)
			(pads allowed)
			(copperpour not_allowed)
			(footprints allowed)
		)
		(placement
			(enabled no)
			(sheetname "")
		)
		(fill
			(thermal_gap 0.5)
			(thermal_bridge_width 0.5)
			(island_removal_mode 0)
		)
		(polygon
			(pts
				(arc
					(start 103.508556 -224.389442)
					(mid 102.855776 -224.389442)
					(end 103.508556 -224.389442)
				)
			)
		)
	)
	(zone
		(layer "B.Cu")
		(hatch none 0.5)
		(connect_pads
			(clearance 0)
		)
		(min_thickness 0.25)
		(keepout
			(tracks allowed)
			(vias allowed)
			(pads allowed)
			(copperpour allowed)
			(footprints not_allowed)
		)
		(placement
			(enabled no)
			(sheetname "")
		)
		(fill
			(thermal_gap 0.5)
			(thermal_bridge_width 0.5)
			(island_removal_mode 0)
		)
		(polygon
			(pts
				(arc
					(start 277.804118 -440.989974)
					(mid 277.309907 -440.047498)
					(end 276.314916 -439.669936)
				)
				(arc
					(start 195.50507 -439.669936)
					(mid 194.51003 -440.047443)
					(end 194.015868 -440.989974)
				)
				(arc
					(start 191.02832 -440.989974)
					(mid 191.960705 -432.926163)
					(end 187.743592 -425.990004)
				)
				(arc
					(start 282.677108 -425.990004)
					(mid 283.479968 -426.614315)
					(end 284.35554 -427.131734)
				)
				(arc
					(start 284.35554 -427.131734)
					(mid 281.188939 -433.741375)
					(end 282.271724 -440.989974)
				)
			)
		)
	)
	(zone
		(layer "B.Cu")
		(hatch none 0.5)
		(connect_pads
			(clearance 0)
		)
		(min_thickness 0.25)
		(keepout
			(tracks allowed)
			(vias allowed)
			(pads allowed)
			(copperpour allowed)
			(footprints allowed)
		)
		(placement
			(enabled no)
			(sheetname "")
		)
		(fill
			(thermal_gap 0.5)
			(thermal_bridge_width 0.5)
			(island_removal_mode 0)
		)
		(polygon
			(pts
				(xy 419.13302 -152.314148) (xy 419.13302 -157.912308) (xy 419.80612 -158.585408) (xy 423.24274 -158.585408)
				(xy 425.26204 -156.566108) (xy 425.26204 -153.347928) (xy 423.60342 -151.689308) (xy 419.75786 -151.689308)
			)
		)
	)
	(zone
		(layer "B.Cu")
		(hatch none 0.5)
		(connect_pads
			(clearance 0)
		)
		(min_thickness 0.25)
		(keepout
			(tracks not_allowed)
			(vias allowed)
			(pads allowed)
			(copperpour not_allowed)
			(footprints allowed)
		)
		(placement
			(enabled no)
			(sheetname "")
		)
		(fill
			(thermal_gap 0.5)
			(thermal_bridge_width 0.5)
			(island_removal_mode 0)
		)
		(polygon
			(pts
				(arc
					(start 134.521956 -224.389442)
					(mid 133.869176 -224.389442)
					(end 134.521956 -224.389442)
				)
			)
		)
	)
	(zone
		(layer "B.Cu")
		(hatch none 0.5)
		(connect_pads
			(clearance 0)
		)
		(min_thickness 0.25)
		(keepout
			(tracks not_allowed)
			(vias allowed)
			(pads allowed)
			(copperpour not_allowed)
			(footprints allowed)
		)
		(placement
			(enabled no)
			(sheetname "")
		)
		(fill
			(thermal_gap 0.5)
			(thermal_bridge_width 0.5)
			(island_removal_mode 0)
		)
		(polygon
			(pts
				(arc
					(start 379.642624 -224.389442)
					(mid 378.989844 -224.389442)
					(end 379.642624 -224.389442)
				)
			)
		)
	)
	(zone
		(layer "B.Cu")
		(hatch none 0.5)
		(connect_pads
			(clearance 0)
		)
		(min_thickness 0.25)
		(keepout
			(tracks allowed)
			(vias allowed)
			(pads allowed)
			(copperpour allowed)
			(footprints allowed)
		)
		(placement
			(enabled no)
			(sheetname "")
		)
		(fill
			(thermal_gap 0.5)
			(thermal_bridge_width 0.5)
			(island_removal_mode 0)
		)
		(polygon
			(pts
				(xy 356.16896 -338.960968) (xy 356.16896 -335.280508) (xy 371.221 -335.280508) (xy 371.221 -338.960968)
			)
		)
	)
	(zone
		(layer "B.Cu")
		(hatch none 0.5)
		(connect_pads
			(clearance 0)
		)
		(min_thickness 0.25)
		(keepout
			(tracks allowed)
			(vias allowed)
			(pads allowed)
			(copperpour allowed)
			(footprints not_allowed)
		)
		(placement
			(enabled no)
			(sheetname "")
		)
		(fill
			(thermal_gap 0.5)
			(thermal_bridge_width 0.5)
			(island_removal_mode 0)
		)
		(polygon
			(pts
				(xy 214.769954 -239.860074) (xy 214.769954 -202.360022) (xy 159.770064 -202.360022) (xy 159.770064 -239.860074)
			)
		)
	)
	(zone
		(layer "B.Cu")
		(hatch none 0.5)
		(connect_pads
			(clearance 0)
		)
		(min_thickness 0.25)
		(keepout
			(tracks allowed)
			(vias allowed)
			(pads allowed)
			(copperpour allowed)
			(footprints allowed)
		)
		(placement
			(enabled no)
			(sheetname "")
		)
		(fill
			(thermal_gap 0.5)
			(thermal_bridge_width 0.5)
			(island_removal_mode 0)
		)
		(polygon
			(pts
				(xy 995.207306 -554.343316) (xy 995.207306 -544.782756) (xy 995.832146 -544.157916) (xy 1002.649506 -544.157916)
				(xy 1003.962686 -542.844736) (xy 1006.065806 -542.844736) (xy 1006.906546 -543.685476) (xy 1009.245886 -543.685476)
				(xy 1009.718326 -544.157916) (xy 1010.272046 -544.711636) (xy 1010.272046 -559.263296) (xy 1009.040146 -560.495196)
				(xy 995.946446 -560.495196) (xy 994.793286 -559.342036) (xy 994.793286 -556.868076) (xy 995.105706 -556.555656)
				(xy 995.207306 -556.454056)
			)
		)
	)
	(zone
		(layer "B.Cu")
		(hatch none 0.5)
		(connect_pads
			(clearance 0)
		)
		(min_thickness 0.25)
		(keepout
			(tracks allowed)
			(vias allowed)
			(pads allowed)
			(copperpour allowed)
			(footprints allowed)
		)
		(placement
			(enabled no)
			(sheetname "")
		)
		(fill
			(thermal_gap 0.5)
			(thermal_bridge_width 0.5)
			(island_removal_mode 0)
		)
		(polygon
			(pts
				(xy 135.41756 -11.96848) (xy 135.41756 -10.70102) (xy 134.1882 -10.70102) (xy 134.1882 -11.96848)
			)
		)
	)
	(zone
		(layer "B.Cu")
		(hatch none 0.5)
		(connect_pads
			(clearance 0)
		)
		(min_thickness 0.25)
		(keepout
			(tracks not_allowed)
			(vias allowed)
			(pads allowed)
			(copperpour not_allowed)
			(footprints allowed)
		)
		(placement
			(enabled no)
			(sheetname "")
		)
		(fill
			(thermal_gap 0.5)
			(thermal_bridge_width 0.5)
			(island_removal_mode 0)
		)
		(polygon
			(pts
				(arc
					(start 19.749516 -382.893824)
					(mid 19.045936 -382.893824)
					(end 19.749516 -382.893824)
				)
			)
		)
	)
	(zone
		(layer "B.Cu")
		(hatch none 0.5)
		(connect_pads
			(clearance 0)
		)
		(min_thickness 0.25)
		(keepout
			(tracks allowed)
			(vias allowed)
			(pads allowed)
			(copperpour allowed)
			(footprints allowed)
		)
		(placement
			(enabled no)
			(sheetname "")
		)
		(fill
			(thermal_gap 0.5)
			(thermal_bridge_width 0.5)
			(island_removal_mode 0)
		)
		(polygon
			(pts
				(xy 911.718014 -85.467444) (xy 925.898834 -85.467444) (xy 926.406834 -85.975444) (xy 929.137334 -85.975444)
				(xy 929.645334 -85.467444) (xy 931.192194 -83.920584) (xy 931.192194 -76.427584) (xy 931.806874 -75.812904)
				(xy 931.806874 -66.219324) (xy 930.407334 -64.819784) (xy 927.219634 -64.819784) (xy 912.302214 -64.819784)
				(xy 911.636734 -65.485264) (xy 911.636734 -67.618864) (xy 912.198074 -68.180204) (xy 912.198074 -69.300344)
				(xy 911.636734 -69.861684) (xy 911.636734 -76.280264) (xy 910.173694 -77.743304) (xy 910.173694 -82.201004)
				(xy 910.209254 -82.201004) (xy 910.836634 -82.828384) (xy 910.836634 -84.586064)
			)
		)
	)
	(zone
		(layer "B.Cu")
		(hatch none 0.5)
		(connect_pads
			(clearance 0)
		)
		(min_thickness 0.25)
		(keepout
			(tracks allowed)
			(vias allowed)
			(pads allowed)
			(copperpour allowed)
			(footprints not_allowed)
		)
		(placement
			(enabled no)
			(sheetname "")
		)
		(fill
			(thermal_gap 0.5)
			(thermal_bridge_width 0.5)
			(island_removal_mode 0)
		)
		(polygon
			(pts
				(arc
					(start 456.460098 -160.50006)
					(mid 461.460088 -165.50005)
					(end 466.460078 -160.50006)
				)
				(arc
					(start 466.460078 -160.50006)
					(mid 461.460088 -155.50007)
					(end 456.460098 -160.50006)
				)
			)
		)
	)
	(zone
		(layer "B.Cu")
		(hatch none 0.5)
		(connect_pads
			(clearance 0)
		)
		(min_thickness 0.25)
		(keepout
			(tracks not_allowed)
			(vias allowed)
			(pads allowed)
			(copperpour not_allowed)
			(footprints allowed)
		)
		(placement
			(enabled no)
			(sheetname "")
		)
		(fill
			(thermal_gap 0.5)
			(thermal_bridge_width 0.5)
			(island_removal_mode 0)
		)
		(polygon
			(pts
				(arc
					(start 324.921118 -407.00452)
					(mid 324.217538 -407.00452)
					(end 324.921118 -407.00452)
				)
			)
		)
	)
	(zone
		(layer "B.Cu")
		(hatch none 0.5)
		(connect_pads
			(clearance 0)
		)
		(min_thickness 0.25)
		(keepout
			(tracks allowed)
			(vias allowed)
			(pads allowed)
			(copperpour allowed)
			(footprints not_allowed)
		)
		(placement
			(enabled no)
			(sheetname "")
		)
		(fill
			(thermal_gap 0.5)
			(thermal_bridge_width 0.5)
			(island_removal_mode 0)
		)
		(polygon
			(pts
				(arc
					(start 245.632478 -361.192826)
					(mid 269.790783 -365.253451)
					(end 249.142758 -352.071178)
				)
				(arc
					(start 249.142758 -352.071178)
					(mid 235.632129 -340.041597)
					(end 224.253298 -354.104702)
				)
				(arc
					(start 224.253298 -354.104702)
					(mid 201.913199 -364.995997)
					(end 226.071684 -359.159302)
				)
				(arc
					(start 226.071684 -359.159302)
					(mid 235.357543 -364.932869)
					(end 245.632478 -361.192826)
				)
			)
		)
	)
	(zone
		(layer "B.Cu")
		(hatch none 0.5)
		(connect_pads
			(clearance 0)
		)
		(min_thickness 0.25)
		(keepout
			(tracks allowed)
			(vias allowed)
			(pads allowed)
			(copperpour allowed)
			(footprints allowed)
		)
		(placement
			(enabled no)
			(sheetname "")
		)
		(fill
			(thermal_gap 0.5)
			(thermal_bridge_width 0.5)
			(island_removal_mode 0)
		)
		(polygon
			(pts
				(xy 129.3876 -28.7274) (xy 129.3876 -27.75204) (xy 130.6449 -27.75204) (xy 130.6449 -28.7274)
			)
		)
	)
	(zone
		(layer "B.Cu")
		(hatch none 0.5)
		(connect_pads
			(clearance 0)
		)
		(min_thickness 0.25)
		(keepout
			(tracks allowed)
			(vias allowed)
			(pads allowed)
			(copperpour allowed)
			(footprints allowed)
		)
		(placement
			(enabled no)
			(sheetname "")
		)
		(fill
			(thermal_gap 0.5)
			(thermal_bridge_width 0.5)
			(island_removal_mode 0)
		)
		(polygon
			(pts
				(xy 21.544788 -184.517284) (xy 21.544788 -184.094374) (xy 22.7838 -184.094374) (xy 22.7838 -184.517284)
			)
		)
	)
	(zone
		(layer "B.Cu")
		(hatch none 0.5)
		(connect_pads
			(clearance 0)
		)
		(min_thickness 0.25)
		(keepout
			(tracks not_allowed)
			(vias allowed)
			(pads allowed)
			(copperpour not_allowed)
			(footprints allowed)
		)
		(placement
			(enabled no)
			(sheetname "")
		)
		(fill
			(thermal_gap 0.5)
			(thermal_bridge_width 0.5)
			(island_removal_mode 0)
		)
		(polygon
			(pts
				(arc
					(start 415.52368 -400.858228)
					(mid 414.8201 -400.858228)
					(end 415.52368 -400.858228)
				)
			)
		)
	)
	(zone
		(layer "B.Cu")
		(hatch none 0.5)
		(connect_pads
			(clearance 0)
		)
		(min_thickness 0.25)
		(keepout
			(tracks allowed)
			(vias allowed)
			(pads allowed)
			(copperpour allowed)
			(footprints allowed)
		)
		(placement
			(enabled no)
			(sheetname "")
		)
		(fill
			(thermal_gap 0.5)
			(thermal_bridge_width 0.5)
			(island_removal_mode 0)
		)
		(polygon
			(pts
				(xy 138.67384 -347.421708) (xy 138.67384 -343.408508) (xy 133.16458 -343.408508) (xy 133.16458 -347.421708)
			)
		)
	)
	(zone
		(layer "B.Cu")
		(hatch none 0.5)
		(connect_pads
			(clearance 0)
		)
		(min_thickness 0.25)
		(keepout
			(tracks not_allowed)
			(vias allowed)
			(pads allowed)
			(copperpour not_allowed)
			(footprints allowed)
		)
		(placement
			(enabled no)
			(sheetname "")
		)
		(fill
			(thermal_gap 0.5)
			(thermal_bridge_width 0.5)
			(island_removal_mode 0)
		)
		(polygon
			(pts
				(arc
					(start 166.455344 -400.858228)
					(mid 165.751764 -400.858228)
					(end 166.455344 -400.858228)
				)
			)
		)
	)
	(zone
		(layer "B.Cu")
		(hatch none 0.5)
		(connect_pads
			(clearance 0)
		)
		(min_thickness 0.25)
		(keepout
			(tracks allowed)
			(vias allowed)
			(pads allowed)
			(copperpour allowed)
			(footprints not_allowed)
		)
		(placement
			(enabled no)
			(sheetname "")
		)
		(fill
			(thermal_gap 0.5)
			(thermal_bridge_width 0.5)
			(island_removal_mode 0)
		)
		(polygon
			(pts
				(arc
					(start 469.799924 -22.29993)
					(mid 464.799934 -17.29994)
					(end 459.799944 -22.29993)
				)
				(arc
					(start 459.799944 -22.29993)
					(mid 464.799934 -27.29992)
					(end 469.799924 -22.29993)
				)
			)
		)
	)
	(zone
		(layer "B.Cu")
		(hatch none 0.5)
		(connect_pads
			(clearance 0)
		)
		(min_thickness 0.25)
		(keepout
			(tracks not_allowed)
			(vias allowed)
			(pads allowed)
			(copperpour not_allowed)
			(footprints allowed)
		)
		(placement
			(enabled no)
			(sheetname "")
		)
		(fill
			(thermal_gap 0.5)
			(thermal_bridge_width 0.5)
			(island_removal_mode 0)
		)
		(polygon
			(pts
				(arc
					(start 95.990156 -224.389442)
					(mid 95.337376 -224.389442)
					(end 95.990156 -224.389442)
				)
			)
		)
	)
	(zone
		(layer "B.Cu")
		(hatch none 0.5)
		(connect_pads
			(clearance 0)
		)
		(min_thickness 0.25)
		(keepout
			(tracks allowed)
			(vias allowed)
			(pads allowed)
			(copperpour allowed)
			(footprints not_allowed)
		)
		(placement
			(enabled no)
			(sheetname "")
		)
		(fill
			(thermal_gap 0.5)
			(thermal_bridge_width 0.5)
			(island_removal_mode 0)
		)
		(polygon
			(pts
				(arc
					(start 231.650032 -352.49993)
					(mid 236.650022 -357.49992)
					(end 241.650012 -352.49993)
				)
				(arc
					(start 241.650012 -352.49993)
					(mid 236.650022 -347.49994)
					(end 231.650032 -352.49993)
				)
			)
		)
	)
	(zone
		(layer "B.Cu")
		(hatch none 0.5)
		(connect_pads
			(clearance 0)
		)
		(min_thickness 0.25)
		(keepout
			(tracks not_allowed)
			(vias allowed)
			(pads allowed)
			(copperpour not_allowed)
			(footprints allowed)
		)
		(placement
			(enabled no)
			(sheetname "")
		)
		(fill
			(thermal_gap 0.5)
			(thermal_bridge_width 0.5)
			(island_removal_mode 0)
		)
		(polygon
			(pts
				(arc
					(start 134.991856 -225.203258)
					(mid 134.339076 -225.203258)
					(end 134.991856 -225.203258)
				)
			)
		)
	)
	(zone
		(layer "B.Cu")
		(hatch none 0.5)
		(connect_pads
			(clearance 0)
		)
		(min_thickness 0.25)
		(keepout
			(tracks allowed)
			(vias allowed)
			(pads allowed)
			(copperpour allowed)
			(footprints not_allowed)
		)
		(placement
			(enabled no)
			(sheetname "")
		)
		(fill
			(thermal_gap 0.5)
			(thermal_bridge_width 0.5)
			(island_removal_mode 0)
		)
		(polygon
			(pts
				(arc
					(start 199.64527 -51.999896)
					(mid 204.64526 -56.999886)
					(end 209.64525 -51.999896)
				)
				(arc
					(start 209.64525 -51.999896)
					(mid 204.64526 -46.999906)
					(end 199.64527 -51.999896)
				)
			)
		)
	)
	(zone
		(layer "B.Cu")
		(hatch none 0.5)
		(connect_pads
			(clearance 0)
		)
		(min_thickness 0.25)
		(keepout
			(tracks not_allowed)
			(vias allowed)
			(pads allowed)
			(copperpour not_allowed)
			(footprints allowed)
		)
		(placement
			(enabled no)
			(sheetname "")
		)
		(fill
			(thermal_gap 0.5)
			(thermal_bridge_width 0.5)
			(island_removal_mode 0)
		)
		(polygon
			(pts
				(arc
					(start 7.999984 -435.600094)
					(mid 12.999974 -440.600084)
					(end 17.999964 -435.600094)
				)
				(arc
					(start 17.999964 -435.600094)
					(mid 12.999974 -430.600104)
					(end 7.999984 -435.600094)
				)
			)
		)
	)
	(zone
		(layer "B.Cu")
		(hatch none 0.5)
		(connect_pads
			(clearance 0)
		)
		(min_thickness 0.25)
		(keepout
			(tracks allowed)
			(vias allowed)
			(pads allowed)
			(copperpour allowed)
			(footprints not_allowed)
		)
		(placement
			(enabled no)
			(sheetname "")
		)
		(fill
			(thermal_gap 0.5)
			(thermal_bridge_width 0.5)
			(island_removal_mode 0)
		)
		(polygon
			(pts
				(arc
					(start 101.03485 -208.88706)
					(mid 99.974282 -209.326362)
					(end 99.53498 -210.38693)
				)
				(arc
					(start 99.53498 -211.676996)
					(mid 99.974177 -212.737818)
					(end 101.03485 -213.17712)
				)
				(arc
					(start 122.825002 -213.17712)
					(mid 123.88566 -212.737728)
					(end 124.324872 -211.676996)
				)
				(arc
					(start 124.324872 -210.38693)
					(mid 123.88557 -209.326362)
					(end 122.825002 -208.88706)
				)
			)
		)
	)
	(zone
		(layer "B.Cu")
		(hatch none 0.5)
		(connect_pads
			(clearance 0)
		)
		(min_thickness 0.25)
		(keepout
			(tracks allowed)
			(vias allowed)
			(pads allowed)
			(copperpour allowed)
			(footprints not_allowed)
		)
		(placement
			(enabled no)
			(sheetname "")
		)
		(fill
			(thermal_gap 0.5)
			(thermal_bridge_width 0.5)
			(island_removal_mode 0)
		)
		(polygon
			(pts
				(arc
					(start 209.674968 -360.764074)
					(mid 213.67496 -364.764066)
					(end 217.674952 -360.764074)
				)
				(arc
					(start 217.674952 -360.764074)
					(mid 213.67496 -356.764082)
					(end 209.674968 -360.764074)
				)
			)
		)
	)
	(zone
		(layer "B.Cu")
		(hatch none 0.5)
		(connect_pads
			(clearance 0)
		)
		(min_thickness 0.25)
		(keepout
			(tracks allowed)
			(vias allowed)
			(pads allowed)
			(copperpour allowed)
			(footprints allowed)
		)
		(placement
			(enabled no)
			(sheetname "")
		)
		(fill
			(thermal_gap 0.5)
			(thermal_bridge_width 0.5)
			(island_removal_mode 0)
		)
		(polygon
			(pts
				(xy 181.98846 -358.107488) (xy 181.98846 -355.435408) (xy 177.96764 -355.435408) (xy 177.96764 -358.107488)
			)
		)
	)
	(zone
		(layer "B.Cu")
		(hatch none 0.5)
		(connect_pads
			(clearance 0)
		)
		(min_thickness 0.25)
		(keepout
			(tracks allowed)
			(vias allowed)
			(pads allowed)
			(copperpour allowed)
			(footprints allowed)
		)
		(placement
			(enabled no)
			(sheetname "")
		)
		(fill
			(thermal_gap 0.5)
			(thermal_bridge_width 0.5)
			(island_removal_mode 0)
		)
		(polygon
			(pts
				(xy 46.65218 -309.984648) (xy 46.65218 -309.362348) (xy 47.27956 -309.362348) (xy 47.27956 -309.984648)
			)
		)
	)
	(zone
		(layer "B.Cu")
		(hatch none 0.5)
		(connect_pads
			(clearance 0)
		)
		(min_thickness 0.25)
		(keepout
			(tracks not_allowed)
			(vias allowed)
			(pads allowed)
			(copperpour not_allowed)
			(footprints allowed)
		)
		(placement
			(enabled no)
			(sheetname "")
		)
		(fill
			(thermal_gap 0.5)
			(thermal_bridge_width 0.5)
			(island_removal_mode 0)
		)
		(polygon
			(pts
				(arc
					(start 99.749356 -224.389442)
					(mid 99.096576 -224.389442)
					(end 99.749356 -224.389442)
				)
			)
		)
	)
	(zone
		(layer "B.Cu")
		(hatch none 0.5)
		(connect_pads
			(clearance 0)
		)
		(min_thickness 0.25)
		(keepout
			(tracks allowed)
			(vias allowed)
			(pads allowed)
			(copperpour allowed)
			(footprints not_allowed)
		)
		(placement
			(enabled no)
			(sheetname "")
		)
		(fill
			(thermal_gap 0.5)
			(thermal_bridge_width 0.5)
			(island_removal_mode 0)
		)
		(polygon
			(pts
				(arc
					(start 347.481906 -211.676996)
					(mid 347.921282 -212.737744)
					(end 348.98203 -213.17712)
				)
				(arc
					(start 370.771928 -213.17712)
					(mid 371.832676 -212.737744)
					(end 372.272052 -211.676996)
				)
				(arc
					(start 372.272052 -210.38693)
					(mid 371.832571 -209.326436)
					(end 370.771928 -208.88706)
				)
				(arc
					(start 348.98203 -208.88706)
					(mid 347.921372 -209.326346)
					(end 347.481906 -210.38693)
				)
			)
		)
	)
	(zone
		(layer "B.Cu")
		(hatch none 0.5)
		(connect_pads
			(clearance 0)
		)
		(min_thickness 0.25)
		(keepout
			(tracks allowed)
			(vias allowed)
			(pads allowed)
			(copperpour allowed)
			(footprints not_allowed)
		)
		(placement
			(enabled no)
			(sheetname "")
		)
		(fill
			(thermal_gap 0.5)
			(thermal_bridge_width 0.5)
			(island_removal_mode 0)
		)
		(polygon
			(pts
				(arc
					(start 467.300056 -336.648044)
					(mid 452.141145 -339.368891)
					(end 451.128892 -354.736908)
				)
				(arc
					(start 451.128892 -354.736908)
					(mid 452.927318 -369.277727)
					(end 467.300056 -372.121938)
				)
			)
		)
	)
	(zone
		(layer "B.Cu")
		(hatch none 0.5)
		(connect_pads
			(clearance 0)
		)
		(min_thickness 0.25)
		(keepout
			(tracks allowed)
			(vias allowed)
			(pads allowed)
			(copperpour allowed)
			(footprints allowed)
		)
		(placement
			(enabled no)
			(sheetname "")
		)
		(fill
			(thermal_gap 0.5)
			(thermal_bridge_width 0.5)
			(island_removal_mode 0)
		)
		(polygon
			(pts
				(xy 349.44812 -50.89398) (xy 349.44812 -49.91608) (xy 359.11282 -49.91608) (xy 359.11282 -50.89398)
			)
		)
	)
	(zone
		(layer "B.Cu")
		(hatch none 0.5)
		(connect_pads
			(clearance 0)
		)
		(min_thickness 0.25)
		(keepout
			(tracks allowed)
			(vias allowed)
			(pads allowed)
			(copperpour allowed)
			(footprints allowed)
		)
		(placement
			(enabled no)
			(sheetname "")
		)
		(fill
			(thermal_gap 0.5)
			(thermal_bridge_width 0.5)
			(island_removal_mode 0)
		)
		(polygon
			(pts
				(xy 348.06636 -368.569748) (xy 348.06636 -367.744248) (xy 346.22994 -367.744248) (xy 346.22994 -368.569748)
			)
		)
	)
	(zone
		(layer "B.Cu")
		(hatch none 0.5)
		(connect_pads
			(clearance 0)
		)
		(min_thickness 0.25)
		(keepout
			(tracks not_allowed)
			(vias allowed)
			(pads allowed)
			(copperpour not_allowed)
			(footprints allowed)
		)
		(placement
			(enabled no)
			(sheetname "")
		)
		(fill
			(thermal_gap 0.5)
			(thermal_bridge_width 0.5)
			(island_removal_mode 0)
		)
		(polygon
			(pts
				(arc
					(start 157.265624 -400.858228)
					(mid 156.562044 -400.858228)
					(end 157.265624 -400.858228)
				)
			)
		)
	)
	(zone
		(layer "B.Cu")
		(hatch none 0.5)
		(connect_pads
			(clearance 0)
		)
		(min_thickness 0.25)
		(keepout
			(tracks allowed)
			(vias allowed)
			(pads allowed)
			(copperpour allowed)
			(footprints allowed)
		)
		(placement
			(enabled no)
			(sheetname "")
		)
		(fill
			(thermal_gap 0.5)
			(thermal_bridge_width 0.5)
			(island_removal_mode 0)
		)
		(polygon
			(pts
				(xy 324.87616 -342.797892) (xy 326.21474 -342.797892) (xy 326.60844 -343.191592) (xy 326.60844 -345.406472)
				(xy 326.79894 -345.596972) (xy 330.34478 -345.596972) (xy 330.56068 -345.812872) (xy 330.56068 -347.974412)
				(xy 330.40066 -348.134432) (xy 324.96506 -348.134432) (xy 324.52056 -347.689932) (xy 324.52056 -343.153492)
			)
		)
	)
	(zone
		(layer "B.Cu")
		(hatch none 0.5)
		(connect_pads
			(clearance 0)
		)
		(min_thickness 0.25)
		(keepout
			(tracks allowed)
			(vias allowed)
			(pads allowed)
			(copperpour allowed)
			(footprints not_allowed)
		)
		(placement
			(enabled no)
			(sheetname "")
		)
		(fill
			(thermal_gap 0.5)
			(thermal_bridge_width 0.5)
			(island_removal_mode 0)
		)
		(polygon
			(pts
				(arc
					(start 453.799956 -435.600094)
					(mid 458.799946 -440.600084)
					(end 463.799936 -435.600094)
				)
				(arc
					(start 463.799936 -435.600094)
					(mid 458.799946 -430.600104)
					(end 453.799956 -435.600094)
				)
			)
		)
	)
	(zone
		(layer "B.Cu")
		(hatch none 0.5)
		(connect_pads
			(clearance 0)
		)
		(min_thickness 0.25)
		(keepout
			(tracks allowed)
			(vias allowed)
			(pads allowed)
			(copperpour allowed)
			(footprints not_allowed)
		)
		(placement
			(enabled no)
			(sheetname "")
		)
		(fill
			(thermal_gap 0.5)
			(thermal_bridge_width 0.5)
			(island_removal_mode 0)
		)
		(polygon
			(pts
				(arc
					(start 438.521602 -70.417944)
					(mid 426.803102 -53.568068)
					(end 415.08426 -70.417944)
				)
				(arc
					(start 415.08426 -70.417944)
					(mid 426.803102 -87.268058)
					(end 438.521602 -70.417944)
				)
			)
		)
	)
	(zone
		(layer "B.Cu")
		(hatch none 0.5)
		(connect_pads
			(clearance 0)
		)
		(min_thickness 0.25)
		(keepout
			(tracks allowed)
			(vias allowed)
			(pads allowed)
			(copperpour allowed)
			(footprints allowed)
		)
		(placement
			(enabled no)
			(sheetname "")
		)
		(fill
			(thermal_gap 0.5)
			(thermal_bridge_width 0.5)
			(island_removal_mode 0)
		)
		(polygon
			(pts
				(xy 37.824664 -353.428808) (xy 39.163244 -353.428808) (xy 39.556944 -353.822508) (xy 39.556944 -356.037388)
				(xy 39.747444 -356.227888) (xy 43.293284 -356.227888) (xy 43.509184 -356.443788) (xy 43.509184 -358.605328)
				(xy 43.349164 -358.765348) (xy 37.913564 -358.765348) (xy 37.469064 -358.320848) (xy 37.469064 -353.784408)
			)
		)
	)
	(zone
		(layer "B.Cu")
		(hatch none 0.5)
		(connect_pads
			(clearance 0)
		)
		(min_thickness 0.25)
		(keepout
			(tracks not_allowed)
			(vias allowed)
			(pads allowed)
			(copperpour not_allowed)
			(footprints allowed)
		)
		(placement
			(enabled no)
			(sheetname "")
		)
		(fill
			(thermal_gap 0.5)
			(thermal_bridge_width 0.5)
			(island_removal_mode 0)
		)
		(polygon
			(pts
				(arc
					(start 215.674956 -360.764074)
					(mid 213.67496 -358.764078)
					(end 211.674964 -360.764074)
				)
				(arc
					(start 211.674964 -360.764074)
					(mid 213.67496 -362.76407)
					(end 215.674956 -360.764074)
				)
			)
		)
	)
	(zone
		(layer "B.Cu")
		(hatch none 0.5)
		(connect_pads
			(clearance 0)
		)
		(min_thickness 0.25)
		(keepout
			(tracks not_allowed)
			(vias allowed)
			(pads allowed)
			(copperpour not_allowed)
			(footprints allowed)
		)
		(placement
			(enabled no)
			(sheetname "")
		)
		(fill
			(thermal_gap 0.5)
			(thermal_bridge_width 0.5)
			(island_removal_mode 0)
		)
		(polygon
			(pts
				(arc
					(start 179.36337 -52.481734)
					(mid 178.65979 -52.481734)
					(end 179.36337 -52.481734)
				)
			)
		)
	)
	(zone
		(layer "B.Cu")
		(hatch none 0.5)
		(connect_pads
			(clearance 0)
		)
		(min_thickness 0.25)
		(keepout
			(tracks allowed)
			(vias allowed)
			(pads allowed)
			(copperpour allowed)
			(footprints allowed)
		)
		(placement
			(enabled no)
			(sheetname "")
		)
		(fill
			(thermal_gap 0.5)
			(thermal_bridge_width 0.5)
			(island_removal_mode 0)
		)
		(polygon
			(pts
				(xy 123.86056 -19.94916) (xy 123.86056 -18.9738) (xy 125.70206 -18.9738) (xy 125.70206 -19.94916)
			)
		)
	)
	(zone
		(layer "B.Cu")
		(hatch none 0.5)
		(connect_pads
			(clearance 0)
		)
		(min_thickness 0.25)
		(keepout
			(tracks not_allowed)
			(vias allowed)
			(pads allowed)
			(copperpour not_allowed)
			(footprints allowed)
		)
		(placement
			(enabled no)
			(sheetname "")
		)
		(fill
			(thermal_gap 0.5)
			(thermal_bridge_width 0.5)
			(island_removal_mode 0)
		)
		(polygon
			(pts
				(arc
					(start 15.387066 -27.963368)
					(mid 13.126021 -28.047628)
					(end 13.210032 -30.308804)
				)
				(arc
					(start 14.38275 -31.397194)
					(mid 16.644175 -31.313052)
					(end 16.559784 -29.051758)
				)
			)
		)
	)
	(zone
		(layer "B.Cu")
		(hatch none 0.5)
		(connect_pads
			(clearance 0)
		)
		(min_thickness 0.25)
		(keepout
			(tracks not_allowed)
			(vias allowed)
			(pads allowed)
			(copperpour not_allowed)
			(footprints allowed)
		)
		(placement
			(enabled no)
			(sheetname "")
		)
		(fill
			(thermal_gap 0.5)
			(thermal_bridge_width 0.5)
			(island_removal_mode 0)
		)
		(polygon
			(pts
				(arc
					(start 345.809824 -224.389442)
					(mid 345.157044 -224.389442)
					(end 345.809824 -224.389442)
				)
			)
		)
	)
	(zone
		(layer "B.Cu")
		(hatch none 0.5)
		(connect_pads
			(clearance 0)
		)
		(min_thickness 0.25)
		(keepout
			(tracks not_allowed)
			(vias allowed)
			(pads allowed)
			(copperpour not_allowed)
			(footprints allowed)
		)
		(placement
			(enabled no)
			(sheetname "")
		)
		(fill
			(thermal_gap 0.5)
			(thermal_bridge_width 0.5)
			(island_removal_mode 0)
		)
		(polygon
			(pts
				(arc
					(start 344.39987 -223.575626)
					(mid 343.74709 -223.575626)
					(end 344.39987 -223.575626)
				)
			)
		)
	)
	(zone
		(layer "B.Cu")
		(hatch none 0.5)
		(connect_pads
			(clearance 0)
		)
		(min_thickness 0.25)
		(keepout
			(tracks not_allowed)
			(vias allowed)
			(pads allowed)
			(copperpour not_allowed)
			(footprints allowed)
		)
		(placement
			(enabled no)
			(sheetname "")
		)
		(fill
			(thermal_gap 0.5)
			(thermal_bridge_width 0.5)
			(island_removal_mode 0)
		)
		(polygon
			(pts
				(arc
					(start 127.003556 -224.389442)
					(mid 126.350776 -224.389442)
					(end 127.003556 -224.389442)
				)
			)
		)
	)
	(zone
		(layer "B.Cu")
		(hatch none 0.5)
		(connect_pads
			(clearance 0)
		)
		(min_thickness 0.25)
		(keepout
			(tracks allowed)
			(vias allowed)
			(pads allowed)
			(copperpour allowed)
			(footprints allowed)
		)
		(placement
			(enabled no)
			(sheetname "")
		)
		(fill
			(thermal_gap 0.5)
			(thermal_bridge_width 0.5)
			(island_removal_mode 0)
		)
		(polygon
			(pts
				(xy 50.15865 -165.78072) (xy 52.81803 -165.78072) (xy 53.12791 -165.47084) (xy 53.12791 -162.24758)
				(xy 53.47589 -161.8996) (xy 55.52567 -161.8996) (xy 55.96255 -161.46272) (xy 55.96255 -159.88792)
				(xy 55.20309 -159.12846) (xy 52.10429 -159.12846) (xy 52.01793 -159.21482) (xy 52.01793 -161.04108)
				(xy 51.85791 -161.2011) (xy 50.35931 -161.2011) (xy 50.01895 -161.54146) (xy 50.01895 -165.64102)
			)
		)
	)
	(zone
		(layer "B.Cu")
		(hatch none 0.5)
		(connect_pads
			(clearance 0)
		)
		(min_thickness 0.25)
		(keepout
			(tracks not_allowed)
			(vias allowed)
			(pads allowed)
			(copperpour not_allowed)
			(footprints allowed)
		)
		(placement
			(enabled no)
			(sheetname "")
		)
		(fill
			(thermal_gap 0.5)
			(thermal_bridge_width 0.5)
			(island_removal_mode 0)
		)
		(polygon
			(pts
				(arc
					(start 58.384948 -400.858228)
					(mid 57.681368 -400.858228)
					(end 58.384948 -400.858228)
				)
			)
		)
	)
	(zone
		(layer "B.Cu")
		(hatch none 0.5)
		(connect_pads
			(clearance 0)
		)
		(min_thickness 0.25)
		(keepout
			(tracks not_allowed)
			(vias allowed)
			(pads allowed)
			(copperpour not_allowed)
			(footprints allowed)
		)
		(placement
			(enabled no)
			(sheetname "")
		)
		(fill
			(thermal_gap 0.5)
			(thermal_bridge_width 0.5)
			(island_removal_mode 0)
		)
		(polygon
			(pts
				(arc
					(start 352.388424 -224.389442)
					(mid 351.735644 -224.389442)
					(end 352.388424 -224.389442)
				)
			)
		)
	)
	(zone
		(layer "B.Cu")
		(hatch none 0.5)
		(connect_pads
			(clearance 0)
		)
		(min_thickness 0.25)
		(keepout
			(tracks allowed)
			(vias allowed)
			(pads allowed)
			(copperpour allowed)
			(footprints not_allowed)
		)
		(placement
			(enabled no)
			(sheetname "")
		)
		(fill
			(thermal_gap 0.5)
			(thermal_bridge_width 0.5)
			(island_removal_mode 0)
		)
		(polygon
			(pts
				(arc
					(start 7.999984 -435.600094)
					(mid 12.999974 -440.600084)
					(end 17.999964 -435.600094)
				)
				(arc
					(start 17.999964 -435.600094)
					(mid 12.999974 -430.600104)
					(end 7.999984 -435.600094)
				)
			)
		)
	)
	(zone
		(layer "B.Cu")
		(hatch none 0.5)
		(connect_pads
			(clearance 0)
		)
		(min_thickness 0.25)
		(keepout
			(tracks not_allowed)
			(vias allowed)
			(pads allowed)
			(copperpour not_allowed)
			(footprints allowed)
		)
		(placement
			(enabled no)
			(sheetname "")
		)
		(fill
			(thermal_gap 0.5)
			(thermal_bridge_width 0.5)
			(island_removal_mode 0)
		)
		(polygon
			(pts
				(arc
					(start 366.29848 -435.59984)
					(mid 371.29847 -440.59983)
					(end 376.29846 -435.59984)
				)
				(arc
					(start 376.29846 -435.59984)
					(mid 371.29847 -430.59985)
					(end 366.29848 -435.59984)
				)
			)
		)
	)
	(zone
		(layer "B.Cu")
		(hatch none 0.5)
		(connect_pads
			(clearance 0)
		)
		(min_thickness 0.25)
		(keepout
			(tracks allowed)
			(vias allowed)
			(pads allowed)
			(copperpour allowed)
			(footprints allowed)
		)
		(placement
			(enabled no)
			(sheetname "")
		)
		(fill
			(thermal_gap 0.5)
			(thermal_bridge_width 0.5)
			(island_removal_mode 0)
		)
		(polygon
			(pts
				(xy 357.6955 -365.196628) (xy 357.6955 -363.014768) (xy 361.44962 -363.014768) (xy 361.44962 -365.196628)
			)
		)
	)
	(zone
		(layer "B.Cu")
		(hatch none 0.5)
		(connect_pads
			(clearance 0)
		)
		(min_thickness 0.25)
		(keepout
			(tracks allowed)
			(vias allowed)
			(pads allowed)
			(copperpour allowed)
			(footprints allowed)
		)
		(placement
			(enabled no)
			(sheetname "")
		)
		(fill
			(thermal_gap 0.5)
			(thermal_bridge_width 0.5)
			(island_removal_mode 0)
		)
		(polygon
			(pts
				(xy 338.99602 -66.942208) (xy 338.99602 -65.959228) (xy 340.64448 -65.959228) (xy 340.64448 -66.942208)
			)
		)
	)
	(zone
		(layer "B.Cu")
		(hatch none 0.5)
		(connect_pads
			(clearance 0)
		)
		(min_thickness 0.25)
		(keepout
			(tracks allowed)
			(vias allowed)
			(pads allowed)
			(copperpour allowed)
			(footprints allowed)
		)
		(placement
			(enabled no)
			(sheetname "")
		)
		(fill
			(thermal_gap 0.5)
			(thermal_bridge_width 0.5)
			(island_removal_mode 0)
		)
		(polygon
			(pts
				(xy 911.718014 -85.467444) (xy 914.514808 -85.467444) (xy 917.200096 -88.152732) (xy 918.638498 -88.152732)
				(xy 919.114748 -87.676482) (xy 920.815786 -85.975444) (xy 926.406834 -85.975444) (xy 929.137334 -85.975444)
				(xy 929.645334 -85.467444) (xy 931.192194 -83.920584) (xy 931.192194 -76.427584) (xy 931.806874 -75.812904)
				(xy 931.806874 -66.219324) (xy 930.407334 -64.819784) (xy 927.219634 -64.819784) (xy 912.302214 -64.819784)
				(xy 911.636734 -65.485264) (xy 911.636734 -67.618864) (xy 912.198074 -68.180204) (xy 912.198074 -69.300344)
				(xy 911.636734 -69.861684) (xy 911.636734 -76.280264) (xy 910.173694 -77.743304) (xy 910.173694 -82.201004)
				(xy 910.209254 -82.201004) (xy 910.836634 -82.828384) (xy 910.836634 -84.586064)
			)
		)
	)
	(zone
		(layer "B.Cu")
		(hatch none 0.5)
		(connect_pads
			(clearance 0)
		)
		(min_thickness 0.25)
		(keepout
			(tracks not_allowed)
			(vias allowed)
			(pads allowed)
			(copperpour not_allowed)
			(footprints allowed)
		)
		(placement
			(enabled no)
			(sheetname "")
		)
		(fill
			(thermal_gap 0.5)
			(thermal_bridge_width 0.5)
			(island_removal_mode 0)
		)
		(polygon
			(pts
				(arc
					(start 127.473202 -225.203258)
					(mid 126.820422 -225.203258)
					(end 127.473202 -225.203258)
				)
			)
		)
	)
	(zone
		(layer "B.Cu")
		(hatch none 0.5)
		(connect_pads
			(clearance 0)
		)
		(min_thickness 0.25)
		(keepout
			(tracks not_allowed)
			(vias allowed)
			(pads allowed)
			(copperpour not_allowed)
			(footprints allowed)
		)
		(placement
			(enabled no)
			(sheetname "")
		)
		(fill
			(thermal_gap 0.5)
			(thermal_bridge_width 0.5)
			(island_removal_mode 0)
		)
		(polygon
			(pts
				(arc
					(start 265.895328 -51.999896)
					(mid 268.645386 -54.749954)
					(end 271.395444 -51.999896)
				)
				(arc
					(start 271.395444 -51.999896)
					(mid 268.645386 -49.249838)
					(end 265.895328 -51.999896)
				)
			)
		)
	)
	(zone
		(layer "B.Cu")
		(hatch none 0.5)
		(connect_pads
			(clearance 0)
		)
		(min_thickness 0.25)
		(keepout
			(tracks not_allowed)
			(vias allowed)
			(pads allowed)
			(copperpour not_allowed)
			(footprints allowed)
		)
		(placement
			(enabled no)
			(sheetname "")
		)
		(fill
			(thermal_gap 0.5)
			(thermal_bridge_width 0.5)
			(island_removal_mode 0)
		)
		(polygon
			(pts
				(arc
					(start 372.63832 -400.858228)
					(mid 371.93474 -400.858228)
					(end 372.63832 -400.858228)
				)
			)
		)
	)
	(zone
		(layer "B.Cu")
		(hatch none 0.5)
		(connect_pads
			(clearance 0)
		)
		(min_thickness 0.25)
		(keepout
			(tracks not_allowed)
			(vias allowed)
			(pads allowed)
			(copperpour not_allowed)
			(footprints allowed)
		)
		(placement
			(enabled no)
			(sheetname "")
		)
		(fill
			(thermal_gap 0.5)
			(thermal_bridge_width 0.5)
			(island_removal_mode 0)
		)
		(polygon
			(pts
				(arc
					(start 121.364756 -224.389442)
					(mid 120.711976 -224.389442)
					(end 121.364756 -224.389442)
				)
			)
		)
	)
	(zone
		(layer "B.Cu")
		(hatch none 0.5)
		(connect_pads
			(clearance 0)
		)
		(min_thickness 0.25)
		(keepout
			(tracks allowed)
			(vias allowed)
			(pads allowed)
			(copperpour allowed)
			(footprints allowed)
		)
		(placement
			(enabled no)
			(sheetname "")
		)
		(fill
			(thermal_gap 0.5)
			(thermal_bridge_width 0.5)
			(island_removal_mode 0)
		)
		(polygon
			(pts
				(xy 130.66014 -24.48306) (xy 130.66014 -23.33498) (xy 131.70662 -23.33498) (xy 131.70662 -24.48306)
			)
		)
	)
	(zone
		(layer "B.Cu")
		(hatch none 0.5)
		(connect_pads
			(clearance 0)
		)
		(min_thickness 0.25)
		(keepout
			(tracks allowed)
			(vias allowed)
			(pads allowed)
			(copperpour allowed)
			(footprints not_allowed)
		)
		(placement
			(enabled no)
			(sheetname "")
		)
		(fill
			(thermal_gap 0.5)
			(thermal_bridge_width 0.5)
			(island_removal_mode 0)
		)
		(polygon
			(pts
				(arc
					(start 232.225596 -37.343588)
					(mid 221.352268 -47.777528)
					(end 236.374432 -46.581568)
				)
				(arc
					(start 236.374432 -46.581568)
					(mid 245.438573 -45.245329)
					(end 247.303798 -36.27501)
				)
				(arc
					(start 232.596182 -36.27501)
					(mid 232.391979 -36.802741)
					(end 232.225596 -37.343588)
				)
			)
		)
	)
	(zone
		(layer "B.Cu")
		(hatch none 0.5)
		(connect_pads
			(clearance 0)
		)
		(min_thickness 0.25)
		(keepout
			(tracks not_allowed)
			(vias allowed)
			(pads allowed)
			(copperpour not_allowed)
			(footprints allowed)
		)
		(placement
			(enabled no)
			(sheetname "")
		)
		(fill
			(thermal_gap 0.5)
			(thermal_bridge_width 0.5)
			(island_removal_mode 0)
		)
		(polygon
			(pts
				(arc
					(start 290.079938 -419.999922)
					(mid 287.98012 -417.900104)
					(end 285.880048 -419.999922)
				)
				(arc
					(start 285.880048 -419.999922)
					(mid 287.98012 -422.099994)
					(end 290.079938 -419.999922)
				)
			)
		)
	)
	(zone
		(layer "B.Cu")
		(hatch none 0.5)
		(connect_pads
			(clearance 0)
		)
		(min_thickness 0.25)
		(keepout
			(tracks not_allowed)
			(vias allowed)
			(pads allowed)
			(copperpour not_allowed)
			(footprints allowed)
		)
		(placement
			(enabled no)
			(sheetname "")
		)
		(fill
			(thermal_gap 0.5)
			(thermal_bridge_width 0.5)
			(island_removal_mode 0)
		)
		(polygon
			(pts
				(arc
					(start 312.668158 -407.00452)
					(mid 311.964578 -407.00452)
					(end 312.668158 -407.00452)
				)
			)
		)
	)
	(zone
		(layer "B.Cu")
		(hatch none 0.5)
		(connect_pads
			(clearance 0)
		)
		(min_thickness 0.25)
		(keepout
			(tracks not_allowed)
			(vias allowed)
			(pads allowed)
			(copperpour not_allowed)
			(footprints allowed)
		)
		(placement
			(enabled no)
			(sheetname "")
		)
		(fill
			(thermal_gap 0.5)
			(thermal_bridge_width 0.5)
			(island_removal_mode 0)
		)
		(polygon
			(pts
				(arc
					(start 95.143828 -400.858228)
					(mid 94.440248 -400.858228)
					(end 95.143828 -400.858228)
				)
			)
		)
	)
	(zone
		(layer "B.Cu")
		(hatch none 0.5)
		(connect_pads
			(clearance 0)
		)
		(min_thickness 0.25)
		(keepout
			(tracks allowed)
			(vias allowed)
			(pads allowed)
			(copperpour allowed)
			(footprints allowed)
		)
		(placement
			(enabled no)
			(sheetname "")
		)
		(fill
			(thermal_gap 0.5)
			(thermal_bridge_width 0.5)
			(island_removal_mode 0)
		)
		(polygon
			(pts
				(xy 390.11098 -26.49728) (xy 390.11098 -24.9428) (xy 388.21614 -24.9428) (xy 388.21614 -26.49728)
			)
		)
	)
	(zone
		(layer "B.Cu")
		(hatch none 0.5)
		(connect_pads
			(clearance 0)
		)
		(min_thickness 0.25)
		(keepout
			(tracks allowed)
			(vias allowed)
			(pads allowed)
			(copperpour allowed)
			(footprints allowed)
		)
		(placement
			(enabled no)
			(sheetname "")
		)
		(fill
			(thermal_gap 0.5)
			(thermal_bridge_width 0.5)
			(island_removal_mode 0)
		)
		(polygon
			(pts
				(xy 137.5283 -20.09394) (xy 137.5283 -19.4437) (xy 138.83894 -19.4437) (xy 138.83894 -20.09394)
			)
		)
	)
	(zone
		(layer "B.Cu")
		(hatch none 0.5)
		(connect_pads
			(clearance 0)
		)
		(min_thickness 0.25)
		(keepout
			(tracks allowed)
			(vias allowed)
			(pads allowed)
			(copperpour allowed)
			(footprints allowed)
		)
		(placement
			(enabled no)
			(sheetname "")
		)
		(fill
			(thermal_gap 0.5)
			(thermal_bridge_width 0.5)
			(island_removal_mode 0)
		)
		(polygon
			(pts
				(xy 122.29084 -338.191348) (xy 122.29084 -334.167988) (xy 115.74272 -334.167988) (xy 115.74272 -338.191348)
			)
		)
	)
	(zone
		(layer "B.Cu")
		(hatch none 0.5)
		(connect_pads
			(clearance 0)
		)
		(min_thickness 0.25)
		(keepout
			(tracks not_allowed)
			(vias allowed)
			(pads allowed)
			(copperpour not_allowed)
			(footprints allowed)
		)
		(placement
			(enabled no)
			(sheetname "")
		)
		(fill
			(thermal_gap 0.5)
			(thermal_bridge_width 0.5)
			(island_removal_mode 0)
		)
		(polygon
			(pts
				(arc
					(start 72.837548 -400.858228)
					(mid 72.133968 -400.858228)
					(end 72.837548 -400.858228)
				)
			)
		)
	)
	(zone
		(layer "B.Cu")
		(hatch none 0.5)
		(connect_pads
			(clearance 0)
		)
		(min_thickness 0.25)
		(keepout
			(tracks not_allowed)
			(vias allowed)
			(pads allowed)
			(copperpour not_allowed)
			(footprints allowed)
		)
		(placement
			(enabled no)
			(sheetname "")
		)
		(fill
			(thermal_gap 0.5)
			(thermal_bridge_width 0.5)
			(island_removal_mode 0)
		)
		(polygon
			(pts
				(arc
					(start 103.47325 -411.213808)
					(mid 102.76967 -411.213808)
					(end 103.47325 -411.213808)
				)
			)
		)
	)
	(zone
		(layer "B.Cu")
		(hatch none 0.5)
		(connect_pads
			(clearance 0)
		)
		(min_thickness 0.25)
		(keepout
			(tracks allowed)
			(vias allowed)
			(pads allowed)
			(copperpour allowed)
			(footprints not_allowed)
		)
		(placement
			(enabled no)
			(sheetname "")
		)
		(fill
			(thermal_gap 0.5)
			(thermal_bridge_width 0.5)
			(island_removal_mode 0)
		)
		(polygon
			(pts
				(xy 153.42997 -240.191036) (xy 153.42997 -191.77) (xy 105.71988 -191.77) (xy 105.71988 -208.88706)
				(arc
					(start 122.825002 -208.88706)
					(mid 123.88557 -209.326362)
					(end 124.324872 -210.38693)
				)
				(arc
					(start 124.324872 -211.676996)
					(mid 123.88566 -212.737728)
					(end 122.825002 -213.17712)
				)
				(arc
					(start 101.03485 -213.17712)
					(mid 99.974356 -212.737639)
					(end 99.53498 -211.676996)
				)
				(arc
					(start 99.53498 -210.38693)
					(mid 99.974282 -209.326362)
					(end 101.03485 -208.88706)
				)
				(xy 105.620058 -208.88706) (xy 105.620058 -191.77) (xy 70.429882 -191.77) (xy 70.429882 -240.191036)
				(xy 102.860094 -240.191036)
				(arc
					(start 102.860094 -237.06455)
					(mid 103.29938 -236.003892)
					(end 104.359964 -235.564426)
				)
				(arc
					(start 106.950002 -235.564426)
					(mid 108.01075 -236.003802)
					(end 108.450126 -237.06455)
				)
				(arc
					(start 108.450126 -261.5946)
					(mid 108.010734 -262.655258)
					(end 106.950002 -263.09447)
				)
				(arc
					(start 104.359964 -263.09447)
					(mid 103.299396 -262.655168)
					(end 102.860094 -261.5946)
				)
				(xy 102.860094 -240.291112) (xy 70.429882 -240.291112) (xy 70.429882 -311.770014) (xy 105.620058 -311.770014)
				(xy 105.620058 -297.065954)
				(arc
					(start 101.745034 -297.065954)
					(mid 100.684466 -296.626652)
					(end 100.24491 -295.566084)
				)
				(arc
					(start 100.24491 -294.276018)
					(mid 100.684286 -293.21527)
					(end 101.745034 -292.775894)
				)
				(arc
					(start 122.115072 -292.775894)
					(mid 123.17582 -293.21527)
					(end 123.614942 -294.276018)
				)
				(arc
					(start 123.614942 -295.566084)
					(mid 123.17564 -296.626652)
					(end 122.115072 -297.065954)
				)
				(xy 105.71988 -297.065954) (xy 105.71988 -311.770014) (xy 153.42997 -311.770014) (xy 153.42997 -240.291112)
				(xy 121.000012 -240.291112)
				(arc
					(start 121.000012 -261.5946)
					(mid 120.56062 -262.655258)
					(end 119.499888 -263.09447)
				)
				(arc
					(start 116.910104 -263.09447)
					(mid 115.849536 -262.655168)
					(end 115.40998 -261.5946)
				)
				(arc
					(start 115.40998 -237.06455)
					(mid 115.849356 -236.003802)
					(end 116.910104 -235.564426)
				)
				(arc
					(start 119.499888 -235.564426)
					(mid 120.560636 -236.003802)
					(end 121.000012 -237.06455)
				)
				(xy 121.000012 -240.191036)
			)
		)
	)
	(zone
		(layer "B.Cu")
		(hatch none 0.5)
		(connect_pads
			(clearance 0)
		)
		(min_thickness 0.25)
		(keepout
			(tracks not_allowed)
			(vias allowed)
			(pads allowed)
			(copperpour not_allowed)
			(footprints allowed)
		)
		(placement
			(enabled no)
			(sheetname "")
		)
		(fill
			(thermal_gap 0.5)
			(thermal_bridge_width 0.5)
			(island_removal_mode 0)
		)
		(polygon
			(pts
				(arc
					(start 69.05498 -419.88994)
					(mid 68.245228 -419.88994)
					(end 69.05498 -419.88994)
				)
			)
		)
	)
	(zone
		(layer "B.Cu")
		(hatch none 0.5)
		(connect_pads
			(clearance 0)
		)
		(min_thickness 0.25)
		(keepout
			(tracks not_allowed)
			(vias allowed)
			(pads allowed)
			(copperpour not_allowed)
			(footprints allowed)
		)
		(placement
			(enabled no)
			(sheetname "")
		)
		(fill
			(thermal_gap 0.5)
			(thermal_bridge_width 0.5)
			(island_removal_mode 0)
		)
		(polygon
			(pts
				(arc
					(start 342.52027 -223.575626)
					(mid 341.86749 -223.575626)
					(end 342.52027 -223.575626)
				)
			)
		)
	)
	(zone
		(layer "B.Cu")
		(hatch none 0.5)
		(connect_pads
			(clearance 0)
		)
		(min_thickness 0.25)
		(keepout
			(tracks allowed)
			(vias allowed)
			(pads allowed)
			(copperpour allowed)
			(footprints allowed)
		)
		(placement
			(enabled no)
			(sheetname "")
		)
		(fill
			(thermal_gap 0.5)
			(thermal_bridge_width 0.5)
			(island_removal_mode 0)
		)
		(polygon
			(pts
				(xy 224.29724 -69.1261) (xy 224.29724 -68.1609) (xy 225.60788 -68.1609) (xy 225.60788 -69.1261)
			)
		)
	)
	(zone
		(layer "B.Cu")
		(hatch none 0.5)
		(connect_pads
			(clearance 0)
		)
		(min_thickness 0.25)
		(keepout
			(tracks allowed)
			(vias allowed)
			(pads allowed)
			(copperpour allowed)
			(footprints allowed)
		)
		(placement
			(enabled no)
			(sheetname "")
		)
		(fill
			(thermal_gap 0.5)
			(thermal_bridge_width 0.5)
			(island_removal_mode 0)
		)
		(polygon
			(pts
				(xy 104.0257 -352.349308) (xy 104.0257 -350.685608) (xy 109.05744 -350.685608) (xy 109.05744 -352.349308)
			)
		)
	)
	(zone
		(layer "B.Cu")
		(hatch none 0.5)
		(connect_pads
			(clearance 0)
		)
		(min_thickness 0.25)
		(keepout
			(tracks not_allowed)
			(vias allowed)
			(pads allowed)
			(copperpour not_allowed)
			(footprints allowed)
		)
		(placement
			(enabled no)
			(sheetname "")
		)
		(fill
			(thermal_gap 0.5)
			(thermal_bridge_width 0.5)
			(island_removal_mode 0)
		)
		(polygon
			(pts
				(arc
					(start 231.650032 -192.499996)
					(mid 236.650022 -197.499986)
					(end 241.650012 -192.499996)
				)
				(arc
					(start 241.650012 -192.499996)
					(mid 236.650022 -187.500006)
					(end 231.650032 -192.499996)
				)
			)
		)
	)
	(zone
		(layer "B.Cu")
		(hatch none 0.5)
		(connect_pads
			(clearance 0)
		)
		(min_thickness 0.25)
		(keepout
			(tracks not_allowed)
			(vias allowed)
			(pads allowed)
			(copperpour not_allowed)
			(footprints allowed)
		)
		(placement
			(enabled no)
			(sheetname "")
		)
		(fill
			(thermal_gap 0.5)
			(thermal_bridge_width 0.5)
			(island_removal_mode 0)
		)
		(polygon
			(pts
				(arc
					(start 283.979874 -419.999922)
					(mid 287.98012 -424.000168)
					(end 291.980112 -419.999922)
				)
				(arc
					(start 291.980112 -419.999922)
					(mid 287.98012 -415.99993)
					(end 283.979874 -419.999922)
				)
			)
		)
	)
	(zone
		(layer "B.Cu")
		(hatch none 0.5)
		(connect_pads
			(clearance 0)
		)
		(min_thickness 0.25)
		(keepout
			(tracks allowed)
			(vias allowed)
			(pads allowed)
			(copperpour allowed)
			(footprints allowed)
		)
		(placement
			(enabled no)
			(sheetname "")
		)
		(fill
			(thermal_gap 0.5)
			(thermal_bridge_width 0.5)
			(island_removal_mode 0)
		)
		(polygon
			(pts
				(xy 300.31944 -154.54122) (xy 300.31944 -149.57552) (xy 302.32096 -149.57552) (xy 302.32096 -154.54122)
			)
		)
	)
	(zone
		(layer "B.Cu")
		(hatch none 0.5)
		(connect_pads
			(clearance 0)
		)
		(min_thickness 0.25)
		(keepout
			(tracks not_allowed)
			(vias allowed)
			(pads allowed)
			(copperpour not_allowed)
			(footprints allowed)
		)
		(placement
			(enabled no)
			(sheetname "")
		)
		(fill
			(thermal_gap 0.5)
			(thermal_bridge_width 0.5)
			(island_removal_mode 0)
		)
		(polygon
			(pts
				(arc
					(start 152.002744 -400.858228)
					(mid 151.299164 -400.858228)
					(end 152.002744 -400.858228)
				)
			)
		)
	)
	(zone
		(layer "B.Cu")
		(hatch none 0.5)
		(connect_pads
			(clearance 0)
		)
		(min_thickness 0.25)
		(keepout
			(tracks allowed)
			(vias allowed)
			(pads allowed)
			(copperpour allowed)
			(footprints not_allowed)
		)
		(placement
			(enabled no)
			(sheetname "")
		)
		(fill
			(thermal_gap 0.5)
			(thermal_bridge_width 0.5)
			(island_removal_mode 0)
		)
		(polygon
			(pts
				(arc
					(start 462.799938 -172.928026)
					(mid 465.115345 -172.453624)
					(end 467.300056 -171.551854)
				)
				(arc
					(start 467.300056 -336.648044)
					(mid 465.115329 -335.746405)
					(end 462.799938 -335.272126)
				)
			)
		)
	)
	(zone
		(layer "B.Cu")
		(hatch none 0.5)
		(connect_pads
			(clearance 0)
		)
		(min_thickness 0.25)
		(keepout
			(tracks allowed)
			(vias allowed)
			(pads allowed)
			(copperpour allowed)
			(footprints not_allowed)
		)
		(placement
			(enabled no)
			(sheetname "")
		)
		(fill
			(thermal_gap 0.5)
			(thermal_bridge_width 0.5)
			(island_removal_mode 0)
		)
		(polygon
			(pts
				(arc
					(start 319.79997 -68.449952)
					(mid 316.900052 -65.550034)
					(end 313.99988 -68.449952)
				)
				(arc
					(start 313.99988 -68.449952)
					(mid 316.900052 -71.350124)
					(end 319.79997 -68.449952)
				)
			)
		)
	)
	(zone
		(layer "B.Cu")
		(hatch none 0.5)
		(connect_pads
			(clearance 0)
		)
		(min_thickness 0.25)
		(keepout
			(tracks not_allowed)
			(vias allowed)
			(pads allowed)
			(copperpour not_allowed)
			(footprints allowed)
		)
		(placement
			(enabled no)
			(sheetname "")
		)
		(fill
			(thermal_gap 0.5)
			(thermal_bridge_width 0.5)
			(island_removal_mode 0)
		)
		(polygon
			(pts
				(arc
					(start 95.500444 -435.600094)
					(mid 100.500434 -440.600084)
					(end 105.500424 -435.600094)
				)
				(arc
					(start 105.500424 -435.600094)
					(mid 100.500434 -430.600104)
					(end 95.500444 -435.600094)
				)
			)
		)
	)
	(zone
		(layer "B.Cu")
		(hatch none 0.5)
		(connect_pads
			(clearance 0)
		)
		(min_thickness 0.25)
		(keepout
			(tracks not_allowed)
			(vias allowed)
			(pads allowed)
			(copperpour not_allowed)
			(footprints allowed)
		)
		(placement
			(enabled no)
			(sheetname "")
		)
		(fill
			(thermal_gap 0.5)
			(thermal_bridge_width 0.5)
			(island_removal_mode 0)
		)
		(polygon
			(pts
				(arc
					(start 37.515038 -398.65935)
					(mid 36.811458 -398.65935)
					(end 37.515038 -398.65935)
				)
			)
		)
	)
	(zone
		(layer "B.Cu")
		(hatch none 0.5)
		(connect_pads
			(clearance 0)
		)
		(min_thickness 0.25)
		(keepout
			(tracks not_allowed)
			(vias allowed)
			(pads allowed)
			(copperpour not_allowed)
			(footprints allowed)
		)
		(placement
			(enabled no)
			(sheetname "")
		)
		(fill
			(thermal_gap 0.5)
			(thermal_bridge_width 0.5)
			(island_removal_mode 0)
		)
		(polygon
			(pts
				(arc
					(start 23.888446 -382.933194)
					(mid 23.184866 -382.933194)
					(end 23.888446 -382.933194)
				)
			)
		)
	)
	(zone
		(layer "B.Cu")
		(hatch none 0.5)
		(connect_pads
			(clearance 0)
		)
		(min_thickness 0.25)
		(keepout
			(tracks allowed)
			(vias allowed)
			(pads allowed)
			(copperpour allowed)
			(footprints allowed)
		)
		(placement
			(enabled no)
			(sheetname "")
		)
		(fill
			(thermal_gap 0.5)
			(thermal_bridge_width 0.5)
			(island_removal_mode 0)
		)
		(polygon
			(pts
				(xy 134.59206 -15.5702) (xy 134.59206 -13.7795) (xy 137.75182 -13.7795) (xy 137.75182 -15.5702)
			)
		)
	)
	(zone
		(layer "B.Cu")
		(hatch none 0.5)
		(connect_pads
			(clearance 0)
		)
		(min_thickness 0.25)
		(keepout
			(tracks not_allowed)
			(vias allowed)
			(pads allowed)
			(copperpour not_allowed)
			(footprints allowed)
		)
		(placement
			(enabled no)
			(sheetname "")
		)
		(fill
			(thermal_gap 0.5)
			(thermal_bridge_width 0.5)
			(island_removal_mode 0)
		)
		(polygon
			(pts
				(arc
					(start 201.399902 -22.29993)
					(mid 203.399898 -24.299926)
					(end 205.399894 -22.29993)
				)
				(arc
					(start 205.399894 -22.29993)
					(mid 203.399898 -20.299934)
					(end 201.399902 -22.29993)
				)
			)
		)
	)
	(zone
		(layer "B.Cu")
		(hatch none 0.5)
		(connect_pads
			(clearance 0)
		)
		(min_thickness 0.25)
		(keepout
			(tracks allowed)
			(vias allowed)
			(pads allowed)
			(copperpour allowed)
			(footprints allowed)
		)
		(placement
			(enabled no)
			(sheetname "")
		)
		(fill
			(thermal_gap 0.5)
			(thermal_bridge_width 0.5)
			(island_removal_mode 0)
		)
		(polygon
			(pts
				(xy 429.86198 -119.969788) (xy 429.86198 -120.861328) (xy 430.05248 -121.051828) (xy 430.29378 -121.051828)
				(xy 430.66716 -120.678448) (xy 430.66716 -120.175528) (xy 430.20996 -119.718328) (xy 430.1617 -119.718328)
				(xy 429.91024 -119.969788)
			)
		)
	)
	(zone
		(layer "B.Cu")
		(hatch none 0.5)
		(connect_pads
			(clearance 0)
		)
		(min_thickness 0.25)
		(keepout
			(tracks not_allowed)
			(vias allowed)
			(pads allowed)
			(copperpour not_allowed)
			(footprints allowed)
		)
		(placement
			(enabled no)
			(sheetname "")
		)
		(fill
			(thermal_gap 0.5)
			(thermal_bridge_width 0.5)
			(island_removal_mode 0)
		)
		(polygon
			(pts
				(arc
					(start 459.799944 -22.29993)
					(mid 464.799934 -27.29992)
					(end 469.799924 -22.29993)
				)
				(arc
					(start 469.799924 -22.29993)
					(mid 464.799934 -17.29994)
					(end 459.799944 -22.29993)
				)
			)
		)
	)
	(zone
		(layer "B.Cu")
		(hatch none 0.5)
		(connect_pads
			(clearance 0)
		)
		(min_thickness 0.25)
		(keepout
			(tracks allowed)
			(vias allowed)
			(pads allowed)
			(copperpour allowed)
			(footprints allowed)
		)
		(placement
			(enabled no)
			(sheetname "")
		)
		(fill
			(thermal_gap 0.5)
			(thermal_bridge_width 0.5)
			(island_removal_mode 0)
		)
		(polygon
			(pts
				(xy 422.108376 -361.968542) (xy 423.446956 -361.968542) (xy 423.840656 -362.362242) (xy 423.840656 -364.577122)
				(xy 424.031156 -364.767622) (xy 427.576996 -364.767622) (xy 427.792896 -364.983522) (xy 427.792896 -367.145062)
				(xy 427.632876 -367.305082) (xy 422.197276 -367.305082) (xy 421.752776 -366.860582) (xy 421.752776 -362.324142)
			)
		)
	)
	(zone
		(layer "B.Cu")
		(hatch none 0.5)
		(connect_pads
			(clearance 0)
		)
		(min_thickness 0.25)
		(keepout
			(tracks allowed)
			(vias allowed)
			(pads allowed)
			(copperpour allowed)
			(footprints not_allowed)
		)
		(placement
			(enabled no)
			(sheetname "")
		)
		(fill
			(thermal_gap 0.5)
			(thermal_bridge_width 0.5)
			(island_removal_mode 0)
		)
		(polygon
			(pts
				(arc
					(start 20.682204 -354.720652)
					(mid 19.039807 -338.72443)
					(end 2.999994 -337.582002)
				)
				(arc
					(start 2.999994 -371.291104)
					(mid 18.287657 -369.884849)
					(end 20.682204 -354.720652)
				)
			)
		)
	)
	(zone
		(layer "B.Cu")
		(hatch none 0.5)
		(connect_pads
			(clearance 0)
		)
		(min_thickness 0.25)
		(keepout
			(tracks allowed)
			(vias allowed)
			(pads allowed)
			(copperpour allowed)
			(footprints allowed)
		)
		(placement
			(enabled no)
			(sheetname "")
		)
		(fill
			(thermal_gap 0.5)
			(thermal_bridge_width 0.5)
			(island_removal_mode 0)
		)
		(polygon
			(pts
				(xy 130.27406 -341.777828) (xy 130.27406 -337.586828) (xy 125.35662 -337.586828) (xy 125.35662 -341.777828)
			)
		)
	)
	(zone
		(layer "B.Cu")
		(hatch none 0.5)
		(connect_pads
			(clearance 0)
		)
		(min_thickness 0.25)
		(keepout
			(tracks not_allowed)
			(vias allowed)
			(pads allowed)
			(copperpour not_allowed)
			(footprints allowed)
		)
		(placement
			(enabled no)
			(sheetname "")
		)
		(fill
			(thermal_gap 0.5)
			(thermal_bridge_width 0.5)
			(island_removal_mode 0)
		)
		(polygon
			(pts
				(arc
					(start 135.822944 -400.858228)
					(mid 135.119364 -400.858228)
					(end 135.822944 -400.858228)
				)
			)
		)
	)
	(zone
		(layer "B.Cu")
		(hatch none 0.5)
		(connect_pads
			(clearance 0)
		)
		(min_thickness 0.25)
		(keepout
			(tracks not_allowed)
			(vias allowed)
			(pads allowed)
			(copperpour not_allowed)
			(footprints allowed)
		)
		(placement
			(enabled no)
			(sheetname "")
		)
		(fill
			(thermal_gap 0.5)
			(thermal_bridge_width 0.5)
			(island_removal_mode 0)
		)
		(polygon
			(pts
				(arc
					(start 161.192464 -400.858228)
					(mid 160.488884 -400.858228)
					(end 161.192464 -400.858228)
				)
			)
		)
	)
	(zone
		(layer "B.Cu")
		(hatch none 0.5)
		(connect_pads
			(clearance 0)
		)
		(min_thickness 0.25)
		(keepout
			(tracks not_allowed)
			(vias allowed)
			(pads allowed)
			(copperpour not_allowed)
			(footprints allowed)
		)
		(placement
			(enabled no)
			(sheetname "")
		)
		(fill
			(thermal_gap 0.5)
			(thermal_bridge_width 0.5)
			(island_removal_mode 0)
		)
		(polygon
			(pts
				(arc
					(start 142.813024 -400.858228)
					(mid 142.109444 -400.858228)
					(end 142.813024 -400.858228)
				)
			)
		)
	)
	(zone
		(layer "B.Cu")
		(hatch none 0.5)
		(connect_pads
			(clearance 0)
		)
		(min_thickness 0.25)
		(keepout
			(tracks allowed)
			(vias allowed)
			(pads allowed)
			(copperpour allowed)
			(footprints allowed)
		)
		(placement
			(enabled no)
			(sheetname "")
		)
		(fill
			(thermal_gap 0.5)
			(thermal_bridge_width 0.5)
			(island_removal_mode 0)
		)
		(polygon
			(pts
				(xy 412.420054 -361.968542) (xy 413.758634 -361.968542) (xy 414.152334 -362.362242) (xy 414.152334 -364.577122)
				(xy 414.342834 -364.767622) (xy 417.888674 -364.767622) (xy 418.104574 -364.983522) (xy 418.104574 -367.145062)
				(xy 417.944554 -367.305082) (xy 412.508954 -367.305082) (xy 412.064454 -366.860582) (xy 412.064454 -362.324142)
			)
		)
	)
	(zone
		(layer "B.Cu")
		(hatch none 0.5)
		(connect_pads
			(clearance 0)
		)
		(min_thickness 0.25)
		(keepout
			(tracks not_allowed)
			(vias allowed)
			(pads allowed)
			(copperpour not_allowed)
			(footprints allowed)
		)
		(placement
			(enabled no)
			(sheetname "")
		)
		(fill
			(thermal_gap 0.5)
			(thermal_bridge_width 0.5)
			(island_removal_mode 0)
		)
		(polygon
			(pts
				(arc
					(start 397.14424 -400.858228)
					(mid 396.44066 -400.858228)
					(end 397.14424 -400.858228)
				)
			)
		)
	)
	(zone
		(layer "B.Cu")
		(hatch none 0.5)
		(connect_pads
			(clearance 0)
		)
		(min_thickness 0.25)
		(keepout
			(tracks not_allowed)
			(vias allowed)
			(pads allowed)
			(copperpour not_allowed)
			(footprints allowed)
		)
		(placement
			(enabled no)
			(sheetname "")
		)
		(fill
			(thermal_gap 0.5)
			(thermal_bridge_width 0.5)
			(island_removal_mode 0)
		)
		(polygon
			(pts
				(arc
					(start 5.340096 -347.700092)
					(mid 10.340086 -352.700082)
					(end 15.340076 -347.700092)
				)
				(arc
					(start 15.340076 -347.700092)
					(mid 10.340086 -342.700102)
					(end 5.340096 -347.700092)
				)
			)
		)
	)
	(zone
		(layer "B.Cu")
		(hatch none 0.5)
		(connect_pads
			(clearance 0)
		)
		(min_thickness 0.25)
		(keepout
			(tracks not_allowed)
			(vias allowed)
			(pads allowed)
			(copperpour not_allowed)
			(footprints allowed)
		)
		(placement
			(enabled no)
			(sheetname "")
		)
		(fill
			(thermal_gap 0.5)
			(thermal_bridge_width 0.5)
			(island_removal_mode 0)
		)
		(polygon
			(pts
				(arc
					(start 378.7648 -400.858228)
					(mid 378.06122 -400.858228)
					(end 378.7648 -400.858228)
				)
			)
		)
	)
	(zone
		(layer "B.Cu")
		(hatch none 0.5)
		(connect_pads
			(clearance 0)
		)
		(min_thickness 0.25)
		(keepout
			(tracks allowed)
			(vias allowed)
			(pads allowed)
			(copperpour allowed)
			(footprints allowed)
		)
		(placement
			(enabled no)
			(sheetname "")
		)
		(fill
			(thermal_gap 0.5)
			(thermal_bridge_width 0.5)
			(island_removal_mode 0)
		)
		(polygon
			(pts
				(xy 348.50832 -53.266848) (xy 348.50832 -52.283868) (xy 350.15678 -52.283868) (xy 350.15678 -53.266848)
			)
		)
	)
	(zone
		(layer "B.Cu")
		(hatch none 0.5)
		(connect_pads
			(clearance 0)
		)
		(min_thickness 0.25)
		(keepout
			(tracks allowed)
			(vias allowed)
			(pads allowed)
			(copperpour allowed)
			(footprints not_allowed)
		)
		(placement
			(enabled no)
			(sheetname "")
		)
		(fill
			(thermal_gap 0.5)
			(thermal_bridge_width 0.5)
			(island_removal_mode 0)
		)
		(polygon
			(pts
				(arc
					(start 260.649974 -22.29993)
					(mid 265.649964 -27.29992)
					(end 270.649954 -22.29993)
				)
				(arc
					(start 270.649954 -22.29993)
					(mid 265.649964 -17.29994)
					(end 260.649974 -22.29993)
				)
			)
		)
	)
	(zone
		(layer "B.Cu")
		(hatch none 0.5)
		(connect_pads
			(clearance 0)
		)
		(min_thickness 0.25)
		(keepout
			(tracks allowed)
			(vias allowed)
			(pads allowed)
			(copperpour allowed)
			(footprints not_allowed)
		)
		(placement
			(enabled no)
			(sheetname "")
		)
		(fill
			(thermal_gap 0.5)
			(thermal_bridge_width 0.5)
			(island_removal_mode 0)
		)
		(polygon
			(pts
				(arc
					(start 196.645276 -51.999896)
					(mid 204.64526 -59.99988)
					(end 212.645244 -51.999896)
				)
				(arc
					(start 212.645244 -51.999896)
					(mid 204.64526 -43.999912)
					(end 196.645276 -51.999896)
				)
			)
		)
	)
	(zone
		(layer "B.Cu")
		(hatch none 0.5)
		(connect_pads
			(clearance 0)
		)
		(min_thickness 0.25)
		(keepout
			(tracks not_allowed)
			(vias allowed)
			(pads allowed)
			(copperpour not_allowed)
			(footprints allowed)
		)
		(placement
			(enabled no)
			(sheetname "")
		)
		(fill
			(thermal_gap 0.5)
			(thermal_bridge_width 0.5)
			(island_removal_mode 0)
		)
		(polygon
			(pts
				(arc
					(start 412.46044 -400.858228)
					(mid 411.75686 -400.858228)
					(end 412.46044 -400.858228)
				)
			)
		)
	)
	(zone
		(layer "B.Cu")
		(hatch none 0.5)
		(connect_pads
			(clearance 0)
		)
		(min_thickness 0.25)
		(keepout
			(tracks not_allowed)
			(vias allowed)
			(pads allowed)
			(copperpour not_allowed)
			(footprints allowed)
		)
		(placement
			(enabled no)
			(sheetname "")
		)
		(fill
			(thermal_gap 0.5)
			(thermal_bridge_width 0.5)
			(island_removal_mode 0)
		)
		(polygon
			(pts
				(arc
					(start 361.82173 -46.802802)
					(mid 361.11815 -46.802802)
					(end 361.82173 -46.802802)
				)
			)
		)
	)
	(zone
		(layer "B.Cu")
		(hatch none 0.5)
		(connect_pads
			(clearance 0)
		)
		(min_thickness 0.25)
		(keepout
			(tracks not_allowed)
			(vias allowed)
			(pads allowed)
			(copperpour not_allowed)
			(footprints allowed)
		)
		(placement
			(enabled no)
			(sheetname "")
		)
		(fill
			(thermal_gap 0.5)
			(thermal_bridge_width 0.5)
			(island_removal_mode 0)
		)
		(polygon
			(pts
				(arc
					(start 361.47502 -431.360072)
					(mid 359.774998 -429.66005)
					(end 358.074976 -431.360072)
				)
				(arc
					(start 358.074976 -431.360072)
					(mid 359.774998 -433.060094)
					(end 361.47502 -431.360072)
				)
			)
		)
	)
	(zone
		(layer "B.Cu")
		(hatch none 0.5)
		(connect_pads
			(clearance 0)
		)
		(min_thickness 0.25)
		(keepout
			(tracks not_allowed)
			(vias allowed)
			(pads allowed)
			(copperpour not_allowed)
			(footprints allowed)
		)
		(placement
			(enabled no)
			(sheetname "")
		)
		(fill
			(thermal_gap 0.5)
			(thermal_bridge_width 0.5)
			(island_removal_mode 0)
		)
		(polygon
			(pts
				(arc
					(start 377.763024 -224.389442)
					(mid 377.110244 -224.389442)
					(end 377.763024 -224.389442)
				)
			)
		)
	)
	(zone
		(layer "B.Cu")
		(hatch none 0.5)
		(connect_pads
			(clearance 0)
		)
		(min_thickness 0.25)
		(keepout
			(tracks not_allowed)
			(vias allowed)
			(pads allowed)
			(copperpour not_allowed)
			(footprints allowed)
		)
		(placement
			(enabled no)
			(sheetname "")
		)
		(fill
			(thermal_gap 0.5)
			(thermal_bridge_width 0.5)
			(island_removal_mode 0)
		)
		(polygon
			(pts
				(arc
					(start 402.40712 -400.858228)
					(mid 401.70354 -400.858228)
					(end 402.40712 -400.858228)
				)
			)
		)
	)
	(zone
		(layer "B.Cu")
		(hatch none 0.5)
		(connect_pads
			(clearance 0)
		)
		(min_thickness 0.25)
		(keepout
			(tracks not_allowed)
			(vias allowed)
			(pads allowed)
			(copperpour not_allowed)
			(footprints allowed)
		)
		(placement
			(enabled no)
			(sheetname "")
		)
		(fill
			(thermal_gap 0.5)
			(thermal_bridge_width 0.5)
			(island_removal_mode 0)
		)
		(polygon
			(pts
				(arc
					(start 108.374942 -431.360072)
					(mid 112.024922 -435.010052)
					(end 115.674902 -431.360072)
				)
				(arc
					(start 115.674902 -431.360072)
					(mid 112.024922 -427.710092)
					(end 108.374942 -431.360072)
				)
			)
		)
	)
	(zone
		(layer "B.Cu")
		(hatch none 0.5)
		(connect_pads
			(clearance 0)
		)
		(min_thickness 0.25)
		(keepout
			(tracks not_allowed)
			(vias allowed)
			(pads allowed)
			(copperpour not_allowed)
			(footprints allowed)
		)
		(placement
			(enabled no)
			(sheetname "")
		)
		(fill
			(thermal_gap 0.5)
			(thermal_bridge_width 0.5)
			(island_removal_mode 0)
		)
		(polygon
			(pts
				(arc
					(start 132.642356 -224.389442)
					(mid 131.989576 -224.389442)
					(end 132.642356 -224.389442)
				)
			)
		)
	)
	(zone
		(layer "B.Cu")
		(hatch none 0.5)
		(connect_pads
			(clearance 0)
		)
		(min_thickness 0.25)
		(keepout
			(tracks allowed)
			(vias allowed)
			(pads allowed)
			(copperpour allowed)
			(footprints not_allowed)
		)
		(placement
			(enabled no)
			(sheetname "")
		)
		(fill
			(thermal_gap 0.5)
			(thermal_bridge_width 0.5)
			(island_removal_mode 0)
		)
		(polygon
			(pts
				(arc
					(start 4.19989 -22.29993)
					(mid 6.999986 -25.100026)
					(end 9.800082 -22.29993)
				)
				(arc
					(start 9.800082 -22.29993)
					(mid 6.999986 -19.499834)
					(end 4.19989 -22.29993)
				)
			)
		)
	)
	(zone
		(layer "B.Cu")
		(hatch none 0.5)
		(connect_pads
			(clearance 0)
		)
		(min_thickness 0.25)
		(keepout
			(tracks not_allowed)
			(vias allowed)
			(pads allowed)
			(copperpour not_allowed)
			(footprints allowed)
		)
		(placement
			(enabled no)
			(sheetname "")
		)
		(fill
			(thermal_gap 0.5)
			(thermal_bridge_width 0.5)
			(island_removal_mode 0)
		)
		(polygon
			(pts
				(arc
					(start 104.918002 -225.203258)
					(mid 104.265222 -225.203258)
					(end 104.918002 -225.203258)
				)
			)
		)
	)
	(zone
		(layer "B.Cu")
		(hatch none 0.5)
		(connect_pads
			(clearance 0)
		)
		(min_thickness 0.25)
		(keepout
			(tracks allowed)
			(vias allowed)
			(pads allowed)
			(copperpour allowed)
			(footprints not_allowed)
		)
		(placement
			(enabled no)
			(sheetname "")
		)
		(fill
			(thermal_gap 0.5)
			(thermal_bridge_width 0.5)
			(island_removal_mode 0)
		)
		(polygon
			(pts
				(arc
					(start 273.750532 -12.78001)
					(mid 275.994308 -29.317239)
					(end 259.799074 -33.346136)
				)
				(xy 259.80009 -33.275016)
				(arc
					(start 259.80009 -13.780008)
					(mid 260.092983 -13.072903)
					(end 260.800088 -12.78001)
				)
			)
		)
	)
	(zone
		(layer "B.Cu")
		(hatch none 0.5)
		(connect_pads
			(clearance 0)
		)
		(min_thickness 0.25)
		(keepout
			(tracks allowed)
			(vias allowed)
			(pads allowed)
			(copperpour allowed)
			(footprints not_allowed)
		)
		(placement
			(enabled no)
			(sheetname "")
		)
		(fill
			(thermal_gap 0.5)
			(thermal_bridge_width 0.5)
			(island_removal_mode 0)
		)
		(polygon
			(pts
				(arc
					(start 285.643828 -412.34868)
					(mid 280.16268 -418.299869)
					(end 282.677108 -425.990004)
				)
				(arc
					(start 187.743592 -425.990004)
					(mid 186.980299 -425.403378)
					(end 186.174126 -424.87723)
				)
				(xy 186.174126 -405.99995) (xy 285.643828 -405.99995)
			)
		)
	)
	(zone
		(layer "B.Cu")
		(hatch none 0.5)
		(connect_pads
			(clearance 0)
		)
		(min_thickness 0.25)
		(keepout
			(tracks allowed)
			(vias allowed)
			(pads allowed)
			(copperpour allowed)
			(footprints not_allowed)
		)
		(placement
			(enabled no)
			(sheetname "")
		)
		(fill
			(thermal_gap 0.5)
			(thermal_bridge_width 0.5)
			(island_removal_mode 0)
		)
		(polygon
			(pts
				(arc
					(start 230.89997 -81.700116)
					(mid 235.89996 -86.700106)
					(end 240.89995 -81.700116)
				)
				(arc
					(start 240.89995 -81.700116)
					(mid 235.89996 -76.700126)
					(end 230.89997 -81.700116)
				)
			)
		)
	)
	(zone
		(layer "B.Cu")
		(hatch none 0.5)
		(connect_pads
			(clearance 0)
		)
		(min_thickness 0.25)
		(keepout
			(tracks not_allowed)
			(vias allowed)
			(pads allowed)
			(copperpour not_allowed)
			(footprints allowed)
		)
		(placement
			(enabled no)
			(sheetname "")
		)
		(fill
			(thermal_gap 0.5)
			(thermal_bridge_width 0.5)
			(island_removal_mode 0)
		)
		(polygon
			(pts
				(arc
					(start 362.68533 -46.802802)
					(mid 361.98175 -46.802802)
					(end 362.68533 -46.802802)
				)
			)
		)
	)
	(zone
		(layer "B.Cu")
		(hatch none 0.5)
		(connect_pads
			(clearance 0)
		)
		(min_thickness 0.25)
		(keepout
			(tracks allowed)
			(vias allowed)
			(pads allowed)
			(copperpour allowed)
			(footprints not_allowed)
		)
		(placement
			(enabled no)
			(sheetname "")
		)
		(fill
			(thermal_gap 0.5)
			(thermal_bridge_width 0.5)
			(island_removal_mode 0)
		)
		(polygon
			(pts
				(arc
					(start 10.199878 -435.600094)
					(mid 12.999974 -438.40019)
					(end 15.80007 -435.600094)
				)
				(arc
					(start 15.80007 -435.600094)
					(mid 12.999974 -432.799998)
					(end 10.199878 -435.600094)
				)
			)
		)
	)
	(zone
		(layer "B.Cu")
		(hatch none 0.5)
		(connect_pads
			(clearance 0)
		)
		(min_thickness 0.25)
		(keepout
			(tracks not_allowed)
			(vias allowed)
			(pads allowed)
			(copperpour not_allowed)
			(footprints allowed)
		)
		(placement
			(enabled no)
			(sheetname "")
		)
		(fill
			(thermal_gap 0.5)
			(thermal_bridge_width 0.5)
			(island_removal_mode 0)
		)
		(polygon
			(pts
				(arc
					(start 375.883424 -224.389442)
					(mid 375.230644 -224.389442)
					(end 375.883424 -224.389442)
				)
			)
		)
	)
	(zone
		(layer "B.Cu")
		(hatch none 0.5)
		(connect_pads
			(clearance 0)
		)
		(min_thickness 0.25)
		(keepout
			(tracks allowed)
			(vias allowed)
			(pads allowed)
			(copperpour allowed)
			(footprints not_allowed)
		)
		(placement
			(enabled no)
			(sheetname "")
		)
		(fill
			(thermal_gap 0.5)
			(thermal_bridge_width 0.5)
			(island_removal_mode 0)
		)
		(polygon
			(pts
				(arc
					(start 64.382904 -48.64989)
					(mid 65.98285 -47.049944)
					(end 64.382904 -45.449998)
				)
				(arc
					(start 62.782958 -45.449998)
					(mid 61.183012 -47.049944)
					(end 62.782958 -48.64989)
				)
			)
		)
	)
	(zone
		(layer "B.Cu")
		(hatch none 0.5)
		(connect_pads
			(clearance 0)
		)
		(min_thickness 0.25)
		(keepout
			(tracks not_allowed)
			(vias allowed)
			(pads allowed)
			(copperpour not_allowed)
			(footprints allowed)
		)
		(placement
			(enabled no)
			(sheetname "")
		)
		(fill
			(thermal_gap 0.5)
			(thermal_bridge_width 0.5)
			(island_removal_mode 0)
		)
		(polygon
			(pts
				(arc
					(start 96.459802 -223.575626)
					(mid 95.807022 -223.575626)
					(end 96.459802 -223.575626)
				)
			)
		)
	)
	(zone
		(layer "B.Cu")
		(hatch none 0.5)
		(connect_pads
			(clearance 0)
		)
		(min_thickness 0.25)
		(keepout
			(tracks not_allowed)
			(vias allowed)
			(pads allowed)
			(copperpour not_allowed)
			(footprints allowed)
		)
		(placement
			(enabled no)
			(sheetname "")
		)
		(fill
			(thermal_gap 0.5)
			(thermal_bridge_width 0.5)
			(island_removal_mode 0)
		)
		(polygon
			(pts
				(arc
					(start 447.249804 -435.59984)
					(mid 448.799966 -437.150002)
					(end 450.349874 -435.59984)
				)
				(arc
					(start 450.349874 -435.59984)
					(mid 448.799966 -434.049932)
					(end 447.249804 -435.59984)
				)
			)
		)
	)
	(zone
		(layer "B.Cu")
		(hatch none 0.5)
		(connect_pads
			(clearance 0)
		)
		(min_thickness 0.25)
		(keepout
			(tracks allowed)
			(vias allowed)
			(pads allowed)
			(copperpour allowed)
			(footprints allowed)
		)
		(placement
			(enabled no)
			(sheetname "")
		)
		(fill
			(thermal_gap 0.5)
			(thermal_bridge_width 0.5)
			(island_removal_mode 0)
		)
		(polygon
			(pts
				(xy 116.25072 -355.239828) (xy 116.25072 -353.538028) (xy 117.06606 -353.538028) (xy 117.06606 -355.239828)
			)
		)
	)
	(zone
		(layer "B.Cu")
		(hatch none 0.5)
		(connect_pads
			(clearance 0)
		)
		(min_thickness 0.25)
		(keepout
			(tracks not_allowed)
			(vias allowed)
			(pads allowed)
			(copperpour not_allowed)
			(footprints allowed)
		)
		(placement
			(enabled no)
			(sheetname "")
		)
		(fill
			(thermal_gap 0.5)
			(thermal_bridge_width 0.5)
			(island_removal_mode 0)
		)
		(polygon
			(pts
				(arc
					(start 102.568756 -224.389442)
					(mid 101.915976 -224.389442)
					(end 102.568756 -224.389442)
				)
			)
		)
	)
	(zone
		(layer "B.Cu")
		(hatch none 0.5)
		(connect_pads
			(clearance 0)
		)
		(min_thickness 0.25)
		(keepout
			(tracks allowed)
			(vias allowed)
			(pads allowed)
			(copperpour allowed)
			(footprints allowed)
		)
		(placement
			(enabled no)
			(sheetname "")
		)
		(fill
			(thermal_gap 0.5)
			(thermal_bridge_width 0.5)
			(island_removal_mode 0)
		)
		(polygon
			(pts
				(xy 124.59716 -21.186648) (xy 124.59716 -19.995388) (xy 126.1491 -19.995388) (xy 126.1491 -21.186648)
			)
		)
	)
	(zone
		(layer "B.Cu")
		(hatch none 0.5)
		(connect_pads
			(clearance 0)
		)
		(min_thickness 0.25)
		(keepout
			(tracks allowed)
			(vias allowed)
			(pads allowed)
			(copperpour allowed)
			(footprints allowed)
		)
		(placement
			(enabled no)
			(sheetname "")
		)
		(fill
			(thermal_gap 0.5)
			(thermal_bridge_width 0.5)
			(island_removal_mode 0)
		)
		(polygon
			(pts
				(xy 35.61334 -316.349888) (xy 35.61334 -315.727588) (xy 36.24072 -315.727588) (xy 36.24072 -316.349888)
			)
		)
	)
	(zone
		(layer "B.Cu")
		(hatch none 0.5)
		(connect_pads
			(clearance 0)
		)
		(min_thickness 0.25)
		(keepout
			(tracks not_allowed)
			(vias allowed)
			(pads allowed)
			(copperpour not_allowed)
			(footprints allowed)
		)
		(placement
			(enabled no)
			(sheetname "")
		)
		(fill
			(thermal_gap 0.5)
			(thermal_bridge_width 0.5)
			(island_removal_mode 0)
		)
		(polygon
			(pts
				(arc
					(start 85.090508 -400.858228)
					(mid 84.386928 -400.858228)
					(end 85.090508 -400.858228)
				)
			)
		)
	)
	(zone
		(layer "B.Cu")
		(hatch none 0.5)
		(connect_pads
			(clearance 0)
		)
		(min_thickness 0.25)
		(keepout
			(tracks allowed)
			(vias allowed)
			(pads allowed)
			(copperpour allowed)
			(footprints allowed)
		)
		(placement
			(enabled no)
			(sheetname "")
		)
		(fill
			(thermal_gap 0.5)
			(thermal_bridge_width 0.5)
			(island_removal_mode 0)
		)
		(polygon
			(pts
				(xy 242.34902 -36.82238) (xy 242.34902 -35.59302) (xy 241.48288 -35.59302) (xy 241.48288 -36.82238)
			)
		)
	)
	(zone
		(layer "B.Cu")
		(hatch none 0.5)
		(connect_pads
			(clearance 0)
		)
		(min_thickness 0.25)
		(keepout
			(tracks not_allowed)
			(vias allowed)
			(pads allowed)
			(copperpour not_allowed)
			(footprints allowed)
		)
		(placement
			(enabled no)
			(sheetname "")
		)
		(fill
			(thermal_gap 0.5)
			(thermal_bridge_width 0.5)
			(island_removal_mode 0)
		)
		(polygon
			(pts
				(arc
					(start 60.584588 -400.858228)
					(mid 59.881008 -400.858228)
					(end 60.584588 -400.858228)
				)
			)
		)
	)
	(zone
		(layer "B.Cu")
		(hatch none 0.5)
		(connect_pads
			(clearance 0)
		)
		(min_thickness 0.25)
		(keepout
			(tracks allowed)
			(vias allowed)
			(pads allowed)
			(copperpour allowed)
			(footprints allowed)
		)
		(placement
			(enabled no)
			(sheetname "")
		)
		(fill
			(thermal_gap 0.5)
			(thermal_bridge_width 0.5)
			(island_removal_mode 0)
		)
		(polygon
			(pts
				(xy 25.986486 -177.403252) (xy 33.631886 -177.403252) (xy 34.282126 -176.753012) (xy 34.282126 -169.427652)
				(xy 32.620966 -167.766492) (xy 25.950926 -167.766492) (xy 24.983186 -168.734232) (xy 24.983186 -176.399952)
			)
		)
	)
	(zone
		(layer "B.Cu")
		(hatch none 0.5)
		(connect_pads
			(clearance 0)
		)
		(min_thickness 0.25)
		(keepout
			(tracks allowed)
			(vias allowed)
			(pads allowed)
			(copperpour allowed)
			(footprints not_allowed)
		)
		(placement
			(enabled no)
			(sheetname "")
		)
		(fill
			(thermal_gap 0.5)
			(thermal_bridge_width 0.5)
			(island_removal_mode 0)
		)
		(polygon
			(pts
				(arc
					(start 254.124968 -360.764074)
					(mid 258.12496 -364.764066)
					(end 262.124952 -360.764074)
				)
				(arc
					(start 262.124952 -360.764074)
					(mid 258.12496 -356.764082)
					(end 254.124968 -360.764074)
				)
			)
		)
	)
	(zone
		(layer "B.Cu")
		(hatch none 0.5)
		(connect_pads
			(clearance 0)
		)
		(min_thickness 0.25)
		(keepout
			(tracks allowed)
			(vias allowed)
			(pads allowed)
			(copperpour allowed)
			(footprints not_allowed)
		)
		(placement
			(enabled no)
			(sheetname "")
		)
		(fill
			(thermal_gap 0.5)
			(thermal_bridge_width 0.5)
			(island_removal_mode 0)
		)
		(polygon
			(pts
				(arc
					(start 140.518896 -354.434902)
					(mid 136.518904 -350.43491)
					(end 132.518912 -354.434902)
				)
				(arc
					(start 132.518912 -354.434902)
					(mid 136.518904 -358.434894)
					(end 140.518896 -354.434902)
				)
			)
		)
	)
	(zone
		(layer "B.Cu")
		(hatch none 0.5)
		(connect_pads
			(clearance 0)
		)
		(min_thickness 0.25)
		(keepout
			(tracks not_allowed)
			(vias allowed)
			(pads allowed)
			(copperpour not_allowed)
			(footprints allowed)
		)
		(placement
			(enabled no)
			(sheetname "")
		)
		(fill
			(thermal_gap 0.5)
			(thermal_bridge_width 0.5)
			(island_removal_mode 0)
		)
		(polygon
			(pts
				(arc
					(start 349.09887 -225.203258)
					(mid 348.44609 -225.203258)
					(end 349.09887 -225.203258)
				)
			)
		)
	)
	(zone
		(layer "B.Cu")
		(hatch none 0.5)
		(connect_pads
			(clearance 0)
		)
		(min_thickness 0.25)
		(keepout
			(tracks not_allowed)
			(vias allowed)
			(pads allowed)
			(copperpour not_allowed)
			(footprints allowed)
		)
		(placement
			(enabled no)
			(sheetname "")
		)
		(fill
			(thermal_gap 0.5)
			(thermal_bridge_width 0.5)
			(island_removal_mode 0)
		)
		(polygon
			(pts
				(arc
					(start 350.508824 -224.389442)
					(mid 349.856044 -224.389442)
					(end 350.508824 -224.389442)
				)
			)
		)
	)
	(zone
		(layer "B.Cu")
		(hatch none 0.5)
		(connect_pads
			(clearance 0)
		)
		(min_thickness 0.25)
		(keepout
			(tracks allowed)
			(vias allowed)
			(pads allowed)
			(copperpour allowed)
			(footprints not_allowed)
		)
		(placement
			(enabled no)
			(sheetname "")
		)
		(fill
			(thermal_gap 0.5)
			(thermal_bridge_width 0.5)
			(island_removal_mode 0)
		)
		(polygon
			(pts
				(arc
					(start 102.860094 -261.5946)
					(mid 103.299396 -262.655168)
					(end 104.359964 -263.09447)
				)
				(arc
					(start 106.950002 -263.09447)
					(mid 108.010734 -262.655258)
					(end 108.450126 -261.5946)
				)
				(arc
					(start 108.450126 -237.06455)
					(mid 108.01075 -236.003802)
					(end 106.950002 -235.564426)
				)
				(arc
					(start 104.359964 -235.564426)
					(mid 103.29938 -236.003892)
					(end 102.860094 -237.06455)
				)
			)
		)
	)
	(zone
		(layer "B.Cu")
		(hatch none 0.5)
		(connect_pads
			(clearance 0)
		)
		(min_thickness 0.25)
		(keepout
			(tracks not_allowed)
			(vias allowed)
			(pads allowed)
			(copperpour not_allowed)
			(footprints allowed)
		)
		(placement
			(enabled no)
			(sheetname "")
		)
		(fill
			(thermal_gap 0.5)
			(thermal_bridge_width 0.5)
			(island_removal_mode 0)
		)
		(polygon
			(pts
				(arc
					(start 179.36337 -46.481746)
					(mid 178.65979 -46.481746)
					(end 179.36337 -46.481746)
				)
			)
		)
	)
	(zone
		(layer "B.Cu")
		(hatch none 0.5)
		(connect_pads
			(clearance 0)
		)
		(min_thickness 0.25)
		(keepout
			(tracks not_allowed)
			(vias allowed)
			(pads allowed)
			(copperpour not_allowed)
			(footprints allowed)
		)
		(placement
			(enabled no)
			(sheetname "")
		)
		(fill
			(thermal_gap 0.5)
			(thermal_bridge_width 0.5)
			(island_removal_mode 0)
		)
		(polygon
			(pts
				(arc
					(start 163.392104 -400.858228)
					(mid 162.688524 -400.858228)
					(end 163.392104 -400.858228)
				)
			)
		)
	)
	(zone
		(layer "B.Cu")
		(hatch none 0.5)
		(connect_pads
			(clearance 0)
		)
		(min_thickness 0.25)
		(keepout
			(tracks allowed)
			(vias allowed)
			(pads allowed)
			(copperpour allowed)
			(footprints allowed)
		)
		(placement
			(enabled no)
			(sheetname "")
		)
		(fill
			(thermal_gap 0.5)
			(thermal_bridge_width 0.5)
			(island_removal_mode 0)
		)
		(polygon
			(pts
				(xy 162.90798 -29.56306) (xy 162.90798 -27.79268) (xy 161.28746 -27.79268) (xy 161.28746 -29.56306)
			)
		)
	)
	(zone
		(layer "B.Cu")
		(hatch none 0.5)
		(connect_pads
			(clearance 0)
		)
		(min_thickness 0.25)
		(keepout
			(tracks allowed)
			(vias allowed)
			(pads allowed)
			(copperpour allowed)
			(footprints allowed)
		)
		(placement
			(enabled no)
			(sheetname "")
		)
		(fill
			(thermal_gap 0.5)
			(thermal_bridge_width 0.5)
			(island_removal_mode 0)
		)
		(polygon
			(pts
				(xy 358.8512 -61.32068) (xy 358.8512 -60.64758) (xy 360.19994 -60.64758) (xy 360.19994 -61.32068)
			)
		)
	)
	(zone
		(layer "B.Cu")
		(hatch none 0.5)
		(connect_pads
			(clearance 0)
		)
		(min_thickness 0.25)
		(keepout
			(tracks allowed)
			(vias allowed)
			(pads allowed)
			(copperpour allowed)
			(footprints allowed)
		)
		(placement
			(enabled no)
			(sheetname "")
		)
		(fill
			(thermal_gap 0.5)
			(thermal_bridge_width 0.5)
			(island_removal_mode 0)
		)
		(polygon
			(pts
				(xy 348.33052 -45.2882) (xy 348.33052 -44.53128) (xy 350.83242 -44.53128) (xy 350.83242 -45.2882)
			)
		)
	)
	(zone
		(layer "B.Cu")
		(hatch none 0.5)
		(connect_pads
			(clearance 0)
		)
		(min_thickness 0.25)
		(keepout
			(tracks not_allowed)
			(vias allowed)
			(pads allowed)
			(copperpour not_allowed)
			(footprints allowed)
		)
		(placement
			(enabled no)
			(sheetname "")
		)
		(fill
			(thermal_gap 0.5)
			(thermal_bridge_width 0.5)
			(island_removal_mode 0)
		)
		(polygon
			(pts
				(arc
					(start 42.18813 -385.575556)
					(mid 41.48455 -385.575556)
					(end 42.18813 -385.575556)
				)
			)
		)
	)
	(zone
		(layer "B.Cu")
		(hatch none 0.5)
		(connect_pads
			(clearance 0)
		)
		(min_thickness 0.25)
		(keepout
			(tracks not_allowed)
			(vias allowed)
			(pads allowed)
			(copperpour not_allowed)
			(footprints allowed)
		)
		(placement
			(enabled no)
			(sheetname "")
		)
		(fill
			(thermal_gap 0.5)
			(thermal_bridge_width 0.5)
			(island_removal_mode 0)
		)
		(polygon
			(pts
				(arc
					(start 356.125018 -431.360072)
					(mid 359.774998 -435.010052)
					(end 363.424978 -431.360072)
				)
				(arc
					(start 363.424978 -431.360072)
					(mid 359.774998 -427.710092)
					(end 356.125018 -431.360072)
				)
			)
		)
	)
	(zone
		(layer "B.Cu")
		(hatch none 0.5)
		(connect_pads
			(clearance 0)
		)
		(min_thickness 0.25)
		(keepout
			(tracks not_allowed)
			(vias allowed)
			(pads allowed)
			(copperpour not_allowed)
			(footprints allowed)
		)
		(placement
			(enabled no)
			(sheetname "")
		)
		(fill
			(thermal_gap 0.5)
			(thermal_bridge_width 0.5)
			(island_removal_mode 0)
		)
		(polygon
			(pts
				(arc
					(start 260.649974 -22.29993)
					(mid 265.649964 -27.29992)
					(end 270.649954 -22.29993)
				)
				(arc
					(start 270.649954 -22.29993)
					(mid 265.649964 -17.29994)
					(end 260.649974 -22.29993)
				)
			)
		)
	)
	(zone
		(layer "B.Cu")
		(hatch none 0.5)
		(connect_pads
			(clearance 0)
		)
		(min_thickness 0.25)
		(keepout
			(tracks allowed)
			(vias allowed)
			(pads allowed)
			(copperpour allowed)
			(footprints not_allowed)
		)
		(placement
			(enabled no)
			(sheetname "")
		)
		(fill
			(thermal_gap 0.5)
			(thermal_bridge_width 0.5)
			(island_removal_mode 0)
		)
		(polygon
			(pts
				(arc
					(start 263.645396 -51.999896)
					(mid 268.645386 -56.999886)
					(end 273.645376 -51.999896)
				)
				(arc
					(start 273.645376 -51.999896)
					(mid 268.645386 -46.999906)
					(end 263.645396 -51.999896)
				)
			)
		)
	)
	(zone
		(layer "B.Cu")
		(hatch none 0.5)
		(connect_pads
			(clearance 0)
		)
		(min_thickness 0.25)
		(keepout
			(tracks not_allowed)
			(vias allowed)
			(pads allowed)
			(copperpour not_allowed)
			(footprints allowed)
		)
		(placement
			(enabled no)
			(sheetname "")
		)
		(fill
			(thermal_gap 0.5)
			(thermal_bridge_width 0.5)
			(island_removal_mode 0)
		)
		(polygon
			(pts
				(arc
					(start 458.659992 -160.50006)
					(mid 461.460088 -163.300156)
					(end 464.25993 -160.50006)
				)
				(arc
					(start 464.25993 -160.50006)
					(mid 461.460088 -157.700218)
					(end 458.659992 -160.50006)
				)
			)
		)
	)
	(zone
		(layer "B.Cu")
		(hatch none 0.5)
		(connect_pads
			(clearance 0)
		)
		(min_thickness 0.25)
		(keepout
			(tracks not_allowed)
			(vias allowed)
			(pads allowed)
			(copperpour not_allowed)
			(footprints allowed)
		)
		(placement
			(enabled no)
			(sheetname "")
		)
		(fill
			(thermal_gap 0.5)
			(thermal_bridge_width 0.5)
			(island_removal_mode 0)
		)
		(polygon
			(pts
				(arc
					(start 130.762756 -224.389442)
					(mid 130.109976 -224.389442)
					(end 130.762756 -224.389442)
				)
			)
		)
	)
	(zone
		(layer "B.Cu")
		(hatch none 0.5)
		(connect_pads
			(clearance 0)
		)
		(min_thickness 0.25)
		(keepout
			(tracks allowed)
			(vias allowed)
			(pads allowed)
			(copperpour allowed)
			(footprints allowed)
		)
		(placement
			(enabled no)
			(sheetname "")
		)
		(fill
			(thermal_gap 0.5)
			(thermal_bridge_width 0.5)
			(island_removal_mode 0)
		)
		(polygon
			(pts
				(xy 231.10444 -36.87572) (xy 231.10444 -35.72002) (xy 232.09504 -35.72002) (xy 232.09504 -36.87572)
			)
		)
	)
	(zone
		(layer "B.Cu")
		(hatch none 0.5)
		(connect_pads
			(clearance 0)
		)
		(min_thickness 0.25)
		(keepout
			(tracks not_allowed)
			(vias allowed)
			(pads allowed)
			(copperpour not_allowed)
			(footprints allowed)
		)
		(placement
			(enabled no)
			(sheetname "")
		)
		(fill
			(thermal_gap 0.5)
			(thermal_bridge_width 0.5)
			(island_removal_mode 0)
		)
		(polygon
			(pts
				(arc
					(start 67.574668 -400.858228)
					(mid 66.871088 -400.858228)
					(end 67.574668 -400.858228)
				)
			)
		)
	)
	(zone
		(layer "B.Cu")
		(hatch none 0.5)
		(connect_pads
			(clearance 0)
		)
		(min_thickness 0.25)
		(keepout
			(tracks not_allowed)
			(vias allowed)
			(pads allowed)
			(copperpour not_allowed)
			(footprints allowed)
		)
		(placement
			(enabled no)
			(sheetname "")
		)
		(fill
			(thermal_gap 0.5)
			(thermal_bridge_width 0.5)
			(island_removal_mode 0)
		)
		(polygon
			(pts
				(xy 128.76022 -25.596088) (xy 128.76022 -25.359868) (xy 128.601978 -25.359868) (xy 128.601978 -25.75433)
				(xy 128.76022 -25.75433)
			)
		)
	)
	(zone
		(layer "B.Cu")
		(hatch none 0.5)
		(connect_pads
			(clearance 0)
		)
		(min_thickness 0.25)
		(keepout
			(tracks allowed)
			(vias allowed)
			(pads allowed)
			(copperpour allowed)
			(footprints not_allowed)
		)
		(placement
			(enabled no)
			(sheetname "")
		)
		(fill
			(thermal_gap 0.5)
			(thermal_bridge_width 0.5)
			(island_removal_mode 0)
		)
		(polygon
			(pts
				(xy 312.040016 -310.522112) (xy 312.040016 -273.02206) (xy 257.040126 -273.02206) (xy 257.040126 -310.522112)
			)
		)
	)
	(zone
		(layer "B.Cu")
		(hatch none 0.5)
		(connect_pads
			(clearance 0)
		)
		(min_thickness 0.25)
		(keepout
			(tracks allowed)
			(vias allowed)
			(pads allowed)
			(copperpour allowed)
			(footprints allowed)
		)
		(placement
			(enabled no)
			(sheetname "")
		)
		(fill
			(thermal_gap 0.5)
			(thermal_bridge_width 0.5)
			(island_removal_mode 0)
		)
		(polygon
			(pts
				(xy 138.89228 -21.03374) (xy 138.89228 -20.05838) (xy 140.40104 -20.05838) (xy 140.40104 -21.03374)
			)
		)
	)
	(zone
		(layer "B.Cu")
		(hatch none 0.5)
		(connect_pads
			(clearance 0)
		)
		(min_thickness 0.25)
		(keepout
			(tracks not_allowed)
			(vias allowed)
			(pads allowed)
			(copperpour not_allowed)
			(footprints allowed)
		)
		(placement
			(enabled no)
			(sheetname "")
		)
		(fill
			(thermal_gap 0.5)
			(thermal_bridge_width 0.5)
			(island_removal_mode 0)
		)
		(polygon
			(pts
				(arc
					(start 378.100082 -22.29993)
					(mid 380.900178 -25.100026)
					(end 383.70002 -22.29993)
				)
				(arc
					(start 383.70002 -22.29993)
					(mid 380.900178 -19.500088)
					(end 378.100082 -22.29993)
				)
			)
		)
	)
	(zone
		(layer "B.Cu")
		(hatch none 0.5)
		(connect_pads
			(clearance 0)
		)
		(min_thickness 0.25)
		(keepout
			(tracks allowed)
			(vias allowed)
			(pads allowed)
			(copperpour allowed)
			(footprints allowed)
		)
		(placement
			(enabled no)
			(sheetname "")
		)
		(fill
			(thermal_gap 0.5)
			(thermal_bridge_width 0.5)
			(island_removal_mode 0)
		)
		(polygon
			(pts
				(xy 50.507646 -149.2504) (xy 53.167026 -149.2504) (xy 53.476906 -148.94052) (xy 53.476906 -145.71726)
				(xy 53.824886 -145.36928) (xy 55.874666 -145.36928) (xy 56.311546 -144.9324) (xy 56.311546 -143.3576)
				(xy 55.552086 -142.59814) (xy 52.453286 -142.59814) (xy 52.366926 -142.6845) (xy 52.366926 -144.51076)
				(xy 52.206906 -144.67078) (xy 50.708306 -144.67078) (xy 50.367946 -145.01114) (xy 50.367946 -149.1107)
			)
		)
	)
	(zone
		(layer "B.Cu")
		(hatch none 0.5)
		(connect_pads
			(clearance 0)
		)
		(min_thickness 0.25)
		(keepout
			(tracks not_allowed)
			(vias allowed)
			(pads allowed)
			(copperpour not_allowed)
			(footprints allowed)
		)
		(placement
			(enabled no)
			(sheetname "")
		)
		(fill
			(thermal_gap 0.5)
			(thermal_bridge_width 0.5)
			(island_removal_mode 0)
		)
		(polygon
			(pts
				(arc
					(start 341.110824 -224.389442)
					(mid 340.458044 -224.389442)
					(end 341.110824 -224.389442)
				)
			)
		)
	)
	(zone
		(layer "B.Cu")
		(hatch none 0.5)
		(connect_pads
			(clearance 0)
		)
		(min_thickness 0.25)
		(keepout
			(tracks allowed)
			(vias allowed)
			(pads allowed)
			(copperpour allowed)
			(footprints allowed)
		)
		(placement
			(enabled no)
			(sheetname "")
		)
		(fill
			(thermal_gap 0.5)
			(thermal_bridge_width 0.5)
			(island_removal_mode 0)
		)
		(polygon
			(pts
				(xy 127.19304 -26.932128) (xy 127.19304 -25.669748) (xy 128.4859 -25.669748) (xy 128.4859 -26.932128)
			)
		)
	)
	(zone
		(layer "B.Cu")
		(hatch none 0.5)
		(connect_pads
			(clearance 0)
		)
		(min_thickness 0.25)
		(keepout
			(tracks not_allowed)
			(vias allowed)
			(pads allowed)
			(copperpour not_allowed)
			(footprints allowed)
		)
		(placement
			(enabled no)
			(sheetname "")
		)
		(fill
			(thermal_gap 0.5)
			(thermal_bridge_width 0.5)
			(island_removal_mode 0)
		)
		(polygon
			(pts
				(arc
					(start 107.83951 -407.111708)
					(mid 107.13593 -407.111708)
					(end 107.83951 -407.111708)
				)
			)
		)
	)
	(zone
		(layer "B.Cu")
		(hatch none 0.5)
		(connect_pads
			(clearance 0)
		)
		(min_thickness 0.25)
		(keepout
			(tracks not_allowed)
			(vias allowed)
			(pads allowed)
			(copperpour not_allowed)
			(footprints allowed)
		)
		(placement
			(enabled no)
			(sheetname "")
		)
		(fill
			(thermal_gap 0.5)
			(thermal_bridge_width 0.5)
			(island_removal_mode 0)
		)
		(polygon
			(pts
				(arc
					(start 296.349928 -435.600094)
					(mid 293.550086 -432.800252)
					(end 290.74999 -435.600094)
				)
				(arc
					(start 290.74999 -435.600094)
					(mid 293.550086 -438.40019)
					(end 296.349928 -435.600094)
				)
			)
		)
	)
	(zone
		(layer "B.Cu")
		(hatch none 0.5)
		(connect_pads
			(clearance 0)
		)
		(min_thickness 0.25)
		(keepout
			(tracks allowed)
			(vias allowed)
			(pads allowed)
			(copperpour allowed)
			(footprints not_allowed)
		)
		(placement
			(enabled no)
			(sheetname "")
		)
		(fill
			(thermal_gap 0.5)
			(thermal_bridge_width 0.5)
			(island_removal_mode 0)
		)
		(polygon
			(pts
				(arc
					(start 165.1 -160.50006)
					(mid 167.900096 -163.300156)
					(end 170.699938 -160.50006)
				)
				(arc
					(start 170.699938 -160.50006)
					(mid 167.900096 -157.700218)
					(end 165.1 -160.50006)
				)
			)
		)
	)
	(zone
		(layer "B.Cu")
		(hatch none 0.5)
		(connect_pads
			(clearance 0)
		)
		(min_thickness 0.25)
		(keepout
			(tracks allowed)
			(vias allowed)
			(pads allowed)
			(copperpour allowed)
			(footprints allowed)
		)
		(placement
			(enabled no)
			(sheetname "")
		)
		(fill
			(thermal_gap 0.5)
			(thermal_bridge_width 0.5)
			(island_removal_mode 0)
		)
		(polygon
			(pts
				(xy 345.21394 -64.592708) (xy 345.21394 -63.609728) (xy 346.8624 -63.609728) (xy 346.8624 -64.592708)
			)
		)
	)
	(zone
		(layer "B.Cu")
		(hatch none 0.5)
		(connect_pads
			(clearance 0)
		)
		(min_thickness 0.25)
		(keepout
			(tracks allowed)
			(vias allowed)
			(pads allowed)
			(copperpour allowed)
			(footprints not_allowed)
		)
		(placement
			(enabled no)
			(sheetname "")
		)
		(fill
			(thermal_gap 0.5)
			(thermal_bridge_width 0.5)
			(island_removal_mode 0)
		)
		(polygon
			(pts
				(xy 63.840106 -273.02206) (xy 8.839962 -273.02206) (xy 8.839962 -310.522112) (xy 63.840106 -310.522112)
			)
		)
	)
	(zone
		(layer "B.Cu")
		(hatch none 0.5)
		(connect_pads
			(clearance 0)
		)
		(min_thickness 0.25)
		(keepout
			(tracks not_allowed)
			(vias allowed)
			(pads allowed)
			(copperpour not_allowed)
			(footprints allowed)
		)
		(placement
			(enabled no)
			(sheetname "")
		)
		(fill
			(thermal_gap 0.5)
			(thermal_bridge_width 0.5)
			(island_removal_mode 0)
		)
		(polygon
			(pts
				(arc
					(start 368.365024 -224.389442)
					(mid 367.712244 -224.389442)
					(end 368.365024 -224.389442)
				)
			)
		)
	)
	(zone
		(layer "B.Cu")
		(hatch none 0.5)
		(connect_pads
			(clearance 0)
		)
		(min_thickness 0.25)
		(keepout
			(tracks allowed)
			(vias allowed)
			(pads allowed)
			(copperpour allowed)
			(footprints allowed)
		)
		(placement
			(enabled no)
			(sheetname "")
		)
		(fill
			(thermal_gap 0.5)
			(thermal_bridge_width 0.5)
			(island_removal_mode 0)
		)
		(polygon
			(pts
				(xy 237.36808 -37.00272) (xy 237.36808 -35.79368) (xy 236.30128 -35.79368) (xy 236.30128 -37.00272)
			)
		)
	)
	(zone
		(layer "B.Cu")
		(hatch none 0.5)
		(connect_pads
			(clearance 0)
		)
		(min_thickness 0.25)
		(keepout
			(tracks not_allowed)
			(vias allowed)
			(pads allowed)
			(copperpour not_allowed)
			(footprints allowed)
		)
		(placement
			(enabled no)
			(sheetname "")
		)
		(fill
			(thermal_gap 0.5)
			(thermal_bridge_width 0.5)
			(island_removal_mode 0)
		)
		(polygon
			(pts
				(arc
					(start 343.46007 -225.203258)
					(mid 342.80729 -225.203258)
					(end 343.46007 -225.203258)
				)
			)
		)
	)
	(zone
		(layer "B.Cu")
		(hatch none 0.5)
		(connect_pads
			(clearance 0)
		)
		(min_thickness 0.25)
		(keepout
			(tracks not_allowed)
			(vias allowed)
			(pads allowed)
			(copperpour not_allowed)
			(footprints allowed)
		)
		(placement
			(enabled no)
			(sheetname "")
		)
		(fill
			(thermal_gap 0.5)
			(thermal_bridge_width 0.5)
			(island_removal_mode 0)
		)
		(polygon
			(pts
				(arc
					(start 351.91827 -223.575626)
					(mid 351.26549 -223.575626)
					(end 351.91827 -223.575626)
				)
			)
		)
	)
	(zone
		(layer "B.Cu")
		(hatch none 0.5)
		(connect_pads
			(clearance 0)
		)
		(min_thickness 0.25)
		(keepout
			(tracks not_allowed)
			(vias allowed)
			(pads allowed)
			(copperpour not_allowed)
			(footprints allowed)
		)
		(placement
			(enabled no)
			(sheetname "")
		)
		(fill
			(thermal_gap 0.5)
			(thermal_bridge_width 0.5)
			(island_removal_mode 0)
		)
		(polygon
			(pts
				(arc
					(start 136.686544 -400.858228)
					(mid 135.982964 -400.858228)
					(end 136.686544 -400.858228)
				)
			)
		)
	)
	(zone
		(layer "B.Cu")
		(hatch none 0.5)
		(connect_pads
			(clearance 0)
		)
		(min_thickness 0.25)
		(keepout
			(tracks not_allowed)
			(vias allowed)
			(pads allowed)
			(copperpour not_allowed)
			(footprints allowed)
		)
		(placement
			(enabled no)
			(sheetname "")
		)
		(fill
			(thermal_gap 0.5)
			(thermal_bridge_width 0.5)
			(island_removal_mode 0)
		)
		(polygon
			(pts
				(arc
					(start 91.760802 -225.203258)
					(mid 91.108022 -225.203258)
					(end 91.760802 -225.203258)
				)
			)
		)
	)
	(zone
		(layer "B.Cu")
		(hatch none 0.5)
		(connect_pads
			(clearance 0)
		)
		(min_thickness 0.25)
		(keepout
			(tracks allowed)
			(vias allowed)
			(pads allowed)
			(copperpour allowed)
			(footprints allowed)
		)
		(placement
			(enabled no)
			(sheetname "")
		)
		(fill
			(thermal_gap 0.5)
			(thermal_bridge_width 0.5)
			(island_removal_mode 0)
		)
		(polygon
			(pts
				(xy 345.45016 -338.201508) (xy 345.45016 -335.445608) (xy 340.3473 -335.445608) (xy 340.3473 -338.201508)
			)
		)
	)
	(zone
		(layer "B.Cu")
		(hatch none 0.5)
		(connect_pads
			(clearance 0)
		)
		(min_thickness 0.25)
		(keepout
			(tracks allowed)
			(vias allowed)
			(pads allowed)
			(copperpour allowed)
			(footprints allowed)
		)
		(placement
			(enabled no)
			(sheetname "")
		)
		(fill
			(thermal_gap 0.5)
			(thermal_bridge_width 0.5)
			(island_removal_mode 0)
		)
		(polygon
			(pts
				(xy 432.08956 -194.313048) (xy 432.08956 -192.918588) (xy 434.50002 -192.918588) (xy 434.50002 -194.313048)
			)
		)
	)
	(zone
		(layer "B.Cu")
		(hatch none 0.5)
		(connect_pads
			(clearance 0)
		)
		(min_thickness 0.25)
		(keepout
			(tracks allowed)
			(vias allowed)
			(pads allowed)
			(copperpour allowed)
			(footprints not_allowed)
		)
		(placement
			(enabled no)
			(sheetname "")
		)
		(fill
			(thermal_gap 0.5)
			(thermal_bridge_width 0.5)
			(island_removal_mode 0)
		)
		(polygon
			(pts
				(arc
					(start 249.150124 -272.50009)
					(mid 236.650022 -259.999988)
					(end 224.14992 -272.50009)
				)
				(arc
					(start 224.14992 -272.50009)
					(mid 236.650022 -285.000192)
					(end 249.150124 -272.50009)
				)
			)
		)
	)
	(zone
		(layer "B.Cu")
		(hatch none 0.5)
		(connect_pads
			(clearance 0)
		)
		(min_thickness 0.25)
		(keepout
			(tracks allowed)
			(vias allowed)
			(pads allowed)
			(copperpour allowed)
			(footprints allowed)
		)
		(placement
			(enabled no)
			(sheetname "")
		)
		(fill
			(thermal_gap 0.5)
			(thermal_bridge_width 0.5)
			(island_removal_mode 0)
		)
		(polygon
			(pts
				(xy 156.74848 -46.58868) (xy 156.74848 -43.80738) (xy 156.00934 -43.80738) (xy 156.00934 -46.58868)
			)
		)
	)
	(zone
		(layer "B.Cu")
		(hatch none 0.5)
		(connect_pads
			(clearance 0)
		)
		(min_thickness 0.25)
		(keepout
			(tracks allowed)
			(vias allowed)
			(pads allowed)
			(copperpour allowed)
			(footprints allowed)
		)
		(placement
			(enabled no)
			(sheetname "")
		)
		(fill
			(thermal_gap 0.5)
			(thermal_bridge_width 0.5)
			(island_removal_mode 0)
		)
		(polygon
			(pts
				(xy 105.82402 -363.085888) (xy 112.60328 -363.085888) (xy 112.60328 -365.539528) (xy 105.82402 -365.539528)
				(xy 104.8258 -365.539528) (xy 104.29748 -365.011208) (xy 104.29748 -363.507528) (xy 104.71912 -363.085888)
			)
		)
	)
	(zone
		(layer "B.Cu")
		(hatch none 0.5)
		(connect_pads
			(clearance 0)
		)
		(min_thickness 0.25)
		(keepout
			(tracks not_allowed)
			(vias allowed)
			(pads allowed)
			(copperpour not_allowed)
			(footprints allowed)
		)
		(placement
			(enabled no)
			(sheetname "")
		)
		(fill
			(thermal_gap 0.5)
			(thermal_bridge_width 0.5)
			(island_removal_mode 0)
		)
		(polygon
			(pts
				(arc
					(start 179.36337 -51.618134)
					(mid 178.65979 -51.618134)
					(end 179.36337 -51.618134)
				)
			)
		)
	)
	(zone
		(layer "B.Cu")
		(hatch none 0.5)
		(connect_pads
			(clearance 0)
		)
		(min_thickness 0.25)
		(keepout
			(tracks allowed)
			(vias allowed)
			(pads allowed)
			(copperpour allowed)
			(footprints allowed)
		)
		(placement
			(enabled no)
			(sheetname "")
		)
		(fill
			(thermal_gap 0.5)
			(thermal_bridge_width 0.5)
			(island_removal_mode 0)
		)
		(polygon
			(pts
				(xy 26.81478 -193.134488) (xy 26.81478 -192.481708) (xy 28.03652 -192.481708) (xy 28.03652 -193.134488)
			)
		)
	)
	(zone
		(layer "B.Cu")
		(hatch none 0.5)
		(connect_pads
			(clearance 0)
		)
		(min_thickness 0.25)
		(keepout
			(tracks allowed)
			(vias allowed)
			(pads allowed)
			(copperpour allowed)
			(footprints allowed)
		)
		(placement
			(enabled no)
			(sheetname "")
		)
		(fill
			(thermal_gap 0.5)
			(thermal_bridge_width 0.5)
			(island_removal_mode 0)
		)
		(polygon
			(pts
				(xy 262.92048 -33.07588) (xy 262.92048 -32.0929) (xy 262.0899 -32.0929) (xy 262.0899 -33.07588)
			)
		)
	)
	(zone
		(layer "B.Cu")
		(hatch none 0.5)
		(connect_pads
			(clearance 0)
		)
		(min_thickness 0.25)
		(keepout
			(tracks not_allowed)
			(vias allowed)
			(pads allowed)
			(copperpour not_allowed)
			(footprints allowed)
		)
		(placement
			(enabled no)
			(sheetname "")
		)
		(fill
			(thermal_gap 0.5)
			(thermal_bridge_width 0.5)
			(island_removal_mode 0)
		)
		(polygon
			(pts
				(arc
					(start 305.678078 -407.00452)
					(mid 304.974498 -407.00452)
					(end 305.678078 -407.00452)
				)
			)
		)
	)
	(zone
		(layer "B.Cu")
		(hatch none 0.5)
		(connect_pads
			(clearance 0)
		)
		(min_thickness 0.25)
		(keepout
			(tracks not_allowed)
			(vias allowed)
			(pads allowed)
			(copperpour not_allowed)
			(footprints allowed)
		)
		(placement
			(enabled no)
			(sheetname "")
		)
		(fill
			(thermal_gap 0.5)
			(thermal_bridge_width 0.5)
			(island_removal_mode 0)
		)
		(polygon
			(pts
				(arc
					(start 123.714002 -225.203258)
					(mid 123.061222 -225.203258)
					(end 123.714002 -225.203258)
				)
			)
		)
	)
	(zone
		(layer "B.Cu")
		(hatch none 0.5)
		(connect_pads
			(clearance 0)
		)
		(min_thickness 0.25)
		(keepout
			(tracks allowed)
			(vias allowed)
			(pads allowed)
			(copperpour allowed)
			(footprints allowed)
		)
		(placement
			(enabled no)
			(sheetname "")
		)
		(fill
			(thermal_gap 0.5)
			(thermal_bridge_width 0.5)
			(island_removal_mode 0)
		)
		(polygon
			(pts
				(xy 373.3419 -341.539068) (xy 373.3419 -338.295488) (xy 377.70816 -338.295488) (xy 377.70816 -341.539068)
			)
		)
	)
	(zone
		(layer "B.Cu")
		(hatch none 0.5)
		(connect_pads
			(clearance 0)
		)
		(min_thickness 0.25)
		(keepout
			(tracks not_allowed)
			(vias allowed)
			(pads allowed)
			(copperpour not_allowed)
			(footprints allowed)
		)
		(placement
			(enabled no)
			(sheetname "")
		)
		(fill
			(thermal_gap 0.5)
			(thermal_bridge_width 0.5)
			(island_removal_mode 0)
		)
		(polygon
			(pts
				(arc
					(start 4.19989 -22.29993)
					(mid 6.999986 -25.100026)
					(end 9.800082 -22.29993)
				)
				(arc
					(start 9.800082 -22.29993)
					(mid 6.999986 -19.499834)
					(end 4.19989 -22.29993)
				)
			)
		)
	)
	(zone
		(layer "B.Cu")
		(hatch none 0.5)
		(connect_pads
			(clearance 0)
		)
		(min_thickness 0.25)
		(keepout
			(tracks not_allowed)
			(vias allowed)
			(pads allowed)
			(copperpour not_allowed)
			(footprints allowed)
		)
		(placement
			(enabled no)
			(sheetname "")
		)
		(fill
			(thermal_gap 0.5)
			(thermal_bridge_width 0.5)
			(island_removal_mode 0)
		)
		(polygon
			(pts
				(arc
					(start 382.462024 -224.389442)
					(mid 381.809244 -224.389442)
					(end 382.462024 -224.389442)
				)
			)
		)
	)
	(zone
		(layer "B.Cu")
		(hatch none 0.5)
		(connect_pads
			(clearance 0)
		)
		(min_thickness 0.25)
		(keepout
			(tracks not_allowed)
			(vias allowed)
			(pads allowed)
			(copperpour not_allowed)
			(footprints allowed)
		)
		(placement
			(enabled no)
			(sheetname "")
		)
		(fill
			(thermal_gap 0.5)
			(thermal_bridge_width 0.5)
			(island_removal_mode 0)
		)
		(polygon
			(pts
				(arc
					(start 357.178356 -46.802802)
					(mid 356.474776 -46.802802)
					(end 357.178356 -46.802802)
				)
			)
		)
	)
	(zone
		(layer "B.Cu")
		(hatch none 0.5)
		(connect_pads
			(clearance 0)
		)
		(min_thickness 0.25)
		(keepout
			(tracks allowed)
			(vias allowed)
			(pads allowed)
			(copperpour allowed)
			(footprints not_allowed)
		)
		(placement
			(enabled no)
			(sheetname "")
		)
		(fill
			(thermal_gap 0.5)
			(thermal_bridge_width 0.5)
			(island_removal_mode 0)
		)
		(polygon
			(pts
				(arc
					(start 313.99988 -68.449952)
					(mid 316.900052 -71.350124)
					(end 319.79997 -68.449952)
				)
				(arc
					(start 319.79997 -68.449952)
					(mid 316.900052 -65.550034)
					(end 313.99988 -68.449952)
				)
			)
		)
	)
	(zone
		(layer "B.Cu")
		(hatch none 0.5)
		(connect_pads
			(clearance 0)
		)
		(min_thickness 0.25)
		(keepout
			(tracks allowed)
			(vias allowed)
			(pads allowed)
			(copperpour allowed)
			(footprints not_allowed)
		)
		(placement
			(enabled no)
			(sheetname "")
		)
		(fill
			(thermal_gap 0.5)
			(thermal_bridge_width 0.5)
			(island_removal_mode 0)
		)
		(polygon
			(pts
				(arc
					(start 97.700338 -435.600094)
					(mid 100.500434 -438.40019)
					(end 103.300276 -435.600094)
				)
				(arc
					(start 103.300276 -435.600094)
					(mid 100.500434 -432.800252)
					(end 97.700338 -435.600094)
				)
			)
		)
	)
	(zone
		(layer "B.Cu")
		(hatch none 0.5)
		(connect_pads
			(clearance 0)
		)
		(min_thickness 0.25)
		(keepout
			(tracks not_allowed)
			(vias allowed)
			(pads allowed)
			(copperpour not_allowed)
			(footprints allowed)
		)
		(placement
			(enabled no)
			(sheetname "")
		)
		(fill
			(thermal_gap 0.5)
			(thermal_bridge_width 0.5)
			(island_removal_mode 0)
		)
		(polygon
			(pts
				(arc
					(start 467.549992 -32.29991)
					(mid 464.800188 -29.550106)
					(end 462.05013 -32.29991)
				)
				(arc
					(start 462.05013 -33.899856)
					(mid 464.800188 -36.649914)
					(end 467.549992 -33.899856)
				)
			)
		)
	)
	(zone
		(layer "B.Cu")
		(hatch none 0.5)
		(connect_pads
			(clearance 0)
		)
		(min_thickness 0.25)
		(keepout
			(tracks not_allowed)
			(vias allowed)
			(pads allowed)
			(copperpour not_allowed)
			(footprints allowed)
		)
		(placement
			(enabled no)
			(sheetname "")
		)
		(fill
			(thermal_gap 0.5)
			(thermal_bridge_width 0.5)
			(island_removal_mode 0)
		)
		(polygon
			(pts
				(arc
					(start 179.36337 -49.48174)
					(mid 178.65979 -49.48174)
					(end 179.36337 -49.48174)
				)
			)
		)
	)
	(zone
		(layer "B.Cu")
		(hatch none 0.5)
		(connect_pads
			(clearance 0)
		)
		(min_thickness 0.25)
		(keepout
			(tracks not_allowed)
			(vias allowed)
			(pads allowed)
			(copperpour not_allowed)
			(footprints allowed)
		)
		(placement
			(enabled no)
			(sheetname "")
		)
		(fill
			(thermal_gap 0.5)
			(thermal_bridge_width 0.5)
			(island_removal_mode 0)
		)
		(polygon
			(pts
				(arc
					(start 131.702556 -224.389442)
					(mid 131.049776 -224.389442)
					(end 131.702556 -224.389442)
				)
			)
		)
	)
	(zone
		(layer "B.Cu")
		(hatch none 0.5)
		(connect_pads
			(clearance 0)
		)
		(min_thickness 0.25)
		(keepout
			(tracks not_allowed)
			(vias allowed)
			(pads allowed)
			(copperpour not_allowed)
			(footprints allowed)
		)
		(placement
			(enabled no)
			(sheetname "")
		)
		(fill
			(thermal_gap 0.5)
			(thermal_bridge_width 0.5)
			(island_removal_mode 0)
		)
		(polygon
			(pts
				(arc
					(start 66.711068 -400.858228)
					(mid 66.007488 -400.858228)
					(end 66.711068 -400.858228)
				)
			)
		)
	)
	(zone
		(layer "B.Cu")
		(hatch none 0.5)
		(connect_pads
			(clearance 0)
		)
		(min_thickness 0.25)
		(keepout
			(tracks not_allowed)
			(vias allowed)
			(pads allowed)
			(copperpour not_allowed)
			(footprints allowed)
		)
		(placement
			(enabled no)
			(sheetname "")
		)
		(fill
			(thermal_gap 0.5)
			(thermal_bridge_width 0.5)
			(island_removal_mode 0)
		)
		(polygon
			(pts
				(arc
					(start 121.370344 -400.858228)
					(mid 120.666764 -400.858228)
					(end 121.370344 -400.858228)
				)
			)
		)
	)
	(zone
		(layer "B.Cu")
		(hatch none 0.5)
		(connect_pads
			(clearance 0)
		)
		(min_thickness 0.25)
		(keepout
			(tracks allowed)
			(vias allowed)
			(pads allowed)
			(copperpour allowed)
			(footprints allowed)
		)
		(placement
			(enabled no)
			(sheetname "")
		)
		(fill
			(thermal_gap 0.5)
			(thermal_bridge_width 0.5)
			(island_removal_mode 0)
		)
		(polygon
			(pts
				(xy 77.43698 -350.810068) (xy 77.43698 -349.324168) (xy 76.3143 -349.324168) (xy 76.3143 -350.810068)
			)
		)
	)
	(zone
		(layer "B.Cu")
		(hatch none 0.5)
		(connect_pads
			(clearance 0)
		)
		(min_thickness 0.25)
		(keepout
			(tracks allowed)
			(vias allowed)
			(pads allowed)
			(copperpour allowed)
			(footprints allowed)
		)
		(placement
			(enabled no)
			(sheetname "")
		)
		(fill
			(thermal_gap 0.5)
			(thermal_bridge_width 0.5)
			(island_removal_mode 0)
		)
		(polygon
			(pts
				(xy 356.25532 -35.93846) (xy 356.25532 -34.92754) (xy 359.34396 -34.92754) (xy 359.34396 -35.93846)
			)
		)
	)
	(zone
		(layer "B.Cu")
		(hatch none 0.5)
		(connect_pads
			(clearance 0)
		)
		(min_thickness 0.25)
		(keepout
			(tracks not_allowed)
			(vias allowed)
			(pads allowed)
			(copperpour not_allowed)
			(footprints allowed)
		)
		(placement
			(enabled no)
			(sheetname "")
		)
		(fill
			(thermal_gap 0.5)
			(thermal_bridge_width 0.5)
			(island_removal_mode 0)
		)
		(polygon
			(pts
				(arc
					(start 314.867798 -407.00452)
					(mid 314.164218 -407.00452)
					(end 314.867798 -407.00452)
				)
			)
		)
	)
	(zone
		(layer "B.Cu")
		(hatch none 0.5)
		(connect_pads
			(clearance 0)
		)
		(min_thickness 0.25)
		(keepout
			(tracks not_allowed)
			(vias allowed)
			(pads allowed)
			(copperpour not_allowed)
			(footprints allowed)
		)
		(placement
			(enabled no)
			(sheetname "")
		)
		(fill
			(thermal_gap 0.5)
			(thermal_bridge_width 0.5)
			(island_removal_mode 0)
		)
		(polygon
			(pts
				(arc
					(start 98.482912 -47.049944)
					(mid 100.382832 -48.949864)
					(end 102.282752 -47.049944)
				)
				(arc
					(start 102.282752 -47.049944)
					(mid 100.382832 -45.150024)
					(end 98.482912 -47.049944)
				)
			)
		)
	)
	(zone
		(layer "B.Cu")
		(hatch none 0.5)
		(connect_pads
			(clearance 0)
		)
		(min_thickness 0.25)
		(keepout
			(tracks allowed)
			(vias allowed)
			(pads allowed)
			(copperpour allowed)
			(footprints allowed)
		)
		(placement
			(enabled no)
			(sheetname "")
		)
		(fill
			(thermal_gap 0.5)
			(thermal_bridge_width 0.5)
			(island_removal_mode 0)
		)
		(polygon
			(pts
				(xy 34.264854 -405.568404) (xy 35.219894 -405.568404) (xy 35.219894 -407.449528) (xy 34.264854 -407.449528)
			)
		)
	)
	(zone
		(layer "B.Cu")
		(hatch none 0.5)
		(connect_pads
			(clearance 0)
		)
		(min_thickness 0.25)
		(keepout
			(tracks allowed)
			(vias allowed)
			(pads allowed)
			(copperpour allowed)
			(footprints not_allowed)
		)
		(placement
			(enabled no)
			(sheetname "")
		)
		(fill
			(thermal_gap 0.5)
			(thermal_bridge_width 0.5)
			(island_removal_mode 0)
		)
		(polygon
			(pts
				(arc
					(start 2.999994 -163.681918)
					(mid 18.339672 -160.50006)
					(end 2.999994 -157.318202)
				)
			)
		)
	)
	(zone
		(layer "B.Cu")
		(hatch none 0.5)
		(connect_pads
			(clearance 0)
		)
		(min_thickness 0.25)
		(keepout
			(tracks not_allowed)
			(vias allowed)
			(pads allowed)
			(copperpour not_allowed)
			(footprints allowed)
		)
		(placement
			(enabled no)
			(sheetname "")
		)
		(fill
			(thermal_gap 0.5)
			(thermal_bridge_width 0.5)
			(island_removal_mode 0)
		)
		(polygon
			(pts
				(arc
					(start 16.169386 -27.120342)
					(mid 12.283054 -27.265244)
					(end 12.427712 -31.151576)
				)
				(arc
					(start 13.60043 -32.239966)
					(mid 17.486947 -32.095372)
					(end 17.342104 -28.208986)
				)
			)
		)
	)
	(zone
		(layer "B.Cu")
		(hatch none 0.5)
		(connect_pads
			(clearance 0)
		)
		(min_thickness 0.25)
		(keepout
			(tracks allowed)
			(vias allowed)
			(pads allowed)
			(copperpour allowed)
			(footprints not_allowed)
		)
		(placement
			(enabled no)
			(sheetname "")
		)
		(fill
			(thermal_gap 0.5)
			(thermal_bridge_width 0.5)
			(island_removal_mode 0)
		)
		(polygon
			(pts
				(arc
					(start 77.914754 -353.525074)
					(mid 81.914746 -357.525066)
					(end 85.914738 -353.525074)
				)
				(arc
					(start 85.914738 -353.525074)
					(mid 81.914746 -349.525082)
					(end 77.914754 -353.525074)
				)
			)
		)
	)
	(zone
		(layer "B.Cu")
		(hatch none 0.5)
		(connect_pads
			(clearance 0)
		)
		(min_thickness 0.25)
		(keepout
			(tracks allowed)
			(vias allowed)
			(pads allowed)
			(copperpour allowed)
			(footprints allowed)
		)
		(placement
			(enabled no)
			(sheetname "")
		)
		(fill
			(thermal_gap 0.5)
			(thermal_bridge_width 0.5)
			(island_removal_mode 0)
		)
		(polygon
			(pts
				(xy 319.22212 -13.97762) (xy 319.22212 -12.93876) (xy 320.802 -12.93876) (xy 320.802 -13.97762)
			)
		)
	)
	(zone
		(layer "B.Cu")
		(hatch none 0.5)
		(connect_pads
			(clearance 0)
		)
		(min_thickness 0.25)
		(keepout
			(tracks allowed)
			(vias allowed)
			(pads allowed)
			(copperpour allowed)
			(footprints allowed)
		)
		(placement
			(enabled no)
			(sheetname "")
		)
		(fill
			(thermal_gap 0.5)
			(thermal_bridge_width 0.5)
			(island_removal_mode 0)
		)
		(polygon
			(pts
				(xy 390.089644 -210.736434) (xy 390.091168 -292.321234) (xy 329.359768 -292.322504) (xy 329.358498 -218.872308)
				(xy 333.766414 -214.464392) (xy 333.766414 -213.09457) (xy 336.123534 -210.73745)
			)
		)
	)
	(zone
		(layer "B.Cu")
		(hatch none 0.5)
		(connect_pads
			(clearance 0)
		)
		(min_thickness 0.25)
		(keepout
			(tracks not_allowed)
			(vias allowed)
			(pads allowed)
			(copperpour not_allowed)
			(footprints allowed)
		)
		(placement
			(enabled no)
			(sheetname "")
		)
		(fill
			(thermal_gap 0.5)
			(thermal_bridge_width 0.5)
			(island_removal_mode 0)
		)
		(polygon
			(pts
				(arc
					(start 120.506744 -400.858228)
					(mid 119.803164 -400.858228)
					(end 120.506744 -400.858228)
				)
			)
		)
	)
	(zone
		(layer "B.Cu")
		(hatch none 0.5)
		(connect_pads
			(clearance 0)
		)
		(min_thickness 0.25)
		(keepout
			(tracks not_allowed)
			(vias allowed)
			(pads allowed)
			(copperpour not_allowed)
			(footprints allowed)
		)
		(placement
			(enabled no)
			(sheetname "")
		)
		(fill
			(thermal_gap 0.5)
			(thermal_bridge_width 0.5)
			(island_removal_mode 0)
		)
		(polygon
			(pts
				(arc
					(start 38.182042 -385.412996)
					(mid 37.478462 -385.412996)
					(end 38.182042 -385.412996)
				)
			)
		)
	)
	(zone
		(layer "B.Cu")
		(hatch none 0.5)
		(connect_pads
			(clearance 0)
		)
		(min_thickness 0.25)
		(keepout
			(tracks not_allowed)
			(vias allowed)
			(pads allowed)
			(copperpour not_allowed)
			(footprints allowed)
		)
		(placement
			(enabled no)
			(sheetname "")
		)
		(fill
			(thermal_gap 0.5)
			(thermal_bridge_width 0.5)
			(island_removal_mode 0)
		)
		(polygon
			(pts
				(arc
					(start 102.60965 -411.213808)
					(mid 101.90607 -411.213808)
					(end 102.60965 -411.213808)
				)
			)
		)
	)
	(zone
		(layer "B.Cu")
		(hatch none 0.5)
		(connect_pads
			(clearance 0)
		)
		(min_thickness 0.25)
		(keepout
			(tracks allowed)
			(vias allowed)
			(pads allowed)
			(copperpour allowed)
			(footprints not_allowed)
		)
		(placement
			(enabled no)
			(sheetname "")
		)
		(fill
			(thermal_gap 0.5)
			(thermal_bridge_width 0.5)
			(island_removal_mode 0)
		)
		(polygon
			(pts
				(arc
					(start 290.74999 -435.600094)
					(mid 293.550086 -438.40019)
					(end 296.349928 -435.600094)
				)
				(arc
					(start 296.349928 -435.600094)
					(mid 293.550086 -432.800252)
					(end 290.74999 -435.600094)
				)
			)
		)
	)
	(zone
		(layer "B.Cu")
		(hatch none 0.5)
		(connect_pads
			(clearance 0)
		)
		(min_thickness 0.25)
		(keepout
			(tracks allowed)
			(vias allowed)
			(pads allowed)
			(copperpour allowed)
			(footprints not_allowed)
		)
		(placement
			(enabled no)
			(sheetname "")
		)
		(fill
			(thermal_gap 0.5)
			(thermal_bridge_width 0.5)
			(island_removal_mode 0)
		)
		(polygon
			(pts
				(arc
					(start 265.895328 -51.999896)
					(mid 268.645386 -54.749954)
					(end 271.395444 -51.999896)
				)
				(arc
					(start 271.395444 -51.999896)
					(mid 268.645386 -49.249838)
					(end 265.895328 -51.999896)
				)
			)
		)
	)
	(zone
		(layer "B.Cu")
		(hatch none 0.5)
		(connect_pads
			(clearance 0)
		)
		(min_thickness 0.25)
		(keepout
			(tracks not_allowed)
			(vias allowed)
			(pads allowed)
			(copperpour not_allowed)
			(footprints allowed)
		)
		(placement
			(enabled no)
			(sheetname "")
		)
		(fill
			(thermal_gap 0.5)
			(thermal_bridge_width 0.5)
			(island_removal_mode 0)
		)
		(polygon
			(pts
				(arc
					(start 64.382904 -50.25009)
					(mid 65.784579 -49.92679)
					(end 66.903092 -49.022254)
				)
				(arc
					(start 66.903092 -49.022254)
					(mid 71.402756 -50.917617)
					(end 74.382884 -47.049944)
				)
				(arc
					(start 74.382884 -47.049944)
					(mid 71.402678 -43.182132)
					(end 66.903092 -45.077888)
				)
				(arc
					(start 66.903092 -45.077888)
					(mid 65.784607 -44.173293)
					(end 64.382904 -43.850052)
				)
				(arc
					(start 62.782958 -43.850052)
					(mid 59.582812 -47.050198)
					(end 62.782958 -50.25009)
				)
			)
		)
	)
	(zone
		(layer "B.Cu")
		(hatch none 0.5)
		(connect_pads
			(clearance 0)
		)
		(min_thickness 0.25)
		(keepout
			(tracks not_allowed)
			(vias allowed)
			(pads allowed)
			(copperpour not_allowed)
			(footprints allowed)
		)
		(placement
			(enabled no)
			(sheetname "")
		)
		(fill
			(thermal_gap 0.5)
			(thermal_bridge_width 0.5)
			(island_removal_mode 0)
		)
		(polygon
			(pts
				(arc
					(start 54.458108 -400.858228)
					(mid 53.754528 -400.858228)
					(end 54.458108 -400.858228)
				)
			)
		)
	)
	(zone
		(layer "B.Cu")
		(hatch none 0.5)
		(connect_pads
			(clearance 0)
		)
		(min_thickness 0.25)
		(keepout
			(tracks not_allowed)
			(vias allowed)
			(pads allowed)
			(copperpour not_allowed)
			(footprints allowed)
		)
		(placement
			(enabled no)
			(sheetname "")
		)
		(fill
			(thermal_gap 0.5)
			(thermal_bridge_width 0.5)
			(island_removal_mode 0)
		)
		(polygon
			(pts
				(arc
					(start 374.83796 -400.858228)
					(mid 374.13438 -400.858228)
					(end 374.83796 -400.858228)
				)
			)
		)
	)
	(zone
		(layer "B.Cu")
		(hatch none 0.5)
		(connect_pads
			(clearance 0)
		)
		(min_thickness 0.25)
		(keepout
			(tracks allowed)
			(vias allowed)
			(pads allowed)
			(copperpour allowed)
			(footprints allowed)
		)
		(placement
			(enabled no)
			(sheetname "")
		)
		(fill
			(thermal_gap 0.5)
			(thermal_bridge_width 0.5)
			(island_removal_mode 0)
		)
		(polygon
			(pts
				(xy 426.58538 -366.796828) (xy 426.58538 -363.616748) (xy 422.11498 -363.616748) (xy 422.11498 -366.796828)
			)
		)
	)
	(zone
		(layer "B.Cu")
		(hatch none 0.5)
		(connect_pads
			(clearance 0)
		)
		(min_thickness 0.25)
		(keepout
			(tracks not_allowed)
			(vias allowed)
			(pads allowed)
			(copperpour not_allowed)
			(footprints allowed)
		)
		(placement
			(enabled no)
			(sheetname "")
		)
		(fill
			(thermal_gap 0.5)
			(thermal_bridge_width 0.5)
			(island_removal_mode 0)
		)
		(polygon
			(pts
				(arc
					(start 123.569984 -400.858228)
					(mid 122.866404 -400.858228)
					(end 123.569984 -400.858228)
				)
			)
		)
	)
	(zone
		(layer "B.Cu")
		(hatch none 0.5)
		(connect_pads
			(clearance 0)
		)
		(min_thickness 0.25)
		(keepout
			(tracks not_allowed)
			(vias allowed)
			(pads allowed)
			(copperpour not_allowed)
			(footprints allowed)
		)
		(placement
			(enabled no)
			(sheetname "")
		)
		(fill
			(thermal_gap 0.5)
			(thermal_bridge_width 0.5)
			(island_removal_mode 0)
		)
		(polygon
			(pts
				(arc
					(start 340.64067 -223.575626)
					(mid 339.98789 -223.575626)
					(end 340.64067 -223.575626)
				)
			)
		)
	)
	(zone
		(layer "B.Cu")
		(hatch none 0.5)
		(connect_pads
			(clearance 0)
		)
		(min_thickness 0.25)
		(keepout
			(tracks allowed)
			(vias allowed)
			(pads allowed)
			(copperpour allowed)
			(footprints allowed)
		)
		(placement
			(enabled no)
			(sheetname "")
		)
		(fill
			(thermal_gap 0.5)
			(thermal_bridge_width 0.5)
			(island_removal_mode 0)
		)
		(polygon
			(pts
				(xy 355.490526 -367.286032) (xy 355.490526 -366.605312) (xy 356.722426 -366.605312) (xy 356.722426 -367.286032)
			)
		)
	)
	(zone
		(layer "B.Cu")
		(hatch none 0.5)
		(connect_pads
			(clearance 0)
		)
		(min_thickness 0.25)
		(keepout
			(tracks not_allowed)
			(vias allowed)
			(pads allowed)
			(copperpour not_allowed)
			(footprints allowed)
		)
		(placement
			(enabled no)
			(sheetname "")
		)
		(fill
			(thermal_gap 0.5)
			(thermal_bridge_width 0.5)
			(island_removal_mode 0)
		)
		(polygon
			(pts
				(arc
					(start 380.582424 -224.389442)
					(mid 379.929644 -224.389442)
					(end 380.582424 -224.389442)
				)
			)
		)
	)
	(zone
		(layer "B.Cu")
		(hatch none 0.5)
		(connect_pads
			(clearance 0)
		)
		(min_thickness 0.25)
		(keepout
			(tracks allowed)
			(vias allowed)
			(pads allowed)
			(copperpour allowed)
			(footprints allowed)
		)
		(placement
			(enabled no)
			(sheetname "")
		)
		(fill
			(thermal_gap 0.5)
			(thermal_bridge_width 0.5)
			(island_removal_mode 0)
		)
		(polygon
			(pts
				(xy 126.98222 -27.043888) (xy 126.98222 -25.580848) (xy 128.58496 -25.580848) (xy 128.58496 -27.043888)
			)
		)
	)
	(zone
		(layer "B.Cu")
		(hatch none 0.5)
		(connect_pads
			(clearance 0)
		)
		(min_thickness 0.25)
		(keepout
			(tracks allowed)
			(vias allowed)
			(pads allowed)
			(copperpour allowed)
			(footprints allowed)
		)
		(placement
			(enabled no)
			(sheetname "")
		)
		(fill
			(thermal_gap 0.5)
			(thermal_bridge_width 0.5)
			(island_removal_mode 0)
		)
		(polygon
			(pts
				(xy 363.45114 -56.41848) (xy 363.45114 -55.45328) (xy 356.01148 -55.45328) (xy 356.01148 -56.41848)
			)
		)
	)
	(zone
		(layer "B.Cu")
		(hatch none 0.5)
		(connect_pads
			(clearance 0)
		)
		(min_thickness 0.25)
		(keepout
			(tracks not_allowed)
			(vias allowed)
			(pads allowed)
			(copperpour not_allowed)
			(footprints allowed)
		)
		(placement
			(enabled no)
			(sheetname "")
		)
		(fill
			(thermal_gap 0.5)
			(thermal_bridge_width 0.5)
			(island_removal_mode 0)
		)
		(polygon
			(pts
				(arc
					(start 179.36337 -45.618146)
					(mid 178.65979 -45.618146)
					(end 179.36337 -45.618146)
				)
			)
		)
	)
	(zone
		(layer "B.Cu")
		(hatch none 0.5)
		(connect_pads
			(clearance 0)
		)
		(min_thickness 0.25)
		(keepout
			(tracks not_allowed)
			(vias allowed)
			(pads allowed)
			(copperpour not_allowed)
			(footprints allowed)
		)
		(placement
			(enabled no)
			(sheetname "")
		)
		(fill
			(thermal_gap 0.5)
			(thermal_bridge_width 0.5)
			(island_removal_mode 0)
		)
		(polygon
			(pts
				(arc
					(start 133.623304 -400.858228)
					(mid 132.919724 -400.858228)
					(end 133.623304 -400.858228)
				)
			)
		)
	)
	(zone
		(layer "B.Cu")
		(hatch none 0.5)
		(connect_pads
			(clearance 0)
		)
		(min_thickness 0.25)
		(keepout
			(tracks not_allowed)
			(vias allowed)
			(pads allowed)
			(copperpour not_allowed)
			(footprints allowed)
		)
		(placement
			(enabled no)
			(sheetname "")
		)
		(fill
			(thermal_gap 0.5)
			(thermal_bridge_width 0.5)
			(island_removal_mode 0)
		)
		(polygon
			(pts
				(arc
					(start 127.496824 -400.858228)
					(mid 126.793244 -400.858228)
					(end 127.496824 -400.858228)
				)
			)
		)
	)
	(zone
		(layer "B.Cu")
		(hatch none 0.5)
		(connect_pads
			(clearance 0)
		)
		(min_thickness 0.25)
		(keepout
			(tracks allowed)
			(vias allowed)
			(pads allowed)
			(copperpour allowed)
			(footprints not_allowed)
		)
		(placement
			(enabled no)
			(sheetname "")
		)
		(fill
			(thermal_gap 0.5)
			(thermal_bridge_width 0.5)
			(island_removal_mode 0)
		)
		(polygon
			(pts
				(arc
					(start 249.150124 -192.499996)
					(mid 236.650022 -179.999894)
					(end 224.14992 -192.499996)
				)
				(arc
					(start 224.14992 -192.499996)
					(mid 236.650022 -205.000098)
					(end 249.150124 -192.499996)
				)
			)
		)
	)
	(zone
		(layer "B.Cu")
		(hatch none 0.5)
		(connect_pads
			(clearance 0)
		)
		(min_thickness 0.25)
		(keepout
			(tracks not_allowed)
			(vias allowed)
			(pads allowed)
			(copperpour not_allowed)
			(footprints allowed)
		)
		(placement
			(enabled no)
			(sheetname "")
		)
		(fill
			(thermal_gap 0.5)
			(thermal_bridge_width 0.5)
			(island_removal_mode 0)
		)
		(polygon
			(pts
				(arc
					(start 371.184424 -224.389442)
					(mid 370.531644 -224.389442)
					(end 371.184424 -224.389442)
				)
			)
		)
	)
	(zone
		(layer "B.Cu")
		(hatch none 0.5)
		(connect_pads
			(clearance 0)
		)
		(min_thickness 0.25)
		(keepout
			(tracks not_allowed)
			(vias allowed)
			(pads allowed)
			(copperpour not_allowed)
			(footprints allowed)
		)
		(placement
			(enabled no)
			(sheetname "")
		)
		(fill
			(thermal_gap 0.5)
			(thermal_bridge_width 0.5)
			(island_removal_mode 0)
		)
		(polygon
			(pts
				(arc
					(start 233.884978 -79.149956)
					(mid 235.89996 -84.950265)
					(end 237.914942 -79.149956)
				)
			)
		)
	)
	(zone
		(layer "B.Cu")
		(hatch none 0.5)
		(connect_pads
			(clearance 0)
		)
		(min_thickness 0.25)
		(keepout
			(tracks not_allowed)
			(vias allowed)
			(pads allowed)
			(copperpour not_allowed)
			(footprints allowed)
		)
		(placement
			(enabled no)
			(sheetname "")
		)
		(fill
			(thermal_gap 0.5)
			(thermal_bridge_width 0.5)
			(island_removal_mode 0)
		)
		(polygon
			(pts
				(arc
					(start 351.626678 -407.00452)
					(mid 350.923098 -407.00452)
					(end 351.626678 -407.00452)
				)
			)
		)
	)
	(zone
		(layer "B.Cu")
		(hatch none 0.5)
		(connect_pads
			(clearance 0)
		)
		(min_thickness 0.25)
		(keepout
			(tracks not_allowed)
			(vias allowed)
			(pads allowed)
			(copperpour not_allowed)
			(footprints allowed)
		)
		(placement
			(enabled no)
			(sheetname "")
		)
		(fill
			(thermal_gap 0.5)
			(thermal_bridge_width 0.5)
			(island_removal_mode 0)
		)
		(polygon
			(pts
				(arc
					(start 387.95452 -400.858228)
					(mid 387.25094 -400.858228)
					(end 387.95452 -400.858228)
				)
			)
		)
	)
	(zone
		(layer "B.Cu")
		(hatch none 0.5)
		(connect_pads
			(clearance 0)
		)
		(min_thickness 0.25)
		(keepout
			(tracks not_allowed)
			(vias allowed)
			(pads allowed)
			(copperpour not_allowed)
			(footprints allowed)
		)
		(placement
			(enabled no)
			(sheetname "")
		)
		(fill
			(thermal_gap 0.5)
			(thermal_bridge_width 0.5)
			(island_removal_mode 0)
		)
		(polygon
			(pts
				(arc
					(start 124.433584 -400.858228)
					(mid 123.730004 -400.858228)
					(end 124.433584 -400.858228)
				)
			)
		)
	)
	(zone
		(layer "B.Cu")
		(hatch none 0.5)
		(connect_pads
			(clearance 0)
		)
		(min_thickness 0.25)
		(keepout
			(tracks allowed)
			(vias allowed)
			(pads allowed)
			(copperpour allowed)
			(footprints allowed)
		)
		(placement
			(enabled no)
			(sheetname "")
		)
		(fill
			(thermal_gap 0.5)
			(thermal_bridge_width 0.5)
			(island_removal_mode 0)
		)
		(polygon
			(pts
				(xy 355.45014 -367.485168) (xy 355.45014 -366.453928) (xy 356.75062 -366.453928) (xy 356.75062 -367.485168)
			)
		)
	)
	(zone
		(layer "B.Cu")
		(hatch none 0.5)
		(connect_pads
			(clearance 0)
		)
		(min_thickness 0.25)
		(keepout
			(tracks allowed)
			(vias allowed)
			(pads allowed)
			(copperpour allowed)
			(footprints not_allowed)
		)
		(placement
			(enabled no)
			(sheetname "")
		)
		(fill
			(thermal_gap 0.5)
			(thermal_bridge_width 0.5)
			(island_removal_mode 0)
		)
		(polygon
			(pts
				(arc
					(start 317.90005 -160.50006)
					(mid 322.90004 -165.50005)
					(end 327.90003 -160.50006)
				)
				(arc
					(start 327.90003 -160.50006)
					(mid 322.90004 -155.50007)
					(end 317.90005 -160.50006)
				)
			)
		)
	)
	(zone
		(layer "B.Cu")
		(hatch none 0.5)
		(connect_pads
			(clearance 0)
		)
		(min_thickness 0.25)
		(keepout
			(tracks allowed)
			(vias allowed)
			(pads allowed)
			(copperpour allowed)
			(footprints allowed)
		)
		(placement
			(enabled no)
			(sheetname "")
		)
		(fill
			(thermal_gap 0.5)
			(thermal_bridge_width 0.5)
			(island_removal_mode 0)
		)
		(polygon
			(pts
				(xy 353.8601 -338.295488) (xy 353.8601 -334.678528) (xy 348.41434 -334.678528) (xy 348.41434 -338.295488)
			)
		)
	)
	(zone
		(layer "B.Cu")
		(hatch none 0.5)
		(connect_pads
			(clearance 0)
		)
		(min_thickness 0.25)
		(keepout
			(tracks not_allowed)
			(vias allowed)
			(pads allowed)
			(copperpour not_allowed)
			(footprints allowed)
		)
		(placement
			(enabled no)
			(sheetname "")
		)
		(fill
			(thermal_gap 0.5)
			(thermal_bridge_width 0.5)
			(island_removal_mode 0)
		)
		(polygon
			(pts
				(arc
					(start 318.44996 -68.449952)
					(mid 316.900052 -66.900044)
					(end 315.34989 -68.449952)
				)
				(arc
					(start 315.34989 -68.449952)
					(mid 316.900052 -70.000114)
					(end 318.44996 -68.449952)
				)
			)
		)
	)
	(zone
		(layer "B.Cu")
		(hatch none 0.5)
		(connect_pads
			(clearance 0)
		)
		(min_thickness 0.25)
		(keepout
			(tracks allowed)
			(vias allowed)
			(pads allowed)
			(copperpour allowed)
			(footprints allowed)
		)
		(placement
			(enabled no)
			(sheetname "")
		)
		(fill
			(thermal_gap 0.5)
			(thermal_bridge_width 0.5)
			(island_removal_mode 0)
		)
		(polygon
			(pts
				(xy 165.04158 -36.08578) (xy 165.04158 -35.36188) (xy 166.33952 -35.36188) (xy 166.33952 -36.08578)
			)
		)
	)
	(zone
		(layer "B.Cu")
		(hatch none 0.5)
		(connect_pads
			(clearance 0)
		)
		(min_thickness 0.25)
		(keepout
			(tracks not_allowed)
			(vias allowed)
			(pads allowed)
			(copperpour not_allowed)
			(footprints allowed)
		)
		(placement
			(enabled no)
			(sheetname "")
		)
		(fill
			(thermal_gap 0.5)
			(thermal_bridge_width 0.5)
			(island_removal_mode 0)
		)
		(polygon
			(pts
				(arc
					(start 396.28064 -400.858228)
					(mid 395.57706 -400.858228)
					(end 396.28064 -400.858228)
				)
			)
		)
	)
	(zone
		(layer "B.Cu")
		(hatch none 0.5)
		(connect_pads
			(clearance 0)
		)
		(min_thickness 0.25)
		(keepout
			(tracks not_allowed)
			(vias allowed)
			(pads allowed)
			(copperpour not_allowed)
			(footprints allowed)
		)
		(placement
			(enabled no)
			(sheetname "")
		)
		(fill
			(thermal_gap 0.5)
			(thermal_bridge_width 0.5)
			(island_removal_mode 0)
		)
		(polygon
			(pts
				(arc
					(start 377.29287 -225.203258)
					(mid 376.64009 -225.203258)
					(end 377.29287 -225.203258)
				)
			)
		)
	)
	(zone
		(layer "B.Cu")
		(hatch none 0.5)
		(connect_pads
			(clearance 0)
		)
		(min_thickness 0.25)
		(keepout
			(tracks allowed)
			(vias allowed)
			(pads allowed)
			(copperpour allowed)
			(footprints allowed)
		)
		(placement
			(enabled no)
			(sheetname "")
		)
		(fill
			(thermal_gap 0.5)
			(thermal_bridge_width 0.5)
			(island_removal_mode 0)
		)
		(polygon
			(pts
				(xy 30.87878 -126.517908) (xy 30.87878 -124.689108) (xy 32.20212 -124.689108) (xy 32.20212 -126.517908)
			)
		)
	)
	(zone
		(layer "B.Cu")
		(hatch none 0.5)
		(connect_pads
			(clearance 0)
		)
		(min_thickness 0.25)
		(keepout
			(tracks allowed)
			(vias allowed)
			(pads allowed)
			(copperpour allowed)
			(footprints allowed)
		)
		(placement
			(enabled no)
			(sheetname "")
		)
		(fill
			(thermal_gap 0.5)
			(thermal_bridge_width 0.5)
			(island_removal_mode 0)
		)
		(polygon
			(pts
				(xy 257.54076 -38.2397) (xy 257.54076 -35.78352) (xy 256.68224 -35.78352) (xy 256.68224 -38.2397)
			)
		)
	)
	(zone
		(layer "B.Cu")
		(hatch none 0.5)
		(connect_pads
			(clearance 0)
		)
		(min_thickness 0.25)
		(keepout
			(tracks not_allowed)
			(vias allowed)
			(pads allowed)
			(copperpour not_allowed)
			(footprints allowed)
		)
		(placement
			(enabled no)
			(sheetname "")
		)
		(fill
			(thermal_gap 0.5)
			(thermal_bridge_width 0.5)
			(island_removal_mode 0)
		)
		(polygon
			(pts
				(arc
					(start 348.15907 -223.575626)
					(mid 347.50629 -223.575626)
					(end 348.15907 -223.575626)
				)
			)
		)
	)
	(zone
		(layer "B.Cu")
		(hatch none 0.5)
		(connect_pads
			(clearance 0)
		)
		(min_thickness 0.25)
		(keepout
			(tracks not_allowed)
			(vias allowed)
			(pads allowed)
			(copperpour not_allowed)
			(footprints allowed)
		)
		(placement
			(enabled no)
			(sheetname "")
		)
		(fill
			(thermal_gap 0.5)
			(thermal_bridge_width 0.5)
			(island_removal_mode 0)
		)
		(polygon
			(pts
				(arc
					(start 80.3148 -353.525074)
					(mid 81.915 -355.125274)
					(end 83.514946 -353.525074)
				)
				(arc
					(start 83.514946 -353.525074)
					(mid 81.915 -351.925128)
					(end 80.3148 -353.525074)
				)
			)
		)
	)
	(zone
		(layer "B.Cu")
		(hatch none 0.5)
		(connect_pads
			(clearance 0)
		)
		(min_thickness 0.25)
		(keepout
			(tracks not_allowed)
			(vias allowed)
			(pads allowed)
			(copperpour not_allowed)
			(footprints allowed)
		)
		(placement
			(enabled no)
			(sheetname "")
		)
		(fill
			(thermal_gap 0.5)
			(thermal_bridge_width 0.5)
			(island_removal_mode 0)
		)
		(polygon
			(pts
				(arc
					(start 318.794638 -407.00452)
					(mid 318.091058 -407.00452)
					(end 318.794638 -407.00452)
				)
			)
		)
	)
	(zone
		(layer "B.Cu")
		(hatch none 0.5)
		(connect_pads
			(clearance 0)
		)
		(min_thickness 0.25)
		(keepout
			(tracks allowed)
			(vias allowed)
			(pads allowed)
			(copperpour allowed)
			(footprints allowed)
		)
		(placement
			(enabled no)
			(sheetname "")
		)
		(fill
			(thermal_gap 0.5)
			(thermal_bridge_width 0.5)
			(island_removal_mode 0)
		)
		(polygon
			(pts
				(xy 47.512986 -353.428808) (xy 48.851566 -353.428808) (xy 49.245266 -353.822508) (xy 49.245266 -356.037388)
				(xy 49.435766 -356.227888) (xy 52.981606 -356.227888) (xy 53.197506 -356.443788) (xy 53.197506 -358.605328)
				(xy 53.037486 -358.765348) (xy 47.601886 -358.765348) (xy 47.157386 -358.320848) (xy 47.157386 -353.784408)
			)
		)
	)
	(zone
		(layer "B.Cu")
		(hatch none 0.5)
		(connect_pads
			(clearance 0)
		)
		(min_thickness 0.25)
		(keepout
			(tracks not_allowed)
			(vias allowed)
			(pads allowed)
			(copperpour not_allowed)
			(footprints allowed)
		)
		(placement
			(enabled no)
			(sheetname "")
		)
		(fill
			(thermal_gap 0.5)
			(thermal_bridge_width 0.5)
			(island_removal_mode 0)
		)
		(polygon
			(pts
				(arc
					(start 52.258468 -400.858228)
					(mid 51.554888 -400.858228)
					(end 52.258468 -400.858228)
				)
			)
		)
	)
	(zone
		(layer "B.Cu")
		(hatch none 0.5)
		(connect_pads
			(clearance 0)
		)
		(min_thickness 0.25)
		(keepout
			(tracks not_allowed)
			(vias allowed)
			(pads allowed)
			(copperpour not_allowed)
			(footprints allowed)
		)
		(placement
			(enabled no)
			(sheetname "")
		)
		(fill
			(thermal_gap 0.5)
			(thermal_bridge_width 0.5)
			(island_removal_mode 0)
		)
		(polygon
			(pts
				(arc
					(start 15.361666 -27.99969)
					(mid 13.170721 -28.072779)
					(end 13.243814 -30.263592)
				)
				(arc
					(start 14.412214 -31.356554)
					(mid 16.603023 -31.283593)
					(end 16.530066 -29.092652)
				)
			)
		)
	)
	(zone
		(layer "B.Cu")
		(hatch none 0.5)
		(connect_pads
			(clearance 0)
		)
		(min_thickness 0.25)
		(keepout
			(tracks allowed)
			(vias allowed)
			(pads allowed)
			(copperpour allowed)
			(footprints not_allowed)
		)
		(placement
			(enabled no)
			(sheetname "")
		)
		(fill
			(thermal_gap 0.5)
			(thermal_bridge_width 0.5)
			(island_removal_mode 0)
		)
		(polygon
			(pts
				(arc
					(start 206.45501 -153.774902)
					(mid 193.955162 -141.275054)
					(end 181.45506 -153.774902)
				)
				(arc
					(start 181.45506 -153.774902)
					(mid 193.955162 -166.275004)
					(end 206.45501 -153.774902)
				)
			)
		)
	)
	(zone
		(layer "B.Cu")
		(hatch none 0.5)
		(connect_pads
			(clearance 0)
		)
		(min_thickness 0.25)
		(keepout
			(tracks allowed)
			(vias allowed)
			(pads allowed)
			(copperpour allowed)
			(footprints not_allowed)
		)
		(placement
			(enabled no)
			(sheetname "")
		)
		(fill
			(thermal_gap 0.5)
			(thermal_bridge_width 0.5)
			(island_removal_mode 0)
		)
		(polygon
			(pts
				(arc
					(start 0.999998 -33.265872)
					(mid 2.097679 -33.798539)
					(end 3.242056 -34.221674)
				)
				(arc
					(start 3.242056 -34.221674)
					(mid 24.015289 -38.217469)
					(end 18.64487 -17.756378)
				)
				(arc
					(start 18.64487 -17.756378)
					(mid 16.568832 -14.257205)
					(end 13.479018 -11.610086)
				)
				(arc
					(start 13.479018 -11.610086)
					(mid 12.426693 -12.471654)
					(end 11.102086 -12.78001)
				)
				(arc
					(start 1.999996 -12.78001)
					(mid 1.292891 -13.072903)
					(end 0.999998 -13.780008)
				)
			)
		)
	)
	(zone
		(layer "B.Cu")
		(hatch none 0.5)
		(connect_pads
			(clearance 0)
		)
		(min_thickness 0.25)
		(keepout
			(tracks allowed)
			(vias allowed)
			(pads allowed)
			(copperpour allowed)
			(footprints not_allowed)
		)
		(placement
			(enabled no)
			(sheetname "")
		)
		(fill
			(thermal_gap 0.5)
			(thermal_bridge_width 0.5)
			(island_removal_mode 0)
		)
		(polygon
			(pts
				(arc
					(start 385.601972 -12.78001)
					(mid 386.779411 -12.539292)
					(end 387.76783 -11.855704)
				)
				(arc
					(start 387.76783 -11.855704)
					(mid 381.670283 -34.776169)
					(end 372.799356 -12.78001)
				)
			)
		)
	)
	(zone
		(layer "B.Cu")
		(hatch none 0.5)
		(connect_pads
			(clearance 0)
		)
		(min_thickness 0.25)
		(keepout
			(tracks allowed)
			(vias allowed)
			(pads allowed)
			(copperpour allowed)
			(footprints allowed)
		)
		(placement
			(enabled no)
			(sheetname "")
		)
		(fill
			(thermal_gap 0.5)
			(thermal_bridge_width 0.5)
			(island_removal_mode 0)
		)
		(polygon
			(pts
				(xy 16.41094 -316.057788) (xy 16.41094 -315.435488) (xy 17.03832 -315.435488) (xy 17.03832 -316.057788)
			)
		)
	)
	(zone
		(layer "B.Cu")
		(hatch none 0.5)
		(connect_pads
			(clearance 0)
		)
		(min_thickness 0.25)
		(keepout
			(tracks not_allowed)
			(vias allowed)
			(pads allowed)
			(copperpour not_allowed)
			(footprints allowed)
		)
		(placement
			(enabled no)
			(sheetname "")
		)
		(fill
			(thermal_gap 0.5)
			(thermal_bridge_width 0.5)
			(island_removal_mode 0)
		)
		(polygon
			(pts
				(arc
					(start 49.195228 -400.858228)
					(mid 48.491648 -400.858228)
					(end 49.195228 -400.858228)
				)
			)
		)
	)
	(zone
		(layer "B.Cu")
		(hatch none 0.5)
		(connect_pads
			(clearance 0)
		)
		(min_thickness 0.25)
		(keepout
			(tracks not_allowed)
			(vias allowed)
			(pads allowed)
			(copperpour not_allowed)
			(footprints allowed)
		)
		(placement
			(enabled no)
			(sheetname "")
		)
		(fill
			(thermal_gap 0.5)
			(thermal_bridge_width 0.5)
			(island_removal_mode 0)
		)
		(polygon
			(pts
				(arc
					(start 62.782958 -45.449998)
					(mid 61.183012 -47.049944)
					(end 62.782958 -48.64989)
				)
				(arc
					(start 64.382904 -48.64989)
					(mid 65.98285 -47.049944)
					(end 64.382904 -45.449998)
				)
			)
		)
	)
	(zone
		(layer "B.Cu")
		(hatch none 0.5)
		(connect_pads
			(clearance 0)
		)
		(min_thickness 0.25)
		(keepout
			(tracks not_allowed)
			(vias allowed)
			(pads allowed)
			(copperpour not_allowed)
			(footprints allowed)
		)
		(placement
			(enabled no)
			(sheetname "")
		)
		(fill
			(thermal_gap 0.5)
			(thermal_bridge_width 0.5)
			(island_removal_mode 0)
		)
		(polygon
			(pts
				(arc
					(start 356.292404 -44.998386)
					(mid 355.588824 -44.998386)
					(end 356.292404 -44.998386)
				)
			)
		)
	)
	(zone
		(layer "B.Cu")
		(hatch none 0.5)
		(connect_pads
			(clearance 0)
		)
		(min_thickness 0.25)
		(keepout
			(tracks allowed)
			(vias allowed)
			(pads allowed)
			(copperpour allowed)
			(footprints not_allowed)
		)
		(placement
			(enabled no)
			(sheetname "")
		)
		(fill
			(thermal_gap 0.5)
			(thermal_bridge_width 0.5)
			(island_removal_mode 0)
		)
		(polygon
			(pts
				(arc
					(start 450.349874 -435.600094)
					(mid 448.799966 -434.050186)
					(end 447.250058 -435.600094)
				)
				(arc
					(start 447.250058 -435.600094)
					(mid 448.799966 -437.150002)
					(end 450.349874 -435.600094)
				)
			)
		)
	)
	(zone
		(layer "B.Cu")
		(hatch none 0.5)
		(connect_pads
			(clearance 0)
		)
		(min_thickness 0.25)
		(keepout
			(tracks not_allowed)
			(vias allowed)
			(pads allowed)
			(copperpour not_allowed)
			(footprints allowed)
		)
		(placement
			(enabled no)
			(sheetname "")
		)
		(fill
			(thermal_gap 0.5)
			(thermal_bridge_width 0.5)
			(island_removal_mode 0)
		)
		(polygon
			(pts
				(arc
					(start 126.633224 -400.858228)
					(mid 125.929644 -400.858228)
					(end 126.633224 -400.858228)
				)
			)
		)
	)
	(zone
		(layer "B.Cu")
		(hatch none 0.5)
		(connect_pads
			(clearance 0)
		)
		(min_thickness 0.25)
		(keepout
			(tracks allowed)
			(vias allowed)
			(pads allowed)
			(copperpour allowed)
			(footprints not_allowed)
		)
		(placement
			(enabled no)
			(sheetname "")
		)
		(fill
			(thermal_gap 0.5)
			(thermal_bridge_width 0.5)
			(island_removal_mode 0)
		)
		(polygon
			(pts
				(arc
					(start 37.954966 -153.766012)
					(mid 29.954982 -145.766028)
					(end 21.954998 -153.766012)
				)
				(arc
					(start 21.954998 -153.766012)
					(mid 29.954982 -161.765996)
					(end 37.954966 -153.766012)
				)
			)
		)
	)
	(zone
		(layer "B.Cu")
		(hatch none 0.5)
		(connect_pads
			(clearance 0)
		)
		(min_thickness 0.25)
		(keepout
			(tracks allowed)
			(vias allowed)
			(pads allowed)
			(copperpour allowed)
			(footprints not_allowed)
		)
		(placement
			(enabled no)
			(sheetname "")
		)
		(fill
			(thermal_gap 0.5)
			(thermal_bridge_width 0.5)
			(island_removal_mode 0)
		)
		(polygon
			(pts
				(arc
					(start 226.071684 -359.159302)
					(mid 235.357543 -364.932869)
					(end 245.632478 -361.192826)
				)
				(arc
					(start 245.632478 -361.192826)
					(mid 269.790783 -365.253451)
					(end 249.142758 -352.071178)
				)
				(arc
					(start 249.142758 -352.071178)
					(mid 235.632129 -340.041597)
					(end 224.253298 -354.104702)
				)
				(arc
					(start 224.253298 -354.104702)
					(mid 201.913199 -364.995997)
					(end 226.071684 -359.159302)
				)
			)
		)
	)
	(zone
		(layer "B.Cu")
		(hatch none 0.5)
		(connect_pads
			(clearance 0)
		)
		(min_thickness 0.25)
		(keepout
			(tracks allowed)
			(vias allowed)
			(pads allowed)
			(copperpour allowed)
			(footprints allowed)
		)
		(placement
			(enabled no)
			(sheetname "")
		)
		(fill
			(thermal_gap 0.5)
			(thermal_bridge_width 0.5)
			(island_removal_mode 0)
		)
		(polygon
			(pts
				(xy 309.62854 -269.334488) (xy 309.62854 -268.953488) (xy 310.40324 -268.953488) (xy 310.40324 -269.334488)
			)
		)
	)
	(zone
		(layer "B.Cu")
		(hatch none 0.5)
		(connect_pads
			(clearance 0)
		)
		(min_thickness 0.25)
		(keepout
			(tracks allowed)
			(vias allowed)
			(pads allowed)
			(copperpour allowed)
			(footprints allowed)
		)
		(placement
			(enabled no)
			(sheetname "")
		)
		(fill
			(thermal_gap 0.5)
			(thermal_bridge_width 0.5)
			(island_removal_mode 0)
		)
		(polygon
			(pts
				(xy 236.17428 -135.656828) (xy 236.17428 -133.802628) (xy 237.16996 -133.802628) (xy 237.16996 -135.656828)
			)
		)
	)
	(zone
		(layer "B.Cu")
		(hatch none 0.5)
		(connect_pads
			(clearance 0)
		)
		(min_thickness 0.25)
		(keepout
			(tracks allowed)
			(vias allowed)
			(pads allowed)
			(copperpour allowed)
			(footprints allowed)
		)
		(placement
			(enabled no)
			(sheetname "")
		)
		(fill
			(thermal_gap 0.5)
			(thermal_bridge_width 0.5)
			(island_removal_mode 0)
		)
		(polygon
			(pts
				(xy 134.87146 -25.69718) (xy 134.87146 -23.3045) (xy 133.4643 -23.3045) (xy 133.4643 -25.69718)
			)
		)
	)
	(zone
		(layer "B.Cu")
		(hatch none 0.5)
		(connect_pads
			(clearance 0)
		)
		(min_thickness 0.25)
		(keepout
			(tracks not_allowed)
			(vias allowed)
			(pads allowed)
			(copperpour not_allowed)
			(footprints allowed)
		)
		(placement
			(enabled no)
			(sheetname "")
		)
		(fill
			(thermal_gap 0.5)
			(thermal_bridge_width 0.5)
			(island_removal_mode 0)
		)
		(polygon
			(pts
				(arc
					(start 409.3972 -400.858228)
					(mid 408.69362 -400.858228)
					(end 409.3972 -400.858228)
				)
			)
		)
	)
	(zone
		(layer "B.Cu")
		(hatch none 0.5)
		(connect_pads
			(clearance 0)
		)
		(min_thickness 0.25)
		(keepout
			(tracks not_allowed)
			(vias allowed)
			(pads allowed)
			(copperpour not_allowed)
			(footprints allowed)
		)
		(placement
			(enabled no)
			(sheetname "")
		)
		(fill
			(thermal_gap 0.5)
			(thermal_bridge_width 0.5)
			(island_removal_mode 0)
		)
		(polygon
			(pts
				(arc
					(start 361.359958 -431.360072)
					(mid 359.774998 -429.775112)
					(end 358.190038 -431.360072)
				)
				(arc
					(start 358.190038 -431.360072)
					(mid 359.774998 -432.945032)
					(end 361.359958 -431.360072)
				)
			)
		)
	)
	(zone
		(layer "B.Cu")
		(hatch none 0.5)
		(connect_pads
			(clearance 0)
		)
		(min_thickness 0.25)
		(keepout
			(tracks not_allowed)
			(vias allowed)
			(pads allowed)
			(copperpour not_allowed)
			(footprints allowed)
		)
		(placement
			(enabled no)
			(sheetname "")
		)
		(fill
			(thermal_gap 0.5)
			(thermal_bridge_width 0.5)
			(island_removal_mode 0)
		)
		(polygon
			(pts
				(arc
					(start 382.931924 -225.203258)
					(mid 382.279144 -225.203258)
					(end 382.931924 -225.203258)
				)
			)
		)
	)
	(zone
		(layer "B.Cu")
		(hatch none 0.5)
		(connect_pads
			(clearance 0)
		)
		(min_thickness 0.25)
		(keepout
			(tracks allowed)
			(vias allowed)
			(pads allowed)
			(copperpour allowed)
			(footprints not_allowed)
		)
		(placement
			(enabled no)
			(sheetname "")
		)
		(fill
			(thermal_gap 0.5)
			(thermal_bridge_width 0.5)
			(island_removal_mode 0)
		)
		(polygon
			(pts
				(arc
					(start 7.500112 -439.989976)
					(mid 7.793005 -440.697081)
					(end 8.50011 -440.989974)
				)
				(arc
					(start 24.278082 -440.989974)
					(mid 21.795428 -426.718286)
					(end 7.500112 -424.375072)
				)
			)
		)
	)
	(zone
		(layer "B.Cu")
		(hatch none 0.5)
		(connect_pads
			(clearance 0)
		)
		(min_thickness 0.25)
		(keepout
			(tracks not_allowed)
			(vias allowed)
			(pads allowed)
			(copperpour not_allowed)
			(footprints allowed)
		)
		(placement
			(enabled no)
			(sheetname "")
		)
		(fill
			(thermal_gap 0.5)
			(thermal_bridge_width 0.5)
			(island_removal_mode 0)
		)
		(polygon
			(pts
				(arc
					(start 92.230956 -224.389442)
					(mid 91.578176 -224.389442)
					(end 92.230956 -224.389442)
				)
			)
		)
	)
	(zone
		(layer "B.Cu")
		(hatch none 0.5)
		(connect_pads
			(clearance 0)
		)
		(min_thickness 0.25)
		(keepout
			(tracks allowed)
			(vias allowed)
			(pads allowed)
			(copperpour allowed)
			(footprints allowed)
		)
		(placement
			(enabled no)
			(sheetname "")
		)
		(fill
			(thermal_gap 0.5)
			(thermal_bridge_width 0.5)
			(island_removal_mode 0)
		)
		(polygon
			(pts
				(xy 164.2745 -38.59276) (xy 164.2745 -37.73678) (xy 165.69436 -37.73678) (xy 165.69436 -38.59276)
			)
		)
	)
	(zone
		(layer "B.Cu")
		(hatch none 0.5)
		(connect_pads
			(clearance 0)
		)
		(min_thickness 0.25)
		(keepout
			(tracks not_allowed)
			(vias allowed)
			(pads allowed)
			(copperpour not_allowed)
			(footprints allowed)
		)
		(placement
			(enabled no)
			(sheetname "")
		)
		(fill
			(thermal_gap 0.5)
			(thermal_bridge_width 0.5)
			(island_removal_mode 0)
		)
		(polygon
			(pts
				(arc
					(start 131.232402 -225.203258)
					(mid 130.579622 -225.203258)
					(end 131.232402 -225.203258)
				)
			)
		)
	)
	(zone
		(layer "B.Cu")
		(hatch none 0.5)
		(connect_pads
			(clearance 0)
		)
		(min_thickness 0.25)
		(keepout
			(tracks not_allowed)
			(vias allowed)
			(pads allowed)
			(copperpour not_allowed)
			(footprints allowed)
		)
		(placement
			(enabled no)
			(sheetname "")
		)
		(fill
			(thermal_gap 0.5)
			(thermal_bridge_width 0.5)
			(island_removal_mode 0)
		)
		(polygon
			(pts
				(arc
					(start 128.413002 -223.575626)
					(mid 127.760222 -223.575626)
					(end 128.413002 -223.575626)
				)
			)
		)
	)
	(zone
		(layer "B.Cu")
		(hatch none 0.5)
		(connect_pads
			(clearance 0)
		)
		(min_thickness 0.25)
		(keepout
			(tracks allowed)
			(vias allowed)
			(pads allowed)
			(copperpour allowed)
			(footprints allowed)
		)
		(placement
			(enabled no)
			(sheetname "")
		)
		(fill
			(thermal_gap 0.5)
			(thermal_bridge_width 0.5)
			(island_removal_mode 0)
		)
		(polygon
			(pts
				(xy 369.854226 -360.295952) (xy 369.854226 -357.448612) (xy 371.469666 -357.448612) (xy 371.469666 -360.295952)
			)
		)
	)
	(zone
		(layer "B.Cu")
		(hatch none 0.5)
		(connect_pads
			(clearance 0)
		)
		(min_thickness 0.25)
		(keepout
			(tracks allowed)
			(vias allowed)
			(pads allowed)
			(copperpour allowed)
			(footprints not_allowed)
		)
		(placement
			(enabled no)
			(sheetname "")
		)
		(fill
			(thermal_gap 0.5)
			(thermal_bridge_width 0.5)
			(island_removal_mode 0)
		)
		(polygon
			(pts
				(arc
					(start 162.900106 -160.50006)
					(mid 167.900096 -165.50005)
					(end 172.900086 -160.50006)
				)
				(arc
					(start 172.900086 -160.50006)
					(mid 167.900096 -155.50007)
					(end 162.900106 -160.50006)
				)
			)
		)
	)
	(zone
		(layer "B.Cu")
		(hatch none 0.5)
		(connect_pads
			(clearance 0)
		)
		(min_thickness 0.25)
		(keepout
			(tracks not_allowed)
			(vias allowed)
			(pads allowed)
			(copperpour not_allowed)
			(footprints allowed)
		)
		(placement
			(enabled no)
			(sheetname "")
		)
		(fill
			(thermal_gap 0.5)
			(thermal_bridge_width 0.5)
			(island_removal_mode 0)
		)
		(polygon
			(pts
				(arc
					(start 94.383098 -48.64989)
					(mid 95.983044 -47.049944)
					(end 94.383098 -45.449998)
				)
				(arc
					(start 92.782898 -45.449998)
					(mid 91.182952 -47.049944)
					(end 92.782898 -48.64989)
				)
			)
		)
	)
	(zone
		(layer "B.Cu")
		(hatch none 0.5)
		(connect_pads
			(clearance 0)
		)
		(min_thickness 0.25)
		(keepout
			(tracks not_allowed)
			(vias allowed)
			(pads allowed)
			(copperpour not_allowed)
			(footprints allowed)
		)
		(placement
			(enabled no)
			(sheetname "")
		)
		(fill
			(thermal_gap 0.5)
			(thermal_bridge_width 0.5)
			(island_removal_mode 0)
		)
		(polygon
			(pts
				(arc
					(start 100.689156 -224.389442)
					(mid 100.036376 -224.389442)
					(end 100.689156 -224.389442)
				)
			)
		)
	)
	(zone
		(layer "B.Cu")
		(hatch none 0.5)
		(connect_pads
			(clearance 0)
		)
		(min_thickness 0.25)
		(keepout
			(tracks not_allowed)
			(vias allowed)
			(pads allowed)
			(copperpour not_allowed)
			(footprints allowed)
		)
		(placement
			(enabled no)
			(sheetname "")
		)
		(fill
			(thermal_gap 0.5)
			(thermal_bridge_width 0.5)
			(island_removal_mode 0)
		)
		(polygon
			(pts
				(arc
					(start 369.77447 -225.203258)
					(mid 369.12169 -225.203258)
					(end 369.77447 -225.203258)
				)
			)
		)
	)
	(zone
		(layer "B.Cu")
		(hatch none 0.5)
		(connect_pads
			(clearance 0)
		)
		(min_thickness 0.25)
		(keepout
			(tracks not_allowed)
			(vias allowed)
			(pads allowed)
			(copperpour not_allowed)
			(footprints allowed)
		)
		(placement
			(enabled no)
			(sheetname "")
		)
		(fill
			(thermal_gap 0.5)
			(thermal_bridge_width 0.5)
			(island_removal_mode 0)
		)
		(polygon
			(pts
				(arc
					(start 400.20748 -400.858228)
					(mid 399.5039 -400.858228)
					(end 400.20748 -400.858228)
				)
			)
		)
	)
	(zone
		(layer "B.Cu")
		(hatch none 0.5)
		(connect_pads
			(clearance 0)
		)
		(min_thickness 0.25)
		(keepout
			(tracks not_allowed)
			(vias allowed)
			(pads allowed)
			(copperpour not_allowed)
			(footprints allowed)
		)
		(placement
			(enabled no)
			(sheetname "")
		)
		(fill
			(thermal_gap 0.5)
			(thermal_bridge_width 0.5)
			(island_removal_mode 0)
		)
		(polygon
			(pts
				(arc
					(start 129.696464 -400.858228)
					(mid 128.992884 -400.858228)
					(end 129.696464 -400.858228)
				)
			)
		)
	)
	(zone
		(layer "B.Cu")
		(hatch none 0.5)
		(connect_pads
			(clearance 0)
		)
		(min_thickness 0.25)
		(keepout
			(tracks not_allowed)
			(vias allowed)
			(pads allowed)
			(copperpour not_allowed)
			(footprints allowed)
		)
		(placement
			(enabled no)
			(sheetname "")
		)
		(fill
			(thermal_gap 0.5)
			(thermal_bridge_width 0.5)
			(island_removal_mode 0)
		)
		(polygon
			(pts
				(arc
					(start 88.153748 -400.858228)
					(mid 87.450168 -400.858228)
					(end 88.153748 -400.858228)
				)
			)
		)
	)
	(zone
		(layer "B.Cu")
		(hatch none 0.5)
		(connect_pads
			(clearance 0)
		)
		(min_thickness 0.25)
		(keepout
			(tracks not_allowed)
			(vias allowed)
			(pads allowed)
			(copperpour not_allowed)
			(footprints allowed)
		)
		(placement
			(enabled no)
			(sheetname "")
		)
		(fill
			(thermal_gap 0.5)
			(thermal_bridge_width 0.5)
			(island_removal_mode 0)
		)
		(polygon
			(pts
				(arc
					(start 167.318944 -400.858228)
					(mid 166.615364 -400.858228)
					(end 167.318944 -400.858228)
				)
			)
		)
	)
	(zone
		(layer "B.Cu")
		(hatch none 0.5)
		(connect_pads
			(clearance 0)
		)
		(min_thickness 0.25)
		(keepout
			(tracks not_allowed)
			(vias allowed)
			(pads allowed)
			(copperpour not_allowed)
			(footprints allowed)
		)
		(placement
			(enabled no)
			(sheetname "")
		)
		(fill
			(thermal_gap 0.5)
			(thermal_bridge_width 0.5)
			(island_removal_mode 0)
		)
		(polygon
			(pts
				(arc
					(start 461.600042 -435.600094)
					(mid 458.8002 -432.800252)
					(end 456.000104 -435.600094)
				)
				(arc
					(start 456.000104 -435.600094)
					(mid 458.8002 -438.40019)
					(end 461.600042 -435.600094)
				)
			)
		)
	)
	(zone
		(layer "B.Cu")
		(hatch none 0.5)
		(connect_pads
			(clearance 0)
		)
		(min_thickness 0.25)
		(keepout
			(tracks allowed)
			(vias allowed)
			(pads allowed)
			(copperpour allowed)
			(footprints allowed)
		)
		(placement
			(enabled no)
			(sheetname "")
		)
		(fill
			(thermal_gap 0.5)
			(thermal_bridge_width 0.5)
			(island_removal_mode 0)
		)
		(polygon
			(pts
				(xy 138.62812 -18.11782) (xy 138.62812 -17.20342) (xy 143.39824 -17.20342) (xy 143.39824 -18.11782)
			)
		)
	)
	(zone
		(layer "B.Cu")
		(hatch none 0.5)
		(connect_pads
			(clearance 0)
		)
		(min_thickness 0.25)
		(keepout
			(tracks not_allowed)
			(vias allowed)
			(pads allowed)
			(copperpour not_allowed)
			(footprints allowed)
		)
		(placement
			(enabled no)
			(sheetname "")
		)
		(fill
			(thermal_gap 0.5)
			(thermal_bridge_width 0.5)
			(island_removal_mode 0)
		)
		(polygon
			(pts
				(arc
					(start 98.339402 -223.575626)
					(mid 97.686622 -223.575626)
					(end 98.339402 -223.575626)
				)
			)
		)
	)
	(zone
		(layer "B.Cu")
		(hatch none 0.5)
		(connect_pads
			(clearance 0)
		)
		(min_thickness 0.25)
		(keepout
			(tracks allowed)
			(vias allowed)
			(pads allowed)
			(copperpour allowed)
			(footprints not_allowed)
		)
		(placement
			(enabled no)
			(sheetname "")
		)
		(fill
			(thermal_gap 0.5)
			(thermal_bridge_width 0.5)
			(island_removal_mode 0)
		)
		(polygon
			(pts
				(arc
					(start 367.447068 -263.09447)
					(mid 368.507636 -262.655168)
					(end 368.946938 -261.5946)
				)
				(arc
					(start 368.946938 -237.06455)
					(mid 368.507636 -236.003982)
					(end 367.447068 -235.564426)
				)
				(arc
					(start 364.85703 -235.564426)
					(mid 363.796282 -236.003802)
					(end 363.356906 -237.06455)
				)
				(arc
					(start 363.356906 -261.5946)
					(mid 363.796282 -262.655348)
					(end 364.85703 -263.09447)
				)
			)
		)
	)
	(zone
		(layer "B.Cu")
		(hatch none 0.5)
		(connect_pads
			(clearance 0)
		)
		(min_thickness 0.25)
		(keepout
			(tracks allowed)
			(vias allowed)
			(pads allowed)
			(copperpour allowed)
			(footprints not_allowed)
		)
		(placement
			(enabled no)
			(sheetname "")
		)
		(fill
			(thermal_gap 0.5)
			(thermal_bridge_width 0.5)
			(island_removal_mode 0)
		)
		(polygon
			(pts
				(arc
					(start 233.849926 -352.49993)
					(mid 236.650022 -355.300026)
					(end 239.450118 -352.49993)
				)
				(arc
					(start 239.450118 -352.49993)
					(mid 236.650022 -349.699834)
					(end 233.849926 -352.49993)
				)
			)
		)
	)
	(zone
		(layer "B.Cu")
		(hatch none 0.5)
		(connect_pads
			(clearance 0)
		)
		(min_thickness 0.25)
		(keepout
			(tracks allowed)
			(vias allowed)
			(pads allowed)
			(copperpour allowed)
			(footprints not_allowed)
		)
		(placement
			(enabled no)
			(sheetname "")
		)
		(fill
			(thermal_gap 0.5)
			(thermal_bridge_width 0.5)
			(island_removal_mode 0)
		)
		(polygon
			(pts
				(arc
					(start 436.881778 -431.830988)
					(mid 436.330488 -436.471367)
					(end 437.521858 -440.989974)
				)
				(arc
					(start 463.300064 -440.989974)
					(mid 464.007169 -440.697081)
					(end 464.300062 -439.989976)
				)
				(arc
					(start 464.300062 -424.375072)
					(mid 459.075499 -423.103142)
					(end 453.799956 -424.143678)
				)
				(arc
					(start 453.799956 -424.143678)
					(mid 445.528601 -423.535773)
					(end 438.69737 -428.23892)
				)
				(arc
					(start 438.69737 -428.23892)
					(mid 439.277182 -424.688541)
					(end 438.82183 -421.120062)
				)
				(arc
					(start 438.82183 -421.120062)
					(mid 426.779216 -405.27014)
					(end 414.73628 -421.120062)
				)
				(arc
					(start 414.73628 -421.120062)
					(mid 421.336371 -435.722912)
					(end 436.881778 -431.830988)
				)
			)
		)
	)
	(zone
		(layer "B.Cu")
		(hatch none 0.5)
		(connect_pads
			(clearance 0)
		)
		(min_thickness 0.25)
		(keepout
			(tracks not_allowed)
			(vias allowed)
			(pads allowed)
			(copperpour not_allowed)
			(footprints allowed)
		)
		(placement
			(enabled no)
			(sheetname "")
		)
		(fill
			(thermal_gap 0.5)
			(thermal_bridge_width 0.5)
			(island_removal_mode 0)
		)
		(polygon
			(pts
				(arc
					(start 393.2174 -400.858228)
					(mid 392.51382 -400.858228)
					(end 393.2174 -400.858228)
				)
			)
		)
	)
	(zone
		(layer "B.Cu")
		(hatch none 0.5)
		(connect_pads
			(clearance 0)
		)
		(min_thickness 0.25)
		(keepout
			(tracks not_allowed)
			(vias allowed)
			(pads allowed)
			(copperpour not_allowed)
			(footprints allowed)
		)
		(placement
			(enabled no)
			(sheetname "")
		)
		(fill
			(thermal_gap 0.5)
			(thermal_bridge_width 0.5)
			(island_removal_mode 0)
		)
		(polygon
			(pts
				(arc
					(start 379.17247 -225.203258)
					(mid 378.51969 -225.203258)
					(end 379.17247 -225.203258)
				)
			)
		)
	)
	(zone
		(layer "B.Cu")
		(hatch none 0.5)
		(connect_pads
			(clearance 0)
		)
		(min_thickness 0.25)
		(keepout
			(tracks not_allowed)
			(vias allowed)
			(pads allowed)
			(copperpour not_allowed)
			(footprints allowed)
		)
		(placement
			(enabled no)
			(sheetname "")
		)
		(fill
			(thermal_gap 0.5)
			(thermal_bridge_width 0.5)
			(island_removal_mode 0)
		)
		(polygon
			(pts
				(arc
					(start 96.903032 -45.077634)
					(mid 95.784625 -44.173275)
					(end 94.383098 -43.850052)
				)
				(arc
					(start 92.782898 -43.850052)
					(mid 89.583006 -47.049944)
					(end 92.782898 -50.249836)
				)
				(arc
					(start 94.383098 -50.249836)
					(mid 95.784661 -49.926686)
					(end 96.903032 -49.022254)
				)
				(arc
					(start 96.903032 -49.022254)
					(mid 101.402945 -50.917846)
					(end 104.383078 -47.049944)
				)
				(arc
					(start 104.383078 -47.049944)
					(mid 101.402918 -43.182144)
					(end 96.903032 -45.077634)
				)
			)
		)
	)
	(zone
		(layer "B.Cu")
		(hatch none 0.5)
		(connect_pads
			(clearance 0)
		)
		(min_thickness 0.25)
		(keepout
			(tracks not_allowed)
			(vias allowed)
			(pads allowed)
			(copperpour not_allowed)
			(footprints allowed)
		)
		(placement
			(enabled no)
			(sheetname "")
		)
		(fill
			(thermal_gap 0.5)
			(thermal_bridge_width 0.5)
			(island_removal_mode 0)
		)
		(polygon
			(pts
				(arc
					(start 368.83467 -223.575626)
					(mid 368.18189 -223.575626)
					(end 368.83467 -223.575626)
				)
			)
		)
	)
	(zone
		(layer "B.Cu")
		(hatch none 0.5)
		(connect_pads
			(clearance 0)
		)
		(min_thickness 0.25)
		(keepout
			(tracks not_allowed)
			(vias allowed)
			(pads allowed)
			(copperpour not_allowed)
			(footprints allowed)
		)
		(placement
			(enabled no)
			(sheetname "")
		)
		(fill
			(thermal_gap 0.5)
			(thermal_bridge_width 0.5)
			(island_removal_mode 0)
		)
		(polygon
			(pts
				(arc
					(start 134.052056 -223.575626)
					(mid 133.399276 -223.575626)
					(end 134.052056 -223.575626)
				)
			)
		)
	)
	(zone
		(layer "B.Cu")
		(hatch none 0.5)
		(connect_pads
			(clearance 0)
		)
		(min_thickness 0.25)
		(keepout
			(tracks allowed)
			(vias allowed)
			(pads allowed)
			(copperpour allowed)
			(footprints allowed)
		)
		(placement
			(enabled no)
			(sheetname "")
		)
		(fill
			(thermal_gap 0.5)
			(thermal_bridge_width 0.5)
			(island_removal_mode 0)
		)
		(polygon
			(pts
				(xy 364.109 -355.072188) (xy 364.109 -353.502468) (xy 365.07674 -353.502468) (xy 365.07674 -355.072188)
			)
		)
	)
	(zone
		(layer "B.Cu")
		(hatch none 0.5)
		(connect_pads
			(clearance 0)
		)
		(min_thickness 0.25)
		(keepout
			(tracks allowed)
			(vias allowed)
			(pads allowed)
			(copperpour allowed)
			(footprints allowed)
		)
		(placement
			(enabled no)
			(sheetname "")
		)
		(fill
			(thermal_gap 0.5)
			(thermal_bridge_width 0.5)
			(island_removal_mode 0)
		)
		(polygon
			(pts
				(xy 420.88054 -134.826248) (xy 420.88054 -137.770108) (xy 421.3733 -138.262868) (xy 421.63746 -138.262868)
				(xy 422.13022 -137.770108) (xy 422.13022 -134.993888) (xy 421.47998 -134.343648) (xy 421.36314 -134.343648)
			)
		)
	)
	(zone
		(layer "B.Cu")
		(hatch none 0.5)
		(connect_pads
			(clearance 0)
		)
		(min_thickness 0.25)
		(keepout
			(tracks allowed)
			(vias allowed)
			(pads allowed)
			(copperpour allowed)
			(footprints not_allowed)
		)
		(placement
			(enabled no)
			(sheetname "")
		)
		(fill
			(thermal_gap 0.5)
			(thermal_bridge_width 0.5)
			(island_removal_mode 0)
		)
		(polygon
			(pts
				(arc
					(start 318.44996 -68.449952)
					(mid 316.900052 -66.900044)
					(end 315.34989 -68.449952)
				)
				(arc
					(start 315.34989 -68.449952)
					(mid 316.900052 -70.000114)
					(end 318.44996 -68.449952)
				)
			)
		)
	)
	(zone
		(layer "B.Cu")
		(hatch none 0.5)
		(connect_pads
			(clearance 0)
		)
		(min_thickness 0.25)
		(keepout
			(tracks allowed)
			(vias allowed)
			(pads allowed)
			(copperpour allowed)
			(footprints allowed)
		)
		(placement
			(enabled no)
			(sheetname "")
		)
		(fill
			(thermal_gap 0.5)
			(thermal_bridge_width 0.5)
			(island_removal_mode 0)
		)
		(polygon
			(pts
				(xy 113.85042 -338.430108) (xy 113.85042 -334.198468) (xy 107.8738 -334.198468) (xy 107.8738 -338.430108)
			)
		)
	)
	(zone
		(layer "B.Cu")
		(hatch none 0.5)
		(connect_pads
			(clearance 0)
		)
		(min_thickness 0.25)
		(keepout
			(tracks allowed)
			(vias allowed)
			(pads allowed)
			(copperpour allowed)
			(footprints allowed)
		)
		(placement
			(enabled no)
			(sheetname "")
		)
		(fill
			(thermal_gap 0.5)
			(thermal_bridge_width 0.5)
			(island_removal_mode 0)
		)
		(polygon
			(pts
				(xy 177.2285 -56.44388) (xy 177.2285 -55.66664) (xy 178.6636 -55.66664) (xy 178.6636 -56.44388)
			)
		)
	)
	(zone
		(layer "B.Cu")
		(hatch none 0.5)
		(connect_pads
			(clearance 0)
		)
		(min_thickness 0.25)
		(keepout
			(tracks not_allowed)
			(vias allowed)
			(pads allowed)
			(copperpour not_allowed)
			(footprints allowed)
		)
		(placement
			(enabled no)
			(sheetname "")
		)
		(fill
			(thermal_gap 0.5)
			(thermal_bridge_width 0.5)
			(island_removal_mode 0)
		)
		(polygon
			(pts
				(arc
					(start 231.650032 -352.49993)
					(mid 236.650022 -357.49992)
					(end 241.650012 -352.49993)
				)
				(arc
					(start 241.650012 -352.49993)
					(mid 236.650022 -347.49994)
					(end 231.650032 -352.49993)
				)
			)
		)
	)
	(zone
		(layer "B.Cu")
		(hatch none 0.5)
		(connect_pads
			(clearance 0)
		)
		(min_thickness 0.25)
		(keepout
			(tracks allowed)
			(vias allowed)
			(pads allowed)
			(copperpour allowed)
			(footprints not_allowed)
		)
		(placement
			(enabled no)
			(sheetname "")
		)
		(fill
			(thermal_gap 0.5)
			(thermal_bridge_width 0.5)
			(island_removal_mode 0)
		)
		(polygon
			(pts
				(arc
					(start 351.775014 -431.360072)
					(mid 359.774998 -439.360056)
					(end 367.774982 -431.360072)
				)
				(arc
					(start 367.774982 -431.360072)
					(mid 359.774998 -423.360088)
					(end 351.775014 -431.360072)
				)
			)
		)
	)
	(zone
		(layer "B.Cu")
		(hatch none 0.5)
		(connect_pads
			(clearance 0)
		)
		(min_thickness 0.25)
		(keepout
			(tracks not_allowed)
			(vias allowed)
			(pads allowed)
			(copperpour not_allowed)
			(footprints allowed)
		)
		(placement
			(enabled no)
			(sheetname "")
		)
		(fill
			(thermal_gap 0.5)
			(thermal_bridge_width 0.5)
			(island_removal_mode 0)
		)
		(polygon
			(pts
				(arc
					(start 120.894602 -223.575626)
					(mid 120.241822 -223.575626)
					(end 120.894602 -223.575626)
				)
			)
		)
	)
	(zone
		(layer "B.Cu")
		(hatch none 0.5)
		(connect_pads
			(clearance 0)
		)
		(min_thickness 0.25)
		(keepout
			(tracks allowed)
			(vias allowed)
			(pads allowed)
			(copperpour allowed)
			(footprints allowed)
		)
		(placement
			(enabled no)
			(sheetname "")
		)
		(fill
			(thermal_gap 0.5)
			(thermal_bridge_width 0.5)
			(island_removal_mode 0)
		)
		(polygon
			(pts
				(xy 172.42536 -358.191308) (xy 172.42536 -355.425248) (xy 167.91432 -355.425248) (xy 167.91432 -358.191308)
			)
		)
	)
	(zone
		(layer "B.Cu")
		(hatch none 0.5)
		(connect_pads
			(clearance 0)
		)
		(min_thickness 0.25)
		(keepout
			(tracks allowed)
			(vias allowed)
			(pads allowed)
			(copperpour allowed)
			(footprints allowed)
		)
		(placement
			(enabled no)
			(sheetname "")
		)
		(fill
			(thermal_gap 0.5)
			(thermal_bridge_width 0.5)
			(island_removal_mode 0)
		)
		(polygon
			(pts
				(xy 419.8874 -194.208908) (xy 419.8874 -192.745868) (xy 422.48582 -192.745868) (xy 422.48582 -194.208908)
			)
		)
	)
	(zone
		(layer "B.Cu")
		(hatch none 0.5)
		(connect_pads
			(clearance 0)
		)
		(min_thickness 0.25)
		(keepout
			(tracks not_allowed)
			(vias allowed)
			(pads allowed)
			(copperpour not_allowed)
			(footprints allowed)
		)
		(placement
			(enabled no)
			(sheetname "")
		)
		(fill
			(thermal_gap 0.5)
			(thermal_bridge_width 0.5)
			(island_removal_mode 0)
		)
		(polygon
			(pts
				(arc
					(start 346.749624 -224.389442)
					(mid 346.096844 -224.389442)
					(end 346.749624 -224.389442)
				)
			)
		)
	)
	(zone
		(layer "B.Cu")
		(hatch none 0.5)
		(connect_pads
			(clearance 0)
		)
		(min_thickness 0.25)
		(keepout
			(tracks not_allowed)
			(vias allowed)
			(pads allowed)
			(copperpour not_allowed)
			(footprints allowed)
		)
		(placement
			(enabled no)
			(sheetname "")
		)
		(fill
			(thermal_gap 0.5)
			(thermal_bridge_width 0.5)
			(island_removal_mode 0)
		)
		(polygon
			(pts
				(arc
					(start 101.628956 -224.389442)
					(mid 100.976176 -224.389442)
					(end 101.628956 -224.389442)
				)
			)
		)
	)
	(zone
		(layer "B.Cu")
		(hatch none 0.5)
		(connect_pads
			(clearance 0)
		)
		(min_thickness 0.25)
		(keepout
			(tracks not_allowed)
			(vias allowed)
			(pads allowed)
			(copperpour not_allowed)
			(footprints allowed)
		)
		(placement
			(enabled no)
			(sheetname "")
		)
		(fill
			(thermal_gap 0.5)
			(thermal_bridge_width 0.5)
			(island_removal_mode 0)
		)
		(polygon
			(pts
				(arc
					(start 85.954108 -400.858228)
					(mid 85.250528 -400.858228)
					(end 85.954108 -400.858228)
				)
			)
		)
	)
	(zone
		(layer "B.Cu")
		(hatch none 0.5)
		(connect_pads
			(clearance 0)
		)
		(min_thickness 0.25)
		(keepout
			(tracks not_allowed)
			(vias allowed)
			(pads allowed)
			(copperpour not_allowed)
			(footprints allowed)
		)
		(placement
			(enabled no)
			(sheetname "")
		)
		(fill
			(thermal_gap 0.5)
			(thermal_bridge_width 0.5)
			(island_removal_mode 0)
		)
		(polygon
			(pts
				(arc
					(start 387.09092 -400.858228)
					(mid 386.38734 -400.858228)
					(end 387.09092 -400.858228)
				)
			)
		)
	)
	(zone
		(layer "B.Cu")
		(hatch none 0.5)
		(connect_pads
			(clearance 0)
		)
		(min_thickness 0.25)
		(keepout
			(tracks not_allowed)
			(vias allowed)
			(pads allowed)
			(copperpour not_allowed)
			(footprints allowed)
		)
		(placement
			(enabled no)
			(sheetname "")
		)
		(fill
			(thermal_gap 0.5)
			(thermal_bridge_width 0.5)
			(island_removal_mode 0)
		)
		(polygon
			(pts
				(arc
					(start 381.82804 -400.858228)
					(mid 381.12446 -400.858228)
					(end 381.82804 -400.858228)
				)
			)
		)
	)
	(zone
		(layer "B.Cu")
		(hatch none 0.5)
		(connect_pads
			(clearance 0)
		)
		(min_thickness 0.25)
		(keepout
			(tracks not_allowed)
			(vias allowed)
			(pads allowed)
			(copperpour not_allowed)
			(footprints allowed)
		)
		(placement
			(enabled no)
			(sheetname "")
		)
		(fill
			(thermal_gap 0.5)
			(thermal_bridge_width 0.5)
			(island_removal_mode 0)
		)
		(polygon
			(pts
				(arc
					(start 371.65407 -225.203258)
					(mid 371.00129 -225.203258)
					(end 371.65407 -225.203258)
				)
			)
		)
	)
	(zone
		(layer "B.Cu")
		(hatch none 0.5)
		(connect_pads
			(clearance 0)
		)
		(min_thickness 0.25)
		(keepout
			(tracks not_allowed)
			(vias allowed)
			(pads allowed)
			(copperpour not_allowed)
			(footprints allowed)
		)
		(placement
			(enabled no)
			(sheetname "")
		)
		(fill
			(thermal_gap 0.5)
			(thermal_bridge_width 0.5)
			(island_removal_mode 0)
		)
		(polygon
			(pts
				(arc
					(start 339.70087 -225.203258)
					(mid 339.04809 -225.203258)
					(end 339.70087 -225.203258)
				)
			)
		)
	)
	(zone
		(layer "B.Cu")
		(hatch none 0.5)
		(connect_pads
			(clearance 0)
		)
		(min_thickness 0.25)
		(keepout
			(tracks allowed)
			(vias allowed)
			(pads allowed)
			(copperpour allowed)
			(footprints allowed)
		)
		(placement
			(enabled no)
			(sheetname "")
		)
		(fill
			(thermal_gap 0.5)
			(thermal_bridge_width 0.5)
			(island_removal_mode 0)
		)
		(polygon
			(pts
				(xy 354.7491 -45.9105) (xy 354.7491 -44.83608) (xy 357.90632 -44.83608) (xy 357.90632 -45.9105)
			)
		)
	)
	(zone
		(layer "B.Cu")
		(hatch none 0.5)
		(connect_pads
			(clearance 0)
		)
		(min_thickness 0.25)
		(keepout
			(tracks not_allowed)
			(vias allowed)
			(pads allowed)
			(copperpour not_allowed)
			(footprints allowed)
		)
		(placement
			(enabled no)
			(sheetname "")
		)
		(fill
			(thermal_gap 0.5)
			(thermal_bridge_width 0.5)
			(island_removal_mode 0)
		)
		(polygon
			(pts
				(arc
					(start 122.774202 -223.575626)
					(mid 122.121422 -223.575626)
					(end 122.774202 -223.575626)
				)
			)
		)
	)
	(zone
		(layer "B.Cu")
		(hatch none 0.5)
		(connect_pads
			(clearance 0)
		)
		(min_thickness 0.25)
		(keepout
			(tracks not_allowed)
			(vias allowed)
			(pads allowed)
			(copperpour not_allowed)
			(footprints allowed)
		)
		(placement
			(enabled no)
			(sheetname "")
		)
		(fill
			(thermal_gap 0.5)
			(thermal_bridge_width 0.5)
			(island_removal_mode 0)
		)
		(polygon
			(pts
				(arc
					(start 380.458726 -354.434902)
					(mid 384.458972 -358.435148)
					(end 388.458964 -354.434902)
				)
				(arc
					(start 388.458964 -354.434902)
					(mid 384.458972 -350.43491)
					(end 380.458726 -354.434902)
				)
			)
		)
	)
	(zone
		(layer "B.Cu")
		(hatch none 0.5)
		(connect_pads
			(clearance 0)
		)
		(min_thickness 0.25)
		(keepout
			(tracks not_allowed)
			(vias allowed)
			(pads allowed)
			(copperpour not_allowed)
			(footprints allowed)
		)
		(placement
			(enabled no)
			(sheetname "")
		)
		(fill
			(thermal_gap 0.5)
			(thermal_bridge_width 0.5)
			(island_removal_mode 0)
		)
		(polygon
			(pts
				(arc
					(start 403.27072 -400.858228)
					(mid 402.56714 -400.858228)
					(end 403.27072 -400.858228)
				)
			)
		)
	)
	(zone
		(layer "B.Cu")
		(hatch none 0.5)
		(connect_pads
			(clearance 0)
		)
		(min_thickness 0.25)
		(keepout
			(tracks not_allowed)
			(vias allowed)
			(pads allowed)
			(copperpour not_allowed)
			(footprints allowed)
		)
		(placement
			(enabled no)
			(sheetname "")
		)
		(fill
			(thermal_gap 0.5)
			(thermal_bridge_width 0.5)
			(island_removal_mode 0)
		)
		(polygon
			(pts
				(arc
					(start 138.886184 -400.858228)
					(mid 138.182604 -400.858228)
					(end 138.886184 -400.858228)
				)
			)
		)
	)
	(zone
		(layer "B.Cu")
		(hatch none 0.5)
		(connect_pads
			(clearance 0)
		)
		(min_thickness 0.25)
		(keepout
			(tracks not_allowed)
			(vias allowed)
			(pads allowed)
			(copperpour not_allowed)
			(footprints allowed)
		)
		(placement
			(enabled no)
			(sheetname "")
		)
		(fill
			(thermal_gap 0.5)
			(thermal_bridge_width 0.5)
			(island_removal_mode 0)
		)
		(polygon
			(pts
				(arc
					(start 414.66008 -400.858228)
					(mid 413.9565 -400.858228)
					(end 414.66008 -400.858228)
				)
			)
		)
	)
	(zone
		(layer "B.Cu")
		(hatch none 0.5)
		(connect_pads
			(clearance 0)
		)
		(min_thickness 0.25)
		(keepout
			(tracks allowed)
			(vias allowed)
			(pads allowed)
			(copperpour allowed)
			(footprints not_allowed)
		)
		(placement
			(enabled no)
			(sheetname "")
		)
		(fill
			(thermal_gap 0.5)
			(thermal_bridge_width 0.5)
			(island_removal_mode 0)
		)
		(polygon
			(pts
				(arc
					(start 446.300098 -435.600094)
					(mid 448.80022 -438.100216)
					(end 451.300088 -435.600094)
				)
				(arc
					(start 451.300088 -435.600094)
					(mid 448.80022 -433.100226)
					(end 446.300098 -435.600094)
				)
			)
		)
	)
	(zone
		(layer "B.Cu")
		(hatch none 0.5)
		(connect_pads
			(clearance 0)
		)
		(min_thickness 0.25)
		(keepout
			(tracks not_allowed)
			(vias allowed)
			(pads allowed)
			(copperpour not_allowed)
			(footprints allowed)
		)
		(placement
			(enabled no)
			(sheetname "")
		)
		(fill
			(thermal_gap 0.5)
			(thermal_bridge_width 0.5)
			(island_removal_mode 0)
		)
		(polygon
			(pts
				(arc
					(start 98.809556 -224.389442)
					(mid 98.156776 -224.389442)
					(end 98.809556 -224.389442)
				)
			)
		)
	)
	(zone
		(layer "B.Cu")
		(hatch none 0.5)
		(connect_pads
			(clearance 0)
		)
		(min_thickness 0.25)
		(keepout
			(tracks not_allowed)
			(vias allowed)
			(pads allowed)
			(copperpour not_allowed)
			(footprints allowed)
		)
		(placement
			(enabled no)
			(sheetname "")
		)
		(fill
			(thermal_gap 0.5)
			(thermal_bridge_width 0.5)
			(island_removal_mode 0)
		)
		(polygon
			(pts
				(arc
					(start 331.047598 -407.00452)
					(mid 330.344018 -407.00452)
					(end 331.047598 -407.00452)
				)
			)
		)
	)
	(zone
		(layer "B.Cu")
		(hatch none 0.5)
		(connect_pads
			(clearance 0)
		)
		(min_thickness 0.25)
		(keepout
			(tracks not_allowed)
			(vias allowed)
			(pads allowed)
			(copperpour not_allowed)
			(footprints allowed)
		)
		(placement
			(enabled no)
			(sheetname "")
		)
		(fill
			(thermal_gap 0.5)
			(thermal_bridge_width 0.5)
			(island_removal_mode 0)
		)
		(polygon
			(pts
				(arc
					(start 308.741318 -407.00452)
					(mid 308.037738 -407.00452)
					(end 308.741318 -407.00452)
				)
			)
		)
	)
	(zone
		(layer "B.Cu")
		(hatch none 0.5)
		(connect_pads
			(clearance 0)
		)
		(min_thickness 0.25)
		(keepout
			(tracks not_allowed)
			(vias allowed)
			(pads allowed)
			(copperpour not_allowed)
			(footprints allowed)
		)
		(placement
			(enabled no)
			(sheetname "")
		)
		(fill
			(thermal_gap 0.5)
			(thermal_bridge_width 0.5)
			(island_removal_mode 0)
		)
		(polygon
			(pts
				(arc
					(start 182.550054 -435.600094)
					(mid 179.750212 -432.800252)
					(end 176.950116 -435.600094)
				)
				(arc
					(start 176.950116 -435.600094)
					(mid 179.750212 -438.40019)
					(end 182.550054 -435.600094)
				)
			)
		)
	)
	(zone
		(layer "B.Cu")
		(hatch none 0.5)
		(connect_pads
			(clearance 0)
		)
		(min_thickness 0.25)
		(keepout
			(tracks not_allowed)
			(vias allowed)
			(pads allowed)
			(copperpour not_allowed)
			(footprints allowed)
		)
		(placement
			(enabled no)
			(sheetname "")
		)
		(fill
			(thermal_gap 0.5)
			(thermal_bridge_width 0.5)
			(island_removal_mode 0)
		)
		(polygon
			(pts
				(arc
					(start 306.541678 -407.00452)
					(mid 305.838098 -407.00452)
					(end 306.541678 -407.00452)
				)
			)
		)
	)
	(zone
		(layer "B.Cu")
		(hatch none 0.5)
		(connect_pads
			(clearance 0)
		)
		(min_thickness 0.25)
		(keepout
			(tracks not_allowed)
			(vias allowed)
			(pads allowed)
			(copperpour not_allowed)
			(footprints allowed)
		)
		(placement
			(enabled no)
			(sheetname "")
		)
		(fill
			(thermal_gap 0.5)
			(thermal_bridge_width 0.5)
			(island_removal_mode 0)
		)
		(polygon
			(pts
				(arc
					(start 151.139144 -400.858228)
					(mid 150.435564 -400.858228)
					(end 151.139144 -400.858228)
				)
			)
		)
	)
	(zone
		(layer "B.Cu")
		(hatch none 0.5)
		(connect_pads
			(clearance 0)
		)
		(min_thickness 0.25)
		(keepout
			(tracks allowed)
			(vias allowed)
			(pads allowed)
			(copperpour allowed)
			(footprints allowed)
		)
		(placement
			(enabled no)
			(sheetname "")
		)
		(fill
			(thermal_gap 0.5)
			(thermal_bridge_width 0.5)
			(island_removal_mode 0)
		)
		(polygon
			(pts
				(xy 221.88678 -73.15962) (xy 221.88678 -72.51954) (xy 224.08134 -72.51954) (xy 224.08134 -73.15962)
			)
		)
	)
	(zone
		(layer "B.Cu")
		(hatch none 0.5)
		(connect_pads
			(clearance 0)
		)
		(min_thickness 0.25)
		(keepout
			(tracks allowed)
			(vias allowed)
			(pads allowed)
			(copperpour allowed)
			(footprints allowed)
		)
		(placement
			(enabled no)
			(sheetname "")
		)
		(fill
			(thermal_gap 0.5)
			(thermal_bridge_width 0.5)
			(island_removal_mode 0)
		)
		(polygon
			(pts
				(xy 349.38462 -333.45755) (xy 350.7232 -333.45755) (xy 351.1169 -333.85125) (xy 351.1169 -336.06613)
				(xy 351.3074 -336.25663) (xy 354.85324 -336.25663) (xy 355.06914 -336.47253) (xy 355.06914 -338.63407)
				(xy 354.90912 -338.79409) (xy 349.47352 -338.79409) (xy 349.02902 -338.34959) (xy 349.02902 -333.81315)
			)
		)
	)
	(zone
		(layer "B.Cu")
		(hatch none 0.5)
		(connect_pads
			(clearance 0)
		)
		(min_thickness 0.25)
		(keepout
			(tracks allowed)
			(vias allowed)
			(pads allowed)
			(copperpour allowed)
			(footprints not_allowed)
		)
		(placement
			(enabled no)
			(sheetname "")
		)
		(fill
			(thermal_gap 0.5)
			(thermal_bridge_width 0.5)
			(island_removal_mode 0)
		)
		(polygon
			(pts
				(arc
					(start 121.000012 -237.06455)
					(mid 120.560636 -236.003802)
					(end 119.499888 -235.564426)
				)
				(arc
					(start 116.910104 -235.564426)
					(mid 115.849356 -236.003802)
					(end 115.40998 -237.06455)
				)
				(arc
					(start 115.40998 -261.5946)
					(mid 115.849356 -262.655348)
					(end 116.910104 -263.09447)
				)
				(arc
					(start 119.499888 -263.09447)
					(mid 120.56062 -262.655258)
					(end 121.000012 -261.5946)
				)
			)
		)
	)
	(zone
		(layer "B.Cu")
		(hatch none 0.5)
		(connect_pads
			(clearance 0)
		)
		(min_thickness 0.25)
		(keepout
			(tracks allowed)
			(vias allowed)
			(pads allowed)
			(copperpour allowed)
			(footprints allowed)
		)
		(placement
			(enabled no)
			(sheetname "")
		)
		(fill
			(thermal_gap 0.5)
			(thermal_bridge_width 0.5)
			(island_removal_mode 0)
		)
		(polygon
			(pts
				(xy 22.2631 -409.70962) (xy 22.2631 -407.77922) (xy 25.18918 -407.77922) (xy 25.18918 -409.70962)
			)
		)
	)
	(zone
		(layer "B.Cu")
		(hatch none 0.5)
		(connect_pads
			(clearance 0)
		)
		(min_thickness 0.25)
		(keepout
			(tracks not_allowed)
			(vias allowed)
			(pads allowed)
			(copperpour not_allowed)
			(footprints allowed)
		)
		(placement
			(enabled no)
			(sheetname "")
		)
		(fill
			(thermal_gap 0.5)
			(thermal_bridge_width 0.5)
			(island_removal_mode 0)
		)
		(polygon
			(pts
				(arc
					(start 408.5336 -400.858228)
					(mid 407.83002 -400.858228)
					(end 408.5336 -400.858228)
				)
			)
		)
	)
	(zone
		(layer "B.Cu")
		(hatch none 0.5)
		(connect_pads
			(clearance 0)
		)
		(min_thickness 0.25)
		(keepout
			(tracks not_allowed)
			(vias allowed)
			(pads allowed)
			(copperpour not_allowed)
			(footprints allowed)
		)
		(placement
			(enabled no)
			(sheetname "")
		)
		(fill
			(thermal_gap 0.5)
			(thermal_bridge_width 0.5)
			(island_removal_mode 0)
		)
		(polygon
			(pts
				(arc
					(start 327.984358 -407.00452)
					(mid 327.280778 -407.00452)
					(end 327.984358 -407.00452)
				)
			)
		)
	)
	(zone
		(layer "B.Cu")
		(hatch none 0.5)
		(connect_pads
			(clearance 0)
		)
		(min_thickness 0.25)
		(keepout
			(tracks allowed)
			(vias allowed)
			(pads allowed)
			(copperpour allowed)
			(footprints not_allowed)
		)
		(placement
			(enabled no)
			(sheetname "")
		)
		(fill
			(thermal_gap 0.5)
			(thermal_bridge_width 0.5)
			(island_removal_mode 0)
		)
		(polygon
			(pts
				(arc
					(start 453.958706 -150.501096)
					(mid 430.07429 -149.711573)
					(end 449.396358 -163.773866)
				)
				(arc
					(start 449.396358 -163.773866)
					(mid 456.479317 -171.964751)
					(end 467.300056 -171.551854)
				)
				(arc
					(start 467.300056 -149.448012)
					(mid 460.476559 -148.038693)
					(end 453.958706 -150.501096)
				)
			)
		)
	)
	(zone
		(layer "B.Cu")
		(hatch none 0.5)
		(connect_pads
			(clearance 0)
		)
		(min_thickness 0.25)
		(keepout
			(tracks not_allowed)
			(vias allowed)
			(pads allowed)
			(copperpour not_allowed)
			(footprints allowed)
		)
		(placement
			(enabled no)
			(sheetname "")
		)
		(fill
			(thermal_gap 0.5)
			(thermal_bridge_width 0.5)
			(island_removal_mode 0)
		)
		(polygon
			(pts
				(arc
					(start 160.328864 -400.858228)
					(mid 159.625284 -400.858228)
					(end 160.328864 -400.858228)
				)
			)
		)
	)
	(zone
		(layer "B.Cu")
		(hatch none 0.5)
		(connect_pads
			(clearance 0)
		)
		(min_thickness 0.25)
		(keepout
			(tracks not_allowed)
			(vias allowed)
			(pads allowed)
			(copperpour not_allowed)
			(footprints allowed)
		)
		(placement
			(enabled no)
			(sheetname "")
		)
		(fill
			(thermal_gap 0.5)
			(thermal_bridge_width 0.5)
			(island_removal_mode 0)
		)
		(polygon
			(pts
				(arc
					(start 370.244624 -224.389442)
					(mid 369.591844 -224.389442)
					(end 370.244624 -224.389442)
				)
			)
		)
	)
	(zone
		(layer "B.Cu")
		(hatch none 0.5)
		(connect_pads
			(clearance 0)
		)
		(min_thickness 0.25)
		(keepout
			(tracks allowed)
			(vias allowed)
			(pads allowed)
			(copperpour allowed)
			(footprints allowed)
		)
		(placement
			(enabled no)
			(sheetname "")
		)
		(fill
			(thermal_gap 0.5)
			(thermal_bridge_width 0.5)
			(island_removal_mode 0)
		)
		(polygon
			(pts
				(xy 26.81478 -130.879088) (xy 26.81478 -128.102868) (xy 30.28442 -128.102868) (xy 30.28442 -130.879088)
			)
		)
	)
	(zone
		(layer "B.Cu")
		(hatch none 0.5)
		(connect_pads
			(clearance 0)
		)
		(min_thickness 0.25)
		(keepout
			(tracks allowed)
			(vias allowed)
			(pads allowed)
			(copperpour allowed)
			(footprints allowed)
		)
		(placement
			(enabled no)
			(sheetname "")
		)
		(fill
			(thermal_gap 0.5)
			(thermal_bridge_width 0.5)
			(island_removal_mode 0)
		)
		(polygon
			(pts
				(xy 427.87824 -122.542808) (xy 427.87824 -124.849128) (xy 428.17796 -125.148848) (xy 428.64786 -125.148848)
				(xy 429.07966 -124.717048) (xy 429.07966 -122.288808) (xy 428.8409 -122.050048) (xy 428.371 -122.050048)
			)
		)
	)
	(zone
		(layer "B.Cu")
		(hatch none 0.5)
		(connect_pads
			(clearance 0)
		)
		(min_thickness 0.25)
		(keepout
			(tracks allowed)
			(vias allowed)
			(pads allowed)
			(copperpour allowed)
			(footprints allowed)
		)
		(placement
			(enabled no)
			(sheetname "")
		)
		(fill
			(thermal_gap 0.5)
			(thermal_bridge_width 0.5)
			(island_removal_mode 0)
		)
		(polygon
			(pts
				(xy 373.839232 -337.0072) (xy 375.177812 -337.0072) (xy 375.571512 -337.4009) (xy 375.571512 -339.61578)
				(xy 375.762012 -339.80628) (xy 379.307852 -339.80628) (xy 379.523752 -340.02218) (xy 379.523752 -342.18372)
				(xy 379.363732 -342.34374) (xy 373.928132 -342.34374) (xy 373.483632 -341.89924) (xy 373.483632 -337.3628)
			)
		)
	)
	(zone
		(layer "B.Cu")
		(hatch none 0.5)
		(connect_pads
			(clearance 0)
		)
		(min_thickness 0.25)
		(keepout
			(tracks allowed)
			(vias allowed)
			(pads allowed)
			(copperpour allowed)
			(footprints allowed)
		)
		(placement
			(enabled no)
			(sheetname "")
		)
		(fill
			(thermal_gap 0.5)
			(thermal_bridge_width 0.5)
			(island_removal_mode 0)
		)
		(polygon
			(pts
				(xy 50.72634 -316.243208) (xy 50.72634 -315.620908) (xy 51.35372 -315.620908) (xy 51.35372 -316.243208)
			)
		)
	)
	(zone
		(layer "B.Cu")
		(hatch none 0.5)
		(connect_pads
			(clearance 0)
		)
		(min_thickness 0.25)
		(keepout
			(tracks allowed)
			(vias allowed)
			(pads allowed)
			(copperpour allowed)
			(footprints not_allowed)
		)
		(placement
			(enabled no)
			(sheetname "")
		)
		(fill
			(thermal_gap 0.5)
			(thermal_bridge_width 0.5)
			(island_removal_mode 0)
		)
		(polygon
			(pts
				(arc
					(start 191.02832 -440.989974)
					(mid 179.750267 -423.099869)
					(end 168.47185 -440.989974)
				)
			)
		)
	)
	(zone
		(layer "B.Cu")
		(hatch none 0.5)
		(connect_pads
			(clearance 0)
		)
		(min_thickness 0.25)
		(keepout
			(tracks not_allowed)
			(vias allowed)
			(pads allowed)
			(copperpour not_allowed)
			(footprints allowed)
		)
		(placement
			(enabled no)
			(sheetname "")
		)
		(fill
			(thermal_gap 0.5)
			(thermal_bridge_width 0.5)
			(island_removal_mode 0)
		)
		(polygon
			(pts
				(arc
					(start 374.098566 -435.600094)
					(mid 371.298724 -432.800252)
					(end 368.498628 -435.600094)
				)
				(arc
					(start 368.498628 -435.600094)
					(mid 371.298724 -438.40019)
					(end 374.098566 -435.600094)
				)
			)
		)
	)
	(zone
		(layer "B.Cu")
		(hatch none 0.5)
		(connect_pads
			(clearance 0)
		)
		(min_thickness 0.25)
		(keepout
			(tracks not_allowed)
			(vias allowed)
			(pads allowed)
			(copperpour not_allowed)
			(footprints allowed)
		)
		(placement
			(enabled no)
			(sheetname "")
		)
		(fill
			(thermal_gap 0.5)
			(thermal_bridge_width 0.5)
			(island_removal_mode 0)
		)
		(polygon
			(pts
				(arc
					(start 263.645396 -51.999896)
					(mid 268.645386 -56.999886)
					(end 273.645376 -51.999896)
				)
				(arc
					(start 273.645376 -51.999896)
					(mid 268.645386 -46.999906)
					(end 263.645396 -51.999896)
				)
			)
		)
	)
	(zone
		(layer "B.Cu")
		(hatch none 0.5)
		(connect_pads
			(clearance 0)
		)
		(min_thickness 0.25)
		(keepout
			(tracks allowed)
			(vias allowed)
			(pads allowed)
			(copperpour allowed)
			(footprints allowed)
		)
		(placement
			(enabled no)
			(sheetname "")
		)
		(fill
			(thermal_gap 0.5)
			(thermal_bridge_width 0.5)
			(island_removal_mode 0)
		)
		(polygon
			(pts
				(xy 352.12528 -352.151188) (xy 352.12528 -351.216468) (xy 353.47402 -351.216468) (xy 353.47402 -352.151188)
			)
		)
	)
	(zone
		(layer "B.Cu")
		(hatch none 0.5)
		(connect_pads
			(clearance 0)
		)
		(min_thickness 0.25)
		(keepout
			(tracks not_allowed)
			(vias allowed)
			(pads allowed)
			(copperpour not_allowed)
			(footprints allowed)
		)
		(placement
			(enabled no)
			(sheetname "")
		)
		(fill
			(thermal_gap 0.5)
			(thermal_bridge_width 0.5)
			(island_removal_mode 0)
		)
		(polygon
			(pts
				(arc
					(start 378.899928 -22.29993)
					(mid 380.899924 -24.299926)
					(end 382.89992 -22.29993)
				)
				(arc
					(start 382.89992 -22.29993)
					(mid 380.899924 -20.299934)
					(end 378.899928 -22.29993)
				)
			)
		)
	)
	(zone
		(layer "B.Cu")
		(hatch none 0.5)
		(connect_pads
			(clearance 0)
		)
		(min_thickness 0.25)
		(keepout
			(tracks not_allowed)
			(vias allowed)
			(pads allowed)
			(copperpour not_allowed)
			(footprints allowed)
		)
		(placement
			(enabled no)
			(sheetname "")
		)
		(fill
			(thermal_gap 0.5)
			(thermal_bridge_width 0.5)
			(island_removal_mode 0)
		)
		(polygon
			(pts
				(arc
					(start 374.003824 -224.389442)
					(mid 373.351044 -224.389442)
					(end 374.003824 -224.389442)
				)
			)
		)
	)
	(zone
		(layer "B.Cu")
		(hatch none 0.5)
		(connect_pads
			(clearance 0)
		)
		(min_thickness 0.25)
		(keepout
			(tracks allowed)
			(vias allowed)
			(pads allowed)
			(copperpour allowed)
			(footprints not_allowed)
		)
		(placement
			(enabled no)
			(sheetname "")
		)
		(fill
			(thermal_gap 0.5)
			(thermal_bridge_width 0.5)
			(island_removal_mode 0)
		)
		(polygon
			(pts
				(arc
					(start 72.283066 -47.049944)
					(mid 70.383146 -45.150024)
					(end 68.482972 -47.049944)
				)
				(arc
					(start 68.482972 -47.049944)
					(mid 70.383146 -48.950118)
					(end 72.283066 -47.049944)
				)
			)
		)
	)
	(zone
		(layer "B.Cu")
		(hatch none 0.5)
		(connect_pads
			(clearance 0)
		)
		(min_thickness 0.25)
		(keepout
			(tracks allowed)
			(vias allowed)
			(pads allowed)
			(copperpour allowed)
			(footprints allowed)
		)
		(placement
			(enabled no)
			(sheetname "")
		)
		(fill
			(thermal_gap 0.5)
			(thermal_bridge_width 0.5)
			(island_removal_mode 0)
		)
		(polygon
			(pts
				(xy 365.66094 -57.65292) (xy 365.66094 -56.52516) (xy 367.1316 -56.52516) (xy 367.1316 -57.65292)
			)
		)
	)
	(zone
		(layer "B.Cu")
		(hatch none 0.5)
		(connect_pads
			(clearance 0)
		)
		(min_thickness 0.25)
		(keepout
			(tracks not_allowed)
			(vias allowed)
			(pads allowed)
			(copperpour not_allowed)
			(footprints allowed)
		)
		(placement
			(enabled no)
			(sheetname "")
		)
		(fill
			(thermal_gap 0.5)
			(thermal_bridge_width 0.5)
			(island_removal_mode 0)
		)
		(polygon
			(pts
				(xy 128.76022 -27.038808) (xy 128.76022 -26.789888) (xy 128.601978 -26.789888) (xy 128.601978 -27.19705)
				(xy 128.76022 -27.19705)
			)
		)
	)
	(zone
		(layer "B.Cu")
		(hatch none 0.5)
		(connect_pads
			(clearance 0)
		)
		(min_thickness 0.25)
		(keepout
			(tracks not_allowed)
			(vias allowed)
			(pads allowed)
			(copperpour not_allowed)
			(footprints allowed)
		)
		(placement
			(enabled no)
			(sheetname "")
		)
		(fill
			(thermal_gap 0.5)
			(thermal_bridge_width 0.5)
			(island_removal_mode 0)
		)
		(polygon
			(pts
				(arc
					(start 19.635978 -395.979396)
					(mid 18.932398 -395.979396)
					(end 19.635978 -395.979396)
				)
			)
		)
	)
	(zone
		(layer "B.Cu")
		(hatch none 0.5)
		(connect_pads
			(clearance 0)
		)
		(min_thickness 0.25)
		(keepout
			(tracks allowed)
			(vias allowed)
			(pads allowed)
			(copperpour allowed)
			(footprints allowed)
		)
		(placement
			(enabled no)
			(sheetname "")
		)
		(fill
			(thermal_gap 0.5)
			(thermal_bridge_width 0.5)
			(island_removal_mode 0)
		)
		(polygon
			(pts
				(xy 139.414758 -24.176482) (xy 140.08989 -24.851614) (xy 138.759692 -26.181812) (xy 138.08456 -25.506426)
			)
		)
	)
	(zone
		(layer "B.Cu")
		(hatch none 0.5)
		(connect_pads
			(clearance 0)
		)
		(min_thickness 0.25)
		(keepout
			(tracks allowed)
			(vias allowed)
			(pads allowed)
			(copperpour allowed)
			(footprints allowed)
		)
		(placement
			(enabled no)
			(sheetname "")
		)
		(fill
			(thermal_gap 0.5)
			(thermal_bridge_width 0.5)
			(island_removal_mode 0)
		)
		(polygon
			(pts
				(xy 11.22426 -109.36224) (xy 11.22426 -108.03636) (xy 13.0302 -108.03636) (xy 13.0302 -109.36224)
			)
		)
	)
	(zone
		(layer "B.Cu")
		(hatch none 0.5)
		(connect_pads
			(clearance 0)
		)
		(min_thickness 0.25)
		(keepout
			(tracks not_allowed)
			(vias allowed)
			(pads allowed)
			(copperpour not_allowed)
			(footprints allowed)
		)
		(placement
			(enabled no)
			(sheetname "")
		)
		(fill
			(thermal_gap 0.5)
			(thermal_bridge_width 0.5)
			(island_removal_mode 0)
		)
		(polygon
			(pts
				(arc
					(start 340.171024 -224.389442)
					(mid 339.518244 -224.389442)
					(end 340.171024 -224.389442)
				)
			)
		)
	)
	(zone
		(layer "B.Cu")
		(hatch none 0.5)
		(connect_pads
			(clearance 0)
		)
		(min_thickness 0.25)
		(keepout
			(tracks not_allowed)
			(vias allowed)
			(pads allowed)
			(copperpour not_allowed)
			(footprints allowed)
		)
		(placement
			(enabled no)
			(sheetname "")
		)
		(fill
			(thermal_gap 0.5)
			(thermal_bridge_width 0.5)
			(island_removal_mode 0)
		)
		(polygon
			(pts
				(arc
					(start 73.701148 -400.858228)
					(mid 72.997568 -400.858228)
					(end 73.701148 -400.858228)
				)
			)
		)
	)
	(zone
		(layer "B.Cu")
		(hatch none 0.5)
		(connect_pads
			(clearance 0)
		)
		(min_thickness 0.25)
		(keepout
			(tracks allowed)
			(vias allowed)
			(pads allowed)
			(copperpour allowed)
			(footprints not_allowed)
		)
		(placement
			(enabled no)
			(sheetname "")
		)
		(fill
			(thermal_gap 0.5)
			(thermal_bridge_width 0.5)
			(island_removal_mode 0)
		)
		(polygon
			(pts
				(arc
					(start 333.854806 -353.525074)
					(mid 329.854814 -349.525082)
					(end 325.854822 -353.525074)
				)
				(arc
					(start 325.854822 -353.525074)
					(mid 329.854814 -357.525066)
					(end 333.854806 -353.525074)
				)
			)
		)
	)
	(zone
		(layer "B.Cu")
		(hatch none 0.5)
		(connect_pads
			(clearance 0)
		)
		(min_thickness 0.25)
		(keepout
			(tracks not_allowed)
			(vias allowed)
			(pads allowed)
			(copperpour not_allowed)
			(footprints allowed)
		)
		(placement
			(enabled no)
			(sheetname "")
		)
		(fill
			(thermal_gap 0.5)
			(thermal_bridge_width 0.5)
			(island_removal_mode 0)
		)
		(polygon
			(pts
				(arc
					(start 95.050356 -224.389442)
					(mid 94.397576 -224.389442)
					(end 95.050356 -224.389442)
				)
			)
		)
	)
	(zone
		(layer "B.Cu")
		(hatch none 0.5)
		(connect_pads
			(clearance 0)
		)
		(min_thickness 0.25)
		(keepout
			(tracks not_allowed)
			(vias allowed)
			(pads allowed)
			(copperpour not_allowed)
			(footprints allowed)
		)
		(placement
			(enabled no)
			(sheetname "")
		)
		(fill
			(thermal_gap 0.5)
			(thermal_bridge_width 0.5)
			(island_removal_mode 0)
		)
		(polygon
			(pts
				(arc
					(start 320.994278 -407.00452)
					(mid 320.290698 -407.00452)
					(end 320.994278 -407.00452)
				)
			)
		)
	)
	(zone
		(layer "B.Cu")
		(hatch none 0.5)
		(connect_pads
			(clearance 0)
		)
		(min_thickness 0.25)
		(keepout
			(tracks not_allowed)
			(vias allowed)
			(pads allowed)
			(copperpour not_allowed)
			(footprints allowed)
		)
		(placement
			(enabled no)
			(sheetname "")
		)
		(fill
			(thermal_gap 0.5)
			(thermal_bridge_width 0.5)
			(island_removal_mode 0)
		)
		(polygon
			(pts
				(arc
					(start 89.899998 -22.29993)
					(mid 94.899988 -27.29992)
					(end 99.899978 -22.29993)
				)
				(arc
					(start 99.899978 -22.29993)
					(mid 94.899988 -17.29994)
					(end 89.899998 -22.29993)
				)
			)
		)
	)
	(zone
		(layer "B.Cu")
		(hatch none 0.5)
		(connect_pads
			(clearance 0)
		)
		(min_thickness 0.25)
		(keepout
			(tracks not_allowed)
			(vias allowed)
			(pads allowed)
			(copperpour not_allowed)
			(footprints allowed)
		)
		(placement
			(enabled no)
			(sheetname "")
		)
		(fill
			(thermal_gap 0.5)
			(thermal_bridge_width 0.5)
			(island_removal_mode 0)
		)
		(polygon
			(pts
				(arc
					(start 62.782958 -50.249836)
					(mid 59.583066 -47.049944)
					(end 62.782958 -43.850052)
				)
				(arc
					(start 64.382904 -43.850052)
					(mid 65.784467 -44.173202)
					(end 66.902838 -45.077634)
				)
				(arc
					(start 66.902838 -45.077634)
					(mid 74.383465 -47.049944)
					(end 66.902838 -49.022254)
				)
				(arc
					(start 66.902838 -49.022254)
					(mid 65.784431 -49.926613)
					(end 64.382904 -50.249836)
				)
			)
		)
	)
	(zone
		(layer "B.Cu")
		(hatch none 0.5)
		(connect_pads
			(clearance 0)
		)
		(min_thickness 0.25)
		(keepout
			(tracks not_allowed)
			(vias allowed)
			(pads allowed)
			(copperpour not_allowed)
			(footprints allowed)
		)
		(placement
			(enabled no)
			(sheetname "")
		)
		(fill
			(thermal_gap 0.5)
			(thermal_bridge_width 0.5)
			(island_removal_mode 0)
		)
		(polygon
			(pts
				(arc
					(start 1.999996 -22.29993)
					(mid 6.999986 -27.29992)
					(end 11.999976 -22.29993)
				)
				(arc
					(start 11.999976 -22.29993)
					(mid 6.999986 -17.29994)
					(end 1.999996 -22.29993)
				)
			)
		)
	)
	(zone
		(layer "B.Cu")
		(hatch none 0.5)
		(connect_pads
			(clearance 0)
		)
		(min_thickness 0.25)
		(keepout
			(tracks not_allowed)
			(vias allowed)
			(pads allowed)
			(copperpour not_allowed)
			(footprints allowed)
		)
		(placement
			(enabled no)
			(sheetname "")
		)
		(fill
			(thermal_gap 0.5)
			(thermal_bridge_width 0.5)
			(island_removal_mode 0)
		)
		(polygon
			(pts
				(arc
					(start 338.76107 -223.575626)
					(mid 338.10829 -223.575626)
					(end 338.76107 -223.575626)
				)
			)
		)
	)
	(zone
		(layer "B.Cu")
		(hatch none 0.5)
		(connect_pads
			(clearance 0)
		)
		(min_thickness 0.25)
		(keepout
			(tracks not_allowed)
			(vias allowed)
			(pads allowed)
			(copperpour not_allowed)
			(footprints allowed)
		)
		(placement
			(enabled no)
			(sheetname "")
		)
		(fill
			(thermal_gap 0.5)
			(thermal_bridge_width 0.5)
			(island_removal_mode 0)
		)
		(polygon
			(pts
				(arc
					(start 373.53367 -225.203258)
					(mid 372.88089 -225.203258)
					(end 373.53367 -225.203258)
				)
			)
		)
	)
	(zone
		(layer "B.Cu")
		(hatch none 0.5)
		(connect_pads
			(clearance 0)
		)
		(min_thickness 0.25)
		(keepout
			(tracks allowed)
			(vias allowed)
			(pads allowed)
			(copperpour allowed)
			(footprints not_allowed)
		)
		(placement
			(enabled no)
			(sheetname "")
		)
		(fill
			(thermal_gap 0.5)
			(thermal_bridge_width 0.5)
			(island_removal_mode 0)
		)
		(polygon
			(pts
				(arc
					(start 458.659992 -160.50006)
					(mid 461.460088 -163.300156)
					(end 464.25993 -160.50006)
				)
				(arc
					(start 464.25993 -160.50006)
					(mid 461.460088 -157.700218)
					(end 458.659992 -160.50006)
				)
			)
		)
	)
	(zone
		(layer "B.Cu")
		(hatch none 0.5)
		(connect_pads
			(clearance 0)
		)
		(min_thickness 0.25)
		(keepout
			(tracks not_allowed)
			(vias allowed)
			(pads allowed)
			(copperpour not_allowed)
			(footprints allowed)
		)
		(placement
			(enabled no)
			(sheetname "")
		)
		(fill
			(thermal_gap 0.5)
			(thermal_bridge_width 0.5)
			(island_removal_mode 0)
		)
		(polygon
			(pts
				(arc
					(start 384.02768 -400.858228)
					(mid 383.3241 -400.858228)
					(end 384.02768 -400.858228)
				)
			)
		)
	)
	(zone
		(layer "B.Cu")
		(hatch none 0.5)
		(connect_pads
			(clearance 0)
		)
		(min_thickness 0.25)
		(keepout
			(tracks allowed)
			(vias allowed)
			(pads allowed)
			(copperpour allowed)
			(footprints not_allowed)
		)
		(placement
			(enabled no)
			(sheetname "")
		)
		(fill
			(thermal_gap 0.5)
			(thermal_bridge_width 0.5)
			(island_removal_mode 0)
		)
		(polygon
			(pts
				(arc
					(start 94.383098 -50.25009)
					(mid 95.784681 -49.926806)
					(end 96.903032 -49.022254)
				)
				(arc
					(start 96.903032 -49.022254)
					(mid 101.402945 -50.917846)
					(end 104.383078 -47.049944)
				)
				(arc
					(start 104.383078 -47.049944)
					(mid 101.402812 -43.182116)
					(end 96.903032 -45.077888)
				)
				(arc
					(start 96.903032 -45.077888)
					(mid 95.784665 -44.173369)
					(end 94.383098 -43.850052)
				)
				(arc
					(start 92.782898 -43.850052)
					(mid 89.582752 -47.050198)
					(end 92.782898 -50.25009)
				)
			)
		)
	)
	(zone
		(layer "B.Cu")
		(hatch none 0.5)
		(connect_pads
			(clearance 0)
		)
		(min_thickness 0.25)
		(keepout
			(tracks allowed)
			(vias allowed)
			(pads allowed)
			(copperpour allowed)
			(footprints allowed)
		)
		(placement
			(enabled no)
			(sheetname "")
		)
		(fill
			(thermal_gap 0.5)
			(thermal_bridge_width 0.5)
			(island_removal_mode 0)
		)
		(polygon
			(pts
				(xy 50.141124 -157.505146) (xy 52.800504 -157.505146) (xy 53.110384 -157.195266) (xy 53.110384 -153.972006)
				(xy 53.458364 -153.624026) (xy 55.508144 -153.624026) (xy 55.945024 -153.187146) (xy 55.945024 -151.612346)
				(xy 55.185564 -150.852886) (xy 52.086764 -150.852886) (xy 52.000404 -150.939246) (xy 52.000404 -151.011128)
				(xy 50.8 -152.211532) (xy 50.8 -152.925526) (xy 50.341784 -152.925526) (xy 50.001424 -153.265886)
				(xy 50.001424 -157.365446)
			)
		)
	)
	(zone
		(layer "B.Cu")
		(hatch none 0.5)
		(connect_pads
			(clearance 0)
		)
		(min_thickness 0.25)
		(keepout
			(tracks not_allowed)
			(vias allowed)
			(pads allowed)
			(copperpour not_allowed)
			(footprints allowed)
		)
		(placement
			(enabled no)
			(sheetname "")
		)
		(fill
			(thermal_gap 0.5)
			(thermal_bridge_width 0.5)
			(island_removal_mode 0)
		)
		(polygon
			(pts
				(arc
					(start 342.990424 -224.389442)
					(mid 342.337644 -224.389442)
					(end 342.990424 -224.389442)
				)
			)
		)
	)
	(zone
		(layer "B.Cu")
		(hatch none 0.5)
		(connect_pads
			(clearance 0)
		)
		(min_thickness 0.25)
		(keepout
			(tracks allowed)
			(vias allowed)
			(pads allowed)
			(copperpour allowed)
			(footprints not_allowed)
		)
		(placement
			(enabled no)
			(sheetname "")
		)
		(fill
			(thermal_gap 0.5)
			(thermal_bridge_width 0.5)
			(island_removal_mode 0)
		)
		(polygon
			(pts
				(arc
					(start 304.721768 -70.411086)
					(mid 293.003268 -53.56121)
					(end 281.284426 -70.411086)
				)
				(arc
					(start 281.284426 -70.411086)
					(mid 293.003268 -87.2612)
					(end 304.721768 -70.411086)
				)
			)
		)
	)
	(zone
		(layer "B.Cu")
		(hatch none 0.5)
		(connect_pads
			(clearance 0)
		)
		(min_thickness 0.25)
		(keepout
			(tracks not_allowed)
			(vias allowed)
			(pads allowed)
			(copperpour not_allowed)
			(footprints allowed)
		)
		(placement
			(enabled no)
			(sheetname "")
		)
		(fill
			(thermal_gap 0.5)
			(thermal_bridge_width 0.5)
			(island_removal_mode 0)
		)
		(polygon
			(pts
				(arc
					(start 100.219002 -223.575626)
					(mid 99.566222 -223.575626)
					(end 100.219002 -223.575626)
				)
			)
		)
	)
	(zone
		(layer "B.Cu")
		(hatch none 0.5)
		(connect_pads
			(clearance 0)
		)
		(min_thickness 0.25)
		(keepout
			(tracks not_allowed)
			(vias allowed)
			(pads allowed)
			(copperpour not_allowed)
			(footprints allowed)
		)
		(placement
			(enabled no)
			(sheetname "")
		)
		(fill
			(thermal_gap 0.5)
			(thermal_bridge_width 0.5)
			(island_removal_mode 0)
		)
		(polygon
			(pts
				(arc
					(start 345.500198 -407.00452)
					(mid 344.796618 -407.00452)
					(end 345.500198 -407.00452)
				)
			)
		)
	)
	(zone
		(layer "B.Cu")
		(hatch none 0.5)
		(connect_pads
			(clearance 0)
		)
		(min_thickness 0.25)
		(keepout
			(tracks not_allowed)
			(vias allowed)
			(pads allowed)
			(copperpour not_allowed)
			(footprints allowed)
		)
		(placement
			(enabled no)
			(sheetname "")
		)
		(fill
			(thermal_gap 0.5)
			(thermal_bridge_width 0.5)
			(island_removal_mode 0)
		)
		(polygon
			(pts
				(arc
					(start 376.823224 -224.389442)
					(mid 376.170444 -224.389442)
					(end 376.823224 -224.389442)
				)
			)
		)
	)
	(zone
		(layer "B.Cu")
		(hatch none 0.5)
		(connect_pads
			(clearance 0)
		)
		(min_thickness 0.25)
		(keepout
			(tracks allowed)
			(vias allowed)
			(pads allowed)
			(copperpour allowed)
			(footprints not_allowed)
		)
		(placement
			(enabled no)
			(sheetname "")
		)
		(fill
			(thermal_gap 0.5)
			(thermal_bridge_width 0.5)
			(island_removal_mode 0)
		)
		(polygon
			(pts
				(arc
					(start 371.562122 -294.276018)
					(mid 371.122746 -293.21527)
					(end 370.061998 -292.775894)
				)
				(arc
					(start 349.69196 -292.775894)
					(mid 348.631376 -293.21536)
					(end 348.19209 -294.276018)
				)
				(arc
					(start 348.19209 -295.566084)
					(mid 348.631392 -296.626652)
					(end 349.69196 -297.065954)
				)
				(arc
					(start 370.061998 -297.065954)
					(mid 371.12273 -296.626742)
					(end 371.562122 -295.566084)
				)
			)
		)
	)
	(zone
		(layer "B.Cu")
		(hatch none 0.5)
		(connect_pads
			(clearance 0)
		)
		(min_thickness 0.25)
		(keepout
			(tracks allowed)
			(vias allowed)
			(pads allowed)
			(copperpour allowed)
			(footprints not_allowed)
		)
		(placement
			(enabled no)
			(sheetname "")
		)
		(fill
			(thermal_gap 0.5)
			(thermal_bridge_width 0.5)
			(island_removal_mode 0)
		)
		(polygon
			(pts
				(arc
					(start 457.002896 -12.52982)
					(mid 452.61588 -19.507898)
					(end 453.526652 -27.69997)
				)
				(arc
					(start 453.526652 -27.69997)
					(mid 456.202713 -42.17388)
					(end 470.799922 -44.065952)
				)
				(arc
					(start 470.799922 -13.780008)
					(mid 470.507029 -13.072903)
					(end 469.799924 -12.78001)
				)
				(arc
					(start 458.20203 -12.78001)
					(mid 457.589557 -12.716771)
					(end 457.002896 -12.52982)
				)
			)
		)
	)
	(zone
		(layer "B.Cu")
		(hatch none 0.5)
		(connect_pads
			(clearance 0)
		)
		(min_thickness 0.25)
		(keepout
			(tracks not_allowed)
			(vias allowed)
			(pads allowed)
			(copperpour not_allowed)
			(footprints allowed)
		)
		(placement
			(enabled no)
			(sheetname "")
		)
		(fill
			(thermal_gap 0.5)
			(thermal_bridge_width 0.5)
			(island_removal_mode 0)
		)
		(polygon
			(pts
				(arc
					(start 73.054972 -421.089836)
					(mid 72.24522 -421.089836)
					(end 73.054972 -421.089836)
				)
			)
		)
	)
	(zone
		(layer "B.Cu")
		(hatch none 0.5)
		(connect_pads
			(clearance 0)
		)
		(min_thickness 0.25)
		(keepout
			(tracks not_allowed)
			(vias allowed)
			(pads allowed)
			(copperpour not_allowed)
			(footprints allowed)
		)
		(placement
			(enabled no)
			(sheetname "")
		)
		(fill
			(thermal_gap 0.5)
			(thermal_bridge_width 0.5)
			(island_removal_mode 0)
		)
		(polygon
			(pts
				(arc
					(start 102.283006 -47.049944)
					(mid 100.383086 -45.150024)
					(end 98.482912 -47.049944)
				)
				(arc
					(start 98.482912 -47.049944)
					(mid 100.383086 -48.950118)
					(end 102.283006 -47.049944)
				)
			)
		)
	)
	(zone
		(layer "B.Cu")
		(hatch none 0.5)
		(connect_pads
			(clearance 0)
		)
		(min_thickness 0.25)
		(keepout
			(tracks not_allowed)
			(vias allowed)
			(pads allowed)
			(copperpour not_allowed)
			(footprints allowed)
		)
		(placement
			(enabled no)
			(sheetname "")
		)
		(fill
			(thermal_gap 0.5)
			(thermal_bridge_width 0.5)
			(island_removal_mode 0)
		)
		(polygon
			(pts
				(arc
					(start 418.58692 -400.858228)
					(mid 417.88334 -400.858228)
					(end 418.58692 -400.858228)
				)
			)
		)
	)
	(zone
		(layer "B.Cu")
		(hatch none 0.5)
		(connect_pads
			(clearance 0)
		)
		(min_thickness 0.25)
		(keepout
			(tracks not_allowed)
			(vias allowed)
			(pads allowed)
			(copperpour not_allowed)
			(footprints allowed)
		)
		(placement
			(enabled no)
			(sheetname "")
		)
		(fill
			(thermal_gap 0.5)
			(thermal_bridge_width 0.5)
			(island_removal_mode 0)
		)
		(polygon
			(pts
				(arc
					(start 170.699938 -160.50006)
					(mid 167.900096 -157.700218)
					(end 165.1 -160.50006)
				)
				(arc
					(start 165.1 -160.50006)
					(mid 167.900096 -163.300156)
					(end 170.699938 -160.50006)
				)
			)
		)
	)
	(zone
		(layer "B.Cu")
		(hatch none 0.5)
		(connect_pads
			(clearance 0)
		)
		(min_thickness 0.25)
		(keepout
			(tracks not_allowed)
			(vias allowed)
			(pads allowed)
			(copperpour not_allowed)
			(footprints allowed)
		)
		(placement
			(enabled no)
			(sheetname "")
		)
		(fill
			(thermal_gap 0.5)
			(thermal_bridge_width 0.5)
			(island_removal_mode 0)
		)
		(polygon
			(pts
				(arc
					(start 73.054972 -424.689778)
					(mid 72.24522 -424.689778)
					(end 73.054972 -424.689778)
				)
			)
		)
	)
	(zone
		(layer "B.Cu")
		(hatch none 0.5)
		(connect_pads
			(clearance 0)
		)
		(min_thickness 0.25)
		(keepout
			(tracks allowed)
			(vias allowed)
			(pads allowed)
			(copperpour allowed)
			(footprints not_allowed)
		)
		(placement
			(enabled no)
			(sheetname "")
		)
		(fill
			(thermal_gap 0.5)
			(thermal_bridge_width 0.5)
			(island_removal_mode 0)
		)
		(polygon
			(pts
				(arc
					(start 356.125018 -431.360072)
					(mid 359.774998 -435.010052)
					(end 363.424978 -431.360072)
				)
				(arc
					(start 363.424978 -431.360072)
					(mid 359.774998 -427.710092)
					(end 356.125018 -431.360072)
				)
			)
		)
	)
	(zone
		(layer "B.Cu")
		(hatch none 0.5)
		(connect_pads
			(clearance 0)
		)
		(min_thickness 0.25)
		(keepout
			(tracks not_allowed)
			(vias allowed)
			(pads allowed)
			(copperpour not_allowed)
			(footprints allowed)
		)
		(placement
			(enabled no)
			(sheetname "")
		)
		(fill
			(thermal_gap 0.5)
			(thermal_bridge_width 0.5)
			(island_removal_mode 0)
		)
		(polygon
			(pts
				(arc
					(start 126.533402 -223.575626)
					(mid 125.880622 -223.575626)
					(end 126.533402 -223.575626)
				)
			)
		)
	)
	(zone
		(layer "B.Cu")
		(hatch none 0.5)
		(connect_pads
			(clearance 0)
		)
		(min_thickness 0.25)
		(keepout
			(tracks allowed)
			(vias allowed)
			(pads allowed)
			(copperpour allowed)
			(footprints not_allowed)
		)
		(placement
			(enabled no)
			(sheetname "")
		)
		(fill
			(thermal_gap 0.5)
			(thermal_bridge_width 0.5)
			(island_removal_mode 0)
		)
		(polygon
			(pts
				(arc
					(start 176.950116 -435.600094)
					(mid 179.750212 -438.40019)
					(end 182.550054 -435.600094)
				)
				(arc
					(start 182.550054 -435.600094)
					(mid 179.750212 -432.800252)
					(end 176.950116 -435.600094)
				)
			)
		)
	)
	(zone
		(layer "B.Cu")
		(hatch none 0.5)
		(connect_pads
			(clearance 0)
		)
		(min_thickness 0.25)
		(keepout
			(tracks not_allowed)
			(vias allowed)
			(pads allowed)
			(copperpour not_allowed)
			(footprints allowed)
		)
		(placement
			(enabled no)
			(sheetname "")
		)
		(fill
			(thermal_gap 0.5)
			(thermal_bridge_width 0.5)
			(island_removal_mode 0)
		)
		(polygon
			(pts
				(arc
					(start 345.33967 -225.203258)
					(mid 344.68689 -225.203258)
					(end 345.33967 -225.203258)
				)
			)
		)
	)
	(zone
		(layer "B.Cu")
		(hatch none 0.5)
		(connect_pads
			(clearance 0)
		)
		(min_thickness 0.25)
		(keepout
			(tracks not_allowed)
			(vias allowed)
			(pads allowed)
			(copperpour not_allowed)
			(footprints allowed)
		)
		(placement
			(enabled no)
			(sheetname "")
		)
		(fill
			(thermal_gap 0.5)
			(thermal_bridge_width 0.5)
			(island_removal_mode 0)
		)
		(polygon
			(pts
				(arc
					(start 126.063756 -224.389442)
					(mid 125.410976 -224.389442)
					(end 126.063756 -224.389442)
				)
			)
		)
	)
	(zone
		(layer "B.Cu")
		(hatch none 0.5)
		(connect_pads
			(clearance 0)
		)
		(min_thickness 0.25)
		(keepout
			(tracks not_allowed)
			(vias allowed)
			(pads allowed)
			(copperpour not_allowed)
			(footprints allowed)
		)
		(placement
			(enabled no)
			(sheetname "")
		)
		(fill
			(thermal_gap 0.5)
			(thermal_bridge_width 0.5)
			(island_removal_mode 0)
		)
		(polygon
			(pts
				(arc
					(start 233.849926 -352.49993)
					(mid 236.650022 -355.300026)
					(end 239.450118 -352.49993)
				)
				(arc
					(start 239.450118 -352.49993)
					(mid 236.650022 -349.699834)
					(end 233.849926 -352.49993)
				)
			)
		)
	)
	(zone
		(layer "B.Cu")
		(hatch none 0.5)
		(connect_pads
			(clearance 0)
		)
		(min_thickness 0.25)
		(keepout
			(tracks not_allowed)
			(vias allowed)
			(pads allowed)
			(copperpour not_allowed)
			(footprints allowed)
		)
		(placement
			(enabled no)
			(sheetname "")
		)
		(fill
			(thermal_gap 0.5)
			(thermal_bridge_width 0.5)
			(island_removal_mode 0)
		)
		(polygon
			(pts
				(arc
					(start 132.759704 -400.858228)
					(mid 132.056124 -400.858228)
					(end 132.759704 -400.858228)
				)
			)
		)
	)
	(zone
		(layer "B.Cu")
		(hatch none 0.5)
		(connect_pads
			(clearance 0)
		)
		(min_thickness 0.25)
		(keepout
			(tracks allowed)
			(vias allowed)
			(pads allowed)
			(copperpour allowed)
			(footprints not_allowed)
		)
		(placement
			(enabled no)
			(sheetname "")
		)
		(fill
			(thermal_gap 0.5)
			(thermal_bridge_width 0.5)
			(island_removal_mode 0)
		)
		(polygon
			(pts
				(arc
					(start 382.858772 -354.434902)
					(mid 384.458972 -356.035102)
					(end 386.058918 -354.434902)
				)
				(arc
					(start 386.058918 -354.434902)
					(mid 384.458972 -352.834956)
					(end 382.858772 -354.434902)
				)
			)
		)
	)
	(zone
		(layer "B.Cu")
		(hatch none 0.5)
		(connect_pads
			(clearance 0)
		)
		(min_thickness 0.25)
		(keepout
			(tracks not_allowed)
			(vias allowed)
			(pads allowed)
			(copperpour not_allowed)
			(footprints allowed)
		)
		(placement
			(enabled no)
			(sheetname "")
		)
		(fill
			(thermal_gap 0.5)
			(thermal_bridge_width 0.5)
			(island_removal_mode 0)
		)
		(polygon
			(pts
				(arc
					(start 55.321708 -400.858228)
					(mid 54.618128 -400.858228)
					(end 55.321708 -400.858228)
				)
			)
		)
	)
	(zone
		(layer "B.Cu")
		(hatch none 0.5)
		(connect_pads
			(clearance 0)
		)
		(min_thickness 0.25)
		(keepout
			(tracks not_allowed)
			(vias allowed)
			(pads allowed)
			(copperpour not_allowed)
			(footprints allowed)
		)
		(placement
			(enabled no)
			(sheetname "")
		)
		(fill
			(thermal_gap 0.5)
			(thermal_bridge_width 0.5)
			(island_removal_mode 0)
		)
		(polygon
			(pts
				(arc
					(start 106.97591 -407.111708)
					(mid 106.27233 -407.111708)
					(end 106.97591 -407.111708)
				)
			)
		)
	)
	(zone
		(layer "B.Cu")
		(hatch none 0.5)
		(connect_pads
			(clearance 0)
		)
		(min_thickness 0.25)
		(keepout
			(tracks allowed)
			(vias allowed)
			(pads allowed)
			(copperpour allowed)
			(footprints not_allowed)
		)
		(placement
			(enabled no)
			(sheetname "")
		)
		(fill
			(thermal_gap 0.5)
			(thermal_bridge_width 0.5)
			(island_removal_mode 0)
		)
		(polygon
			(pts
				(arc
					(start 190.581788 -70.417944)
					(mid 178.863288 -53.568068)
					(end 167.144446 -70.417944)
				)
				(arc
					(start 167.144446 -70.417944)
					(mid 178.863288 -87.268058)
					(end 190.581788 -70.417944)
				)
			)
		)
	)
	(zone
		(layer "B.Cu")
		(hatch none 0.5)
		(connect_pads
			(clearance 0)
		)
		(min_thickness 0.25)
		(keepout
			(tracks allowed)
			(vias allowed)
			(pads allowed)
			(copperpour allowed)
			(footprints allowed)
		)
		(placement
			(enabled no)
			(sheetname "")
		)
		(fill
			(thermal_gap 0.5)
			(thermal_bridge_width 0.5)
			(island_removal_mode 0)
		)
		(polygon
			(pts
				(xy 168.2623 -10.264648) (xy 168.2623 -8.600948) (xy 169.73042 -8.600948) (xy 169.73042 -10.264648)
			)
		)
	)
	(zone
		(layer "B.Cu")
		(hatch none 0.5)
		(connect_pads
			(clearance 0)
		)
		(min_thickness 0.25)
		(keepout
			(tracks not_allowed)
			(vias allowed)
			(pads allowed)
			(copperpour not_allowed)
			(footprints allowed)
		)
		(placement
			(enabled no)
			(sheetname "")
		)
		(fill
			(thermal_gap 0.5)
			(thermal_bridge_width 0.5)
			(island_removal_mode 0)
		)
		(polygon
			(pts
				(arc
					(start 145.876264 -400.858228)
					(mid 145.172684 -400.858228)
					(end 145.876264 -400.858228)
				)
			)
		)
	)
	(zone
		(layer "B.Cu")
		(hatch none 0.5)
		(connect_pads
			(clearance 0)
		)
		(min_thickness 0.25)
		(keepout
			(tracks not_allowed)
			(vias allowed)
			(pads allowed)
			(copperpour not_allowed)
			(footprints allowed)
		)
		(placement
			(enabled no)
			(sheetname "")
		)
		(fill
			(thermal_gap 0.5)
			(thermal_bridge_width 0.5)
			(island_removal_mode 0)
		)
		(polygon
			(pts
				(arc
					(start 90.351356 -224.389442)
					(mid 89.698576 -224.389442)
					(end 90.351356 -224.389442)
				)
			)
		)
	)
	(zone
		(layer "B.Cu")
		(hatch none 0.5)
		(connect_pads
			(clearance 0)
		)
		(min_thickness 0.25)
		(keepout
			(tracks not_allowed)
			(vias allowed)
			(pads allowed)
			(copperpour not_allowed)
			(footprints allowed)
		)
		(placement
			(enabled no)
			(sheetname "")
		)
		(fill
			(thermal_gap 0.5)
			(thermal_bridge_width 0.5)
			(island_removal_mode 0)
		)
		(polygon
			(pts
				(arc
					(start 77.914754 -353.525074)
					(mid 81.914746 -357.525066)
					(end 85.914738 -353.525074)
				)
				(arc
					(start 85.914738 -353.525074)
					(mid 81.914746 -349.525082)
					(end 77.914754 -353.525074)
				)
			)
		)
	)
	(zone
		(layer "B.Cu")
		(hatch none 0.5)
		(connect_pads
			(clearance 0)
		)
		(min_thickness 0.25)
		(keepout
			(tracks allowed)
			(vias allowed)
			(pads allowed)
			(copperpour allowed)
			(footprints allowed)
		)
		(placement
			(enabled no)
			(sheetname "")
		)
		(fill
			(thermal_gap 0.5)
			(thermal_bridge_width 0.5)
			(island_removal_mode 0)
		)
		(polygon
			(pts
				(xy 364.15472 -60.89396) (xy 364.15472 -59.68492) (xy 362.68152 -59.68492) (xy 362.68152 -60.89396)
			)
		)
	)
	(zone
		(layer "B.Cu")
		(hatch none 0.5)
		(connect_pads
			(clearance 0)
		)
		(min_thickness 0.25)
		(keepout
			(tracks allowed)
			(vias allowed)
			(pads allowed)
			(copperpour allowed)
			(footprints not_allowed)
		)
		(placement
			(enabled no)
			(sheetname "")
		)
		(fill
			(thermal_gap 0.5)
			(thermal_bridge_width 0.5)
			(island_removal_mode 0)
		)
		(polygon
			(pts
				(arc
					(start 224.14992 -272.50009)
					(mid 236.650022 -285.000192)
					(end 249.150124 -272.50009)
				)
				(arc
					(start 249.150124 -272.50009)
					(mid 236.650022 -259.999988)
					(end 224.14992 -272.50009)
				)
			)
		)
	)
	(zone
		(layer "B.Cu")
		(hatch none 0.5)
		(connect_pads
			(clearance 0)
		)
		(min_thickness 0.25)
		(keepout
			(tracks allowed)
			(vias allowed)
			(pads allowed)
			(copperpour allowed)
			(footprints not_allowed)
		)
		(placement
			(enabled no)
			(sheetname "")
		)
		(fill
			(thermal_gap 0.5)
			(thermal_bridge_width 0.5)
			(island_removal_mode 0)
		)
		(polygon
			(pts
				(arc
					(start 467.300056 -149.448012)
					(mid 465.115329 -148.546373)
					(end 462.799938 -148.072094)
				)
				(xy 462.799938 -96.19996) (xy 467.300056 -96.19996)
			)
		)
	)
	(zone
		(layer "B.Cu")
		(hatch none 0.5)
		(connect_pads
			(clearance 0)
		)
		(min_thickness 0.25)
		(keepout
			(tracks not_allowed)
			(vias allowed)
			(pads allowed)
			(copperpour not_allowed)
			(footprints allowed)
		)
		(placement
			(enabled no)
			(sheetname "")
		)
		(fill
			(thermal_gap 0.5)
			(thermal_bridge_width 0.5)
			(island_removal_mode 0)
		)
		(polygon
			(pts
				(arc
					(start 372.124224 -224.389442)
					(mid 371.471444 -224.389442)
					(end 372.124224 -224.389442)
				)
			)
		)
	)
	(zone
		(layer "B.Cu")
		(hatch none 0.5)
		(connect_pads
			(clearance 0)
		)
		(min_thickness 0.25)
		(keepout
			(tracks allowed)
			(vias allowed)
			(pads allowed)
			(copperpour allowed)
			(footprints not_allowed)
		)
		(placement
			(enabled no)
			(sheetname "")
		)
		(fill
			(thermal_gap 0.5)
			(thermal_bridge_width 0.5)
			(island_removal_mode 0)
		)
		(polygon
			(pts
				(xy 159.770064 -239.860074) (xy 214.769954 -239.860074) (xy 214.769954 -202.360022) (xy 159.770064 -202.360022)
			)
		)
	)
	(zone
		(layer "B.Cu")
		(hatch none 0.5)
		(connect_pads
			(clearance 0)
		)
		(min_thickness 0.25)
		(keepout
			(tracks not_allowed)
			(vias allowed)
			(pads allowed)
			(copperpour not_allowed)
			(footprints allowed)
		)
		(placement
			(enabled no)
			(sheetname "")
		)
		(fill
			(thermal_gap 0.5)
			(thermal_bridge_width 0.5)
			(island_removal_mode 0)
		)
		(polygon
			(pts
				(arc
					(start 417.72332 -400.858228)
					(mid 417.01974 -400.858228)
					(end 417.72332 -400.858228)
				)
			)
		)
	)
	(zone
		(layer "B.Cu")
		(hatch none 0.5)
		(connect_pads
			(clearance 0)
		)
		(min_thickness 0.25)
		(keepout
			(tracks allowed)
			(vias allowed)
			(pads allowed)
			(copperpour allowed)
			(footprints allowed)
		)
		(placement
			(enabled no)
			(sheetname "")
		)
		(fill
			(thermal_gap 0.5)
			(thermal_bridge_width 0.5)
			(island_removal_mode 0)
		)
		(polygon
			(pts
				(xy 297.6499 -16.13408) (xy 297.6499 -15.33906) (xy 299.22978 -15.33906) (xy 299.22978 -16.13408)
			)
		)
	)
	(zone
		(layer "B.Cu")
		(hatch none 0.5)
		(connect_pads
			(clearance 0)
		)
		(min_thickness 0.25)
		(keepout
			(tracks allowed)
			(vias allowed)
			(pads allowed)
			(copperpour allowed)
			(footprints not_allowed)
		)
		(placement
			(enabled no)
			(sheetname "")
		)
		(fill
			(thermal_gap 0.5)
			(thermal_bridge_width 0.5)
			(island_removal_mode 0)
		)
		(polygon
			(pts
				(arc
					(start 201.895456 -51.999896)
					(mid 204.645514 -54.749954)
					(end 207.395318 -51.999896)
				)
				(arc
					(start 207.395318 -51.999896)
					(mid 204.645514 -49.250092)
					(end 201.895456 -51.999896)
				)
			)
		)
	)
	(zone
		(layer "B.Cu")
		(hatch none 0.5)
		(connect_pads
			(clearance 0)
		)
		(min_thickness 0.25)
		(keepout
			(tracks not_allowed)
			(vias allowed)
			(pads allowed)
			(copperpour not_allowed)
			(footprints allowed)
		)
		(placement
			(enabled no)
			(sheetname "")
		)
		(fill
			(thermal_gap 0.5)
			(thermal_bridge_width 0.5)
			(island_removal_mode 0)
		)
		(polygon
			(pts
				(arc
					(start 129.352802 -225.203258)
					(mid 128.700022 -225.203258)
					(end 129.352802 -225.203258)
				)
			)
		)
	)
	(zone
		(layer "B.Cu")
		(hatch none 0.5)
		(connect_pads
			(clearance 0)
		)
		(min_thickness 0.25)
		(keepout
			(tracks not_allowed)
			(vias allowed)
			(pads allowed)
			(copperpour not_allowed)
			(footprints allowed)
		)
		(placement
			(enabled no)
			(sheetname "")
		)
		(fill
			(thermal_gap 0.5)
			(thermal_bridge_width 0.5)
			(island_removal_mode 0)
		)
		(polygon
			(pts
				(arc
					(start 133.112002 -225.203258)
					(mid 132.459222 -225.203258)
					(end 133.112002 -225.203258)
				)
			)
		)
	)
	(zone
		(layer "B.Cu")
		(hatch none 0.5)
		(connect_pads
			(clearance 0)
		)
		(min_thickness 0.25)
		(keepout
			(tracks allowed)
			(vias allowed)
			(pads allowed)
			(copperpour allowed)
			(footprints allowed)
		)
		(placement
			(enabled no)
			(sheetname "")
		)
		(fill
			(thermal_gap 0.5)
			(thermal_bridge_width 0.5)
			(island_removal_mode 0)
		)
		(polygon
			(pts
				(xy 36.03244 -130.658108) (xy 36.03244 -127.917448) (xy 38.7096 -127.917448) (xy 38.7096 -130.658108)
			)
		)
	)
	(zone
		(layer "B.Cu")
		(hatch none 0.5)
		(connect_pads
			(clearance 0)
		)
		(min_thickness 0.25)
		(keepout
			(tracks not_allowed)
			(vias allowed)
			(pads allowed)
			(copperpour not_allowed)
			(footprints allowed)
		)
		(placement
			(enabled no)
			(sheetname "")
		)
		(fill
			(thermal_gap 0.5)
			(thermal_bridge_width 0.5)
			(island_removal_mode 0)
		)
		(polygon
			(pts
				(arc
					(start 260.124956 -360.764074)
					(mid 258.12496 -358.764078)
					(end 256.124964 -360.764074)
				)
				(arc
					(start 256.124964 -360.764074)
					(mid 258.12496 -362.76407)
					(end 260.124956 -360.764074)
				)
			)
		)
	)
	(zone
		(layer "B.Cu")
		(hatch none 0.5)
		(connect_pads
			(clearance 0)
		)
		(min_thickness 0.25)
		(keepout
			(tracks allowed)
			(vias allowed)
			(pads allowed)
			(copperpour allowed)
			(footprints allowed)
		)
		(placement
			(enabled no)
			(sheetname "")
		)
		(fill
			(thermal_gap 0.5)
			(thermal_bridge_width 0.5)
			(island_removal_mode 0)
		)
		(polygon
			(pts
				(xy 23.47722 -193.840608) (xy 23.47722 -192.705228) (xy 25.85212 -192.705228) (xy 25.85212 -193.840608)
			)
		)
	)
	(zone
		(layer "B.Cu")
		(hatch none 0.5)
		(connect_pads
			(clearance 0)
		)
		(min_thickness 0.25)
		(keepout
			(tracks not_allowed)
			(vias allowed)
			(pads allowed)
			(copperpour not_allowed)
			(footprints allowed)
		)
		(placement
			(enabled no)
			(sheetname "")
		)
		(fill
			(thermal_gap 0.5)
			(thermal_bridge_width 0.5)
			(island_removal_mode 0)
		)
		(polygon
			(pts
				(arc
					(start 317.90005 -160.50006)
					(mid 322.90004 -165.50005)
					(end 327.90003 -160.50006)
				)
				(arc
					(start 327.90003 -160.50006)
					(mid 322.90004 -155.50007)
					(end 317.90005 -160.50006)
				)
			)
		)
	)
	(zone
		(layer "B.Cu")
		(hatch none 0.5)
		(connect_pads
			(clearance 0)
		)
		(min_thickness 0.25)
		(keepout
			(tracks not_allowed)
			(vias allowed)
			(pads allowed)
			(copperpour not_allowed)
			(footprints allowed)
		)
		(placement
			(enabled no)
			(sheetname "")
		)
		(fill
			(thermal_gap 0.5)
			(thermal_bridge_width 0.5)
			(island_removal_mode 0)
		)
		(polygon
			(pts
				(arc
					(start 446.299844 -435.59984)
					(mid 448.799966 -438.099962)
					(end 451.299834 -435.59984)
				)
				(arc
					(start 451.299834 -435.59984)
					(mid 448.799966 -433.099972)
					(end 446.299844 -435.59984)
				)
			)
		)
	)
	(zone
		(layer "B.Cu")
		(hatch none 0.5)
		(connect_pads
			(clearance 0)
		)
		(min_thickness 0.25)
		(keepout
			(tracks allowed)
			(vias allowed)
			(pads allowed)
			(copperpour allowed)
			(footprints allowed)
		)
		(placement
			(enabled no)
			(sheetname "")
		)
		(fill
			(thermal_gap 0.5)
			(thermal_bridge_width 0.5)
			(island_removal_mode 0)
		)
		(polygon
			(pts
				(xy 159.77616 -30.69082) (xy 159.77616 -29.49194) (xy 161.09442 -29.49194) (xy 161.09442 -30.69082)
			)
		)
	)
	(zone
		(layer "B.Cu")
		(hatch none 0.5)
		(connect_pads
			(clearance 0)
		)
		(min_thickness 0.25)
		(keepout
			(tracks allowed)
			(vias allowed)
			(pads allowed)
			(copperpour allowed)
			(footprints allowed)
		)
		(placement
			(enabled no)
			(sheetname "")
		)
		(fill
			(thermal_gap 0.5)
			(thermal_bridge_width 0.5)
			(island_removal_mode 0)
		)
		(polygon
			(pts
				(xy 335.44256 -13.29944) (xy 335.44256 -12.16406) (xy 332.59014 -12.16406) (xy 332.59014 -13.29944)
			)
		)
	)
	(zone
		(layer "B.Cu")
		(hatch none 0.5)
		(connect_pads
			(clearance 0)
		)
		(min_thickness 0.25)
		(keepout
			(tracks not_allowed)
			(vias allowed)
			(pads allowed)
			(copperpour not_allowed)
			(footprints allowed)
		)
		(placement
			(enabled no)
			(sheetname "")
		)
		(fill
			(thermal_gap 0.5)
			(thermal_bridge_width 0.5)
			(island_removal_mode 0)
		)
		(polygon
			(pts
				(arc
					(start 375.70156 -400.858228)
					(mid 374.99798 -400.858228)
					(end 375.70156 -400.858228)
				)
			)
		)
	)
	(zone
		(layer "B.Cu")
		(hatch none 0.5)
		(connect_pads
			(clearance 0)
		)
		(min_thickness 0.25)
		(keepout
			(tracks allowed)
			(vias allowed)
			(pads allowed)
			(copperpour allowed)
			(footprints allowed)
		)
		(placement
			(enabled no)
			(sheetname "")
		)
		(fill
			(thermal_gap 0.5)
			(thermal_bridge_width 0.5)
			(island_removal_mode 0)
		)
		(polygon
			(pts
				(xy 340.3981 -13.21054) (xy 340.3981 -12.17168) (xy 339.42274 -12.17168) (xy 339.42274 -13.21054)
			)
		)
	)
	(zone
		(layer "B.Cu")
		(hatch none 0.5)
		(connect_pads
			(clearance 0)
		)
		(min_thickness 0.25)
		(keepout
			(tracks allowed)
			(vias allowed)
			(pads allowed)
			(copperpour allowed)
			(footprints allowed)
		)
		(placement
			(enabled no)
			(sheetname "")
		)
		(fill
			(thermal_gap 0.5)
			(thermal_bridge_width 0.5)
			(island_removal_mode 0)
		)
		(polygon
			(pts
				(xy 140.27912 -29.825188) (xy 140.27912 -27.041348) (xy 141.1478 -27.041348) (xy 141.1478 -29.825188)
			)
		)
	)
	(zone
		(layer "B.Cu")
		(hatch none 0.5)
		(connect_pads
			(clearance 0)
		)
		(min_thickness 0.25)
		(keepout
			(tracks allowed)
			(vias allowed)
			(pads allowed)
			(copperpour allowed)
			(footprints allowed)
		)
		(placement
			(enabled no)
			(sheetname "")
		)
		(fill
			(thermal_gap 0.5)
			(thermal_bridge_width 0.5)
			(island_removal_mode 0)
		)
		(polygon
			(pts
				(xy 367.91646 -60.98286) (xy 367.91646 -59.46648) (xy 366.25784 -59.46648) (xy 366.25784 -60.98286)
			)
		)
	)
	(zone
		(layer "B.Cu")
		(hatch none 0.5)
		(connect_pads
			(clearance 0)
		)
		(min_thickness 0.25)
		(keepout
			(tracks not_allowed)
			(vias allowed)
			(pads allowed)
			(copperpour not_allowed)
			(footprints allowed)
		)
		(placement
			(enabled no)
			(sheetname "")
		)
		(fill
			(thermal_gap 0.5)
			(thermal_bridge_width 0.5)
			(island_removal_mode 0)
		)
		(polygon
			(pts
				(arc
					(start 148.939504 -400.858228)
					(mid 148.235924 -400.858228)
					(end 148.939504 -400.858228)
				)
			)
		)
	)
	(zone
		(layer "B.Cu")
		(hatch none 0.5)
		(connect_pads
			(clearance 0)
		)
		(min_thickness 0.25)
		(keepout
			(tracks not_allowed)
			(vias allowed)
			(pads allowed)
			(copperpour not_allowed)
			(footprints allowed)
		)
		(placement
			(enabled no)
			(sheetname "")
		)
		(fill
			(thermal_gap 0.5)
			(thermal_bridge_width 0.5)
			(island_removal_mode 0)
		)
		(polygon
			(pts
				(arc
					(start 7.53999 -347.700092)
					(mid 10.340086 -350.500188)
					(end 13.139928 -347.700092)
				)
				(arc
					(start 13.139928 -347.700092)
					(mid 10.340086 -344.90025)
					(end 7.53999 -347.700092)
				)
			)
		)
	)
	(zone
		(layer "B.Cu")
		(hatch none 0.5)
		(connect_pads
			(clearance 0)
		)
		(min_thickness 0.25)
		(keepout
			(tracks not_allowed)
			(vias allowed)
			(pads allowed)
			(copperpour not_allowed)
			(footprints allowed)
		)
		(placement
			(enabled no)
			(sheetname "")
		)
		(fill
			(thermal_gap 0.5)
			(thermal_bridge_width 0.5)
			(island_removal_mode 0)
		)
		(polygon
			(pts
				(arc
					(start 450.399912 -435.59984)
					(mid 448.799966 -433.999894)
					(end 447.20002 -435.59984)
				)
				(arc
					(start 447.20002 -435.59984)
					(mid 448.799966 -437.199786)
					(end 450.399912 -435.59984)
				)
			)
		)
	)
	(zone
		(layer "B.Cu")
		(hatch none 0.5)
		(connect_pads
			(clearance 0)
		)
		(min_thickness 0.25)
		(keepout
			(tracks not_allowed)
			(vias allowed)
			(pads allowed)
			(copperpour not_allowed)
			(footprints allowed)
		)
		(placement
			(enabled no)
			(sheetname "")
		)
		(fill
			(thermal_gap 0.5)
			(thermal_bridge_width 0.5)
			(island_removal_mode 0)
		)
		(polygon
			(pts
				(arc
					(start 347.689424 -224.389442)
					(mid 347.036644 -224.389442)
					(end 347.689424 -224.389442)
				)
			)
		)
	)
	(zone
		(layer "B.Cu")
		(hatch none 0.5)
		(connect_pads
			(clearance 0)
		)
		(min_thickness 0.25)
		(keepout
			(tracks not_allowed)
			(vias allowed)
			(pads allowed)
			(copperpour not_allowed)
			(footprints allowed)
		)
		(placement
			(enabled no)
			(sheetname "")
		)
		(fill
			(thermal_gap 0.5)
			(thermal_bridge_width 0.5)
			(island_removal_mode 0)
		)
		(polygon
			(pts
				(arc
					(start 349.569024 -224.389442)
					(mid 348.916244 -224.389442)
					(end 349.569024 -224.389442)
				)
			)
		)
	)
	(zone
		(layer "B.Cu")
		(hatch none 0.5)
		(connect_pads
			(clearance 0)
		)
		(min_thickness 0.25)
		(keepout
			(tracks not_allowed)
			(vias allowed)
			(pads allowed)
			(copperpour not_allowed)
			(footprints allowed)
		)
		(placement
			(enabled no)
			(sheetname "")
		)
		(fill
			(thermal_gap 0.5)
			(thermal_bridge_width 0.5)
			(island_removal_mode 0)
		)
		(polygon
			(pts
				(arc
					(start 145.012664 -400.858228)
					(mid 144.309084 -400.858228)
					(end 145.012664 -400.858228)
				)
			)
		)
	)
	(zone
		(layer "B.Cu")
		(hatch none 0.5)
		(connect_pads
			(clearance 0)
		)
		(min_thickness 0.25)
		(keepout
			(tracks allowed)
			(vias allowed)
			(pads allowed)
			(copperpour allowed)
			(footprints not_allowed)
		)
		(placement
			(enabled no)
			(sheetname "")
		)
		(fill
			(thermal_gap 0.5)
			(thermal_bridge_width 0.5)
			(island_removal_mode 0)
		)
		(polygon
			(pts
				(arc
					(start 174.749968 -435.600094)
					(mid 179.749958 -440.600084)
					(end 184.749948 -435.600094)
				)
				(arc
					(start 184.749948 -435.600094)
					(mid 179.749958 -430.600104)
					(end 174.749968 -435.600094)
				)
			)
		)
	)
	(zone
		(layer "B.Cu")
		(hatch none 0.5)
		(connect_pads
			(clearance 0)
		)
		(min_thickness 0.25)
		(keepout
			(tracks not_allowed)
			(vias allowed)
			(pads allowed)
			(copperpour not_allowed)
			(footprints allowed)
		)
		(placement
			(enabled no)
			(sheetname "")
		)
		(fill
			(thermal_gap 0.5)
			(thermal_bridge_width 0.5)
			(island_removal_mode 0)
		)
		(polygon
			(pts
				(arc
					(start 57.521348 -400.858228)
					(mid 56.817768 -400.858228)
					(end 57.521348 -400.858228)
				)
			)
		)
	)
	(zone
		(layer "B.Cu")
		(hatch none 0.5)
		(connect_pads
			(clearance 0)
		)
		(min_thickness 0.25)
		(keepout
			(tracks not_allowed)
			(vias allowed)
			(pads allowed)
			(copperpour not_allowed)
			(footprints allowed)
		)
		(placement
			(enabled no)
			(sheetname "")
		)
		(fill
			(thermal_gap 0.5)
			(thermal_bridge_width 0.5)
			(island_removal_mode 0)
		)
		(polygon
			(pts
				(arc
					(start 348.563438 -407.00452)
					(mid 347.859858 -407.00452)
					(end 348.563438 -407.00452)
				)
			)
		)
	)
	(zone
		(layer "B.Cu")
		(hatch none 0.5)
		(connect_pads
			(clearance 0)
		)
		(min_thickness 0.25)
		(keepout
			(tracks not_allowed)
			(vias allowed)
			(pads allowed)
			(copperpour not_allowed)
			(footprints allowed)
		)
		(placement
			(enabled no)
			(sheetname "")
		)
		(fill
			(thermal_gap 0.5)
			(thermal_bridge_width 0.5)
			(island_removal_mode 0)
		)
		(polygon
			(pts
				(arc
					(start 348.629224 -224.389442)
					(mid 347.976444 -224.389442)
					(end 348.629224 -224.389442)
				)
			)
		)
	)
	(zone
		(layer "B.Cu")
		(hatch none 0.5)
		(connect_pads
			(clearance 0)
		)
		(min_thickness 0.25)
		(keepout
			(tracks allowed)
			(vias allowed)
			(pads allowed)
			(copperpour allowed)
			(footprints allowed)
		)
		(placement
			(enabled no)
			(sheetname "")
		)
		(fill
			(thermal_gap 0.5)
			(thermal_bridge_width 0.5)
			(island_removal_mode 0)
		)
		(polygon
			(pts
				(xy 287.543494 -319.12179) (xy 287.543494 -318.762634) (xy 288.573972 -318.762634) (xy 288.573972 -319.12179)
			)
		)
	)
	(zone
		(layer "B.Cu")
		(hatch none 0.5)
		(connect_pads
			(clearance 0)
		)
		(min_thickness 0.25)
		(keepout
			(tracks allowed)
			(vias allowed)
			(pads allowed)
			(copperpour allowed)
			(footprints not_allowed)
		)
		(placement
			(enabled no)
			(sheetname "")
		)
		(fill
			(thermal_gap 0.5)
			(thermal_bridge_width 0.5)
			(island_removal_mode 0)
		)
		(polygon
			(pts
				(arc
					(start 290.394898 -153.766012)
					(mid 277.89505 -141.266164)
					(end 265.394948 -153.766012)
				)
				(arc
					(start 265.394948 -153.766012)
					(mid 277.89505 -166.266114)
					(end 290.394898 -153.766012)
				)
			)
		)
	)
	(zone
		(layer "B.Cu")
		(hatch none 0.5)
		(connect_pads
			(clearance 0)
		)
		(min_thickness 0.25)
		(keepout
			(tracks not_allowed)
			(vias allowed)
			(pads allowed)
			(copperpour not_allowed)
			(footprints allowed)
		)
		(placement
			(enabled no)
			(sheetname "")
		)
		(fill
			(thermal_gap 0.5)
			(thermal_bridge_width 0.5)
			(island_removal_mode 0)
		)
		(polygon
			(pts
				(arc
					(start 374.943624 -224.389442)
					(mid 374.290844 -224.389442)
					(end 374.943624 -224.389442)
				)
			)
		)
	)
	(zone
		(layer "B.Cu")
		(hatch none 0.5)
		(connect_pads
			(clearance 0)
		)
		(min_thickness 0.25)
		(keepout
			(tracks allowed)
			(vias allowed)
			(pads allowed)
			(copperpour allowed)
			(footprints allowed)
		)
		(placement
			(enabled no)
			(sheetname "")
		)
		(fill
			(thermal_gap 0.5)
			(thermal_bridge_width 0.5)
			(island_removal_mode 0)
		)
		(polygon
			(pts
				(xy 219.91066 -68.52158) (xy 219.91066 -67.19316) (xy 222.91802 -67.19316) (xy 222.91802 -68.52158)
			)
		)
	)
	(zone
		(layer "B.Cu")
		(hatch none 0.5)
		(connect_pads
			(clearance 0)
		)
		(min_thickness 0.25)
		(keepout
			(tracks not_allowed)
			(vias allowed)
			(pads allowed)
			(copperpour not_allowed)
			(footprints allowed)
		)
		(placement
			(enabled no)
			(sheetname "")
		)
		(fill
			(thermal_gap 0.5)
			(thermal_bridge_width 0.5)
			(island_removal_mode 0)
		)
		(polygon
			(pts
				(arc
					(start 406.33396 -400.858228)
					(mid 405.63038 -400.858228)
					(end 406.33396 -400.858228)
				)
			)
		)
	)
	(zone
		(layer "B.Cu")
		(hatch none 0.5)
		(connect_pads
			(clearance 0)
		)
		(min_thickness 0.25)
		(keepout
			(tracks allowed)
			(vias allowed)
			(pads allowed)
			(copperpour allowed)
			(footprints allowed)
		)
		(placement
			(enabled no)
			(sheetname "")
		)
		(fill
			(thermal_gap 0.5)
			(thermal_bridge_width 0.5)
			(island_removal_mode 0)
		)
		(polygon
			(pts
				(xy 226.10318 -36.82238) (xy 226.10318 -35.68446) (xy 227.16744 -35.68446) (xy 227.16744 -36.82238)
			)
		)
	)
	(zone
		(layer "B.Cu")
		(hatch none 0.5)
		(connect_pads
			(clearance 0)
		)
		(min_thickness 0.25)
		(keepout
			(tracks allowed)
			(vias allowed)
			(pads allowed)
			(copperpour allowed)
			(footprints allowed)
		)
		(placement
			(enabled no)
			(sheetname "")
		)
		(fill
			(thermal_gap 0.5)
			(thermal_bridge_width 0.5)
			(island_removal_mode 0)
		)
		(polygon
			(pts
				(xy 46.59122 -315.549788) (xy 46.59122 -314.927488) (xy 47.2186 -314.927488) (xy 47.2186 -315.549788)
			)
		)
	)
	(zone
		(layer "B.Cu")
		(hatch none 0.5)
		(connect_pads
			(clearance 0)
		)
		(min_thickness 0.25)
		(keepout
			(tracks not_allowed)
			(vias allowed)
			(pads allowed)
			(copperpour not_allowed)
			(footprints allowed)
		)
		(placement
			(enabled no)
			(sheetname "")
		)
		(fill
			(thermal_gap 0.5)
			(thermal_bridge_width 0.5)
			(island_removal_mode 0)
		)
		(polygon
			(pts
				(arc
					(start 82.027268 -400.858228)
					(mid 81.323688 -400.858228)
					(end 82.027268 -400.858228)
				)
			)
		)
	)
	(zone
		(layer "B.Cu")
		(hatch none 0.5)
		(connect_pads
			(clearance 0)
		)
		(min_thickness 0.25)
		(keepout
			(tracks allowed)
			(vias allowed)
			(pads allowed)
			(copperpour allowed)
			(footprints not_allowed)
		)
		(placement
			(enabled no)
			(sheetname "")
		)
		(fill
			(thermal_gap 0.5)
			(thermal_bridge_width 0.5)
			(island_removal_mode 0)
		)
		(polygon
			(pts
				(arc
					(start 212.645244 -51.999896)
					(mid 204.64526 -43.999912)
					(end 196.645276 -51.999896)
				)
				(arc
					(start 196.645276 -51.999896)
					(mid 204.64526 -59.99988)
					(end 212.645244 -51.999896)
				)
			)
		)
	)
	(zone
		(layer "B.Cu")
		(hatch none 0.5)
		(connect_pads
			(clearance 0)
		)
		(min_thickness 0.25)
		(keepout
			(tracks allowed)
			(vias allowed)
			(pads allowed)
			(copperpour allowed)
			(footprints not_allowed)
		)
		(placement
			(enabled no)
			(sheetname "")
		)
		(fill
			(thermal_gap 0.5)
			(thermal_bridge_width 0.5)
			(island_removal_mode 0)
		)
		(polygon
			(pts
				(arc
					(start 233.884978 -79.149956)
					(mid 235.89996 -84.949812)
					(end 237.914942 -79.149956)
				)
			)
		)
	)
	(zone
		(layer "B.Cu")
		(hatch none 0.5)
		(connect_pads
			(clearance 0)
		)
		(min_thickness 0.25)
		(keepout
			(tracks allowed)
			(vias allowed)
			(pads allowed)
			(copperpour allowed)
			(footprints allowed)
		)
		(placement
			(enabled no)
			(sheetname "")
		)
		(fill
			(thermal_gap 0.5)
			(thermal_bridge_width 0.5)
			(island_removal_mode 0)
		)
		(polygon
			(pts
				(xy 11.6459 -113.617248) (xy 11.6459 -110.993428) (xy 12.8524 -110.993428) (xy 12.8524 -113.617248)
			)
		)
	)
	(zone
		(layer "B.Cu")
		(hatch none 0.5)
		(connect_pads
			(clearance 0)
		)
		(min_thickness 0.25)
		(keepout
			(tracks not_allowed)
			(vias allowed)
			(pads allowed)
			(copperpour not_allowed)
			(footprints allowed)
		)
		(placement
			(enabled no)
			(sheetname "")
		)
		(fill
			(thermal_gap 0.5)
			(thermal_bridge_width 0.5)
			(island_removal_mode 0)
		)
		(polygon
			(pts
				(arc
					(start 97.700338 -435.600094)
					(mid 100.500434 -438.40019)
					(end 103.300276 -435.600094)
				)
				(arc
					(start 103.300276 -435.600094)
					(mid 100.500434 -432.800252)
					(end 97.700338 -435.600094)
				)
			)
		)
	)
	(zone
		(layer "B.Cu")
		(hatch none 0.5)
		(connect_pads
			(clearance 0)
		)
		(min_thickness 0.25)
		(keepout
			(tracks allowed)
			(vias allowed)
			(pads allowed)
			(copperpour allowed)
			(footprints not_allowed)
		)
		(placement
			(enabled no)
			(sheetname "")
		)
		(fill
			(thermal_gap 0.5)
			(thermal_bridge_width 0.5)
			(island_removal_mode 0)
		)
		(polygon
			(pts
				(arc
					(start 94.383098 -48.64989)
					(mid 95.983044 -47.049944)
					(end 94.383098 -45.449998)
				)
				(arc
					(start 92.782898 -45.449998)
					(mid 91.182952 -47.049944)
					(end 92.782898 -48.64989)
				)
			)
		)
	)
	(zone
		(layer "B.Cu")
		(hatch none 0.5)
		(connect_pads
			(clearance 0)
		)
		(min_thickness 0.25)
		(keepout
			(tracks allowed)
			(vias allowed)
			(pads allowed)
			(copperpour allowed)
			(footprints allowed)
		)
		(placement
			(enabled no)
			(sheetname "")
		)
		(fill
			(thermal_gap 0.5)
			(thermal_bridge_width 0.5)
			(island_removal_mode 0)
		)
		(polygon
			(pts
				(xy 295.66108 -154.574748) (xy 295.66108 -149.494748) (xy 297.89374 -149.494748) (xy 297.89374 -154.574748)
			)
		)
	)
	(zone
		(layer "B.Cu")
		(hatch none 0.5)
		(connect_pads
			(clearance 0)
		)
		(min_thickness 0.25)
		(keepout
			(tracks allowed)
			(vias allowed)
			(pads allowed)
			(copperpour allowed)
			(footprints not_allowed)
		)
		(placement
			(enabled no)
			(sheetname "")
		)
		(fill
			(thermal_gap 0.5)
			(thermal_bridge_width 0.5)
			(island_removal_mode 0)
		)
		(polygon
			(pts
				(arc
					(start 237.949994 -39.425118)
					(mid 239.94999 -41.425114)
					(end 241.949986 -39.425118)
				)
				(arc
					(start 241.949986 -39.425118)
					(mid 239.94999 -37.425122)
					(end 237.949994 -39.425118)
				)
			)
		)
	)
	(zone
		(layer "B.Cu")
		(hatch none 0.5)
		(connect_pads
			(clearance 0)
		)
		(min_thickness 0.25)
		(keepout
			(tracks not_allowed)
			(vias allowed)
			(pads allowed)
			(copperpour not_allowed)
			(footprints allowed)
		)
		(placement
			(enabled no)
			(sheetname "")
		)
		(fill
			(thermal_gap 0.5)
			(thermal_bridge_width 0.5)
			(island_removal_mode 0)
		)
		(polygon
			(pts
				(arc
					(start 154.202384 -400.858228)
					(mid 153.498804 -400.858228)
					(end 154.202384 -400.858228)
				)
			)
		)
	)
	(zone
		(layer "B.Cu")
		(hatch none 0.5)
		(connect_pads
			(clearance 0)
		)
		(min_thickness 0.25)
		(keepout
			(tracks not_allowed)
			(vias allowed)
			(pads allowed)
			(copperpour not_allowed)
			(footprints allowed)
		)
		(placement
			(enabled no)
			(sheetname "")
		)
		(fill
			(thermal_gap 0.5)
			(thermal_bridge_width 0.5)
			(island_removal_mode 0)
		)
		(polygon
			(pts
				(arc
					(start 63.647828 -400.858228)
					(mid 62.944248 -400.858228)
					(end 63.647828 -400.858228)
				)
			)
		)
	)
	(zone
		(layer "B.Cu")
		(hatch none 0.5)
		(connect_pads
			(clearance 0)
		)
		(min_thickness 0.25)
		(keepout
			(tracks allowed)
			(vias allowed)
			(pads allowed)
			(copperpour allowed)
			(footprints allowed)
		)
		(placement
			(enabled no)
			(sheetname "")
		)
		(fill
			(thermal_gap 0.5)
			(thermal_bridge_width 0.5)
			(island_removal_mode 0)
		)
		(polygon
			(pts
				(xy 177.80508 -50.45964) (xy 177.80508 -49.3014) (xy 178.80076 -49.3014) (xy 178.80076 -50.45964)
			)
		)
	)
	(zone
		(layer "B.Cu")
		(hatch none 0.5)
		(connect_pads
			(clearance 0)
		)
		(min_thickness 0.25)
		(keepout
			(tracks not_allowed)
			(vias allowed)
			(pads allowed)
			(copperpour not_allowed)
			(footprints allowed)
		)
		(placement
			(enabled no)
			(sheetname "")
		)
		(fill
			(thermal_gap 0.5)
			(thermal_bridge_width 0.5)
			(island_removal_mode 0)
		)
		(polygon
			(pts
				(arc
					(start 174.749968 -435.59984)
					(mid 179.749958 -440.59983)
					(end 184.749948 -435.59984)
				)
				(arc
					(start 184.749948 -435.59984)
					(mid 179.749958 -430.59985)
					(end 174.749968 -435.59984)
				)
			)
		)
	)
	(zone
		(layer "B.Cu")
		(hatch none 0.5)
		(connect_pads
			(clearance 0)
		)
		(min_thickness 0.25)
		(keepout
			(tracks allowed)
			(vias allowed)
			(pads allowed)
			(copperpour allowed)
			(footprints allowed)
		)
		(placement
			(enabled no)
			(sheetname "")
		)
		(fill
			(thermal_gap 0.5)
			(thermal_bridge_width 0.5)
			(island_removal_mode 0)
		)
		(polygon
			(pts
				(xy 180.75402 -55.01894) (xy 180.75402 -53.90388) (xy 183.07812 -53.90388) (xy 183.07812 -55.01894)
			)
		)
	)
	(zone
		(layer "B.Cu")
		(hatch none 0.5)
		(connect_pads
			(clearance 0)
		)
		(min_thickness 0.25)
		(keepout
			(tracks not_allowed)
			(vias allowed)
			(pads allowed)
			(copperpour not_allowed)
			(footprints allowed)
		)
		(placement
			(enabled no)
			(sheetname "")
		)
		(fill
			(thermal_gap 0.5)
			(thermal_bridge_width 0.5)
			(island_removal_mode 0)
		)
		(polygon
			(pts
				(arc
					(start 378.702824 -224.389442)
					(mid 378.050044 -224.389442)
					(end 378.702824 -224.389442)
				)
			)
		)
	)
	(zone
		(layer "B.Cu")
		(hatch none 0.5)
		(connect_pads
			(clearance 0)
		)
		(min_thickness 0.25)
		(keepout
			(tracks not_allowed)
			(vias allowed)
			(pads allowed)
			(copperpour not_allowed)
			(footprints allowed)
		)
		(placement
			(enabled no)
			(sheetname "")
		)
		(fill
			(thermal_gap 0.5)
			(thermal_bridge_width 0.5)
			(island_removal_mode 0)
		)
		(polygon
			(pts
				(arc
					(start 70.637908 -400.858228)
					(mid 69.934328 -400.858228)
					(end 70.637908 -400.858228)
				)
			)
		)
	)
	(zone
		(layer "B.Cu")
		(hatch none 0.5)
		(connect_pads
			(clearance 0)
		)
		(min_thickness 0.25)
		(keepout
			(tracks not_allowed)
			(vias allowed)
			(pads allowed)
			(copperpour not_allowed)
			(footprints allowed)
		)
		(placement
			(enabled no)
			(sheetname "")
		)
		(fill
			(thermal_gap 0.5)
			(thermal_bridge_width 0.5)
			(island_removal_mode 0)
		)
		(polygon
			(pts
				(arc
					(start 103.038402 -225.203258)
					(mid 102.385622 -225.203258)
					(end 103.038402 -225.203258)
				)
			)
		)
	)
	(zone
		(layer "B.Cu")
		(hatch none 0.5)
		(connect_pads
			(clearance 0)
		)
		(min_thickness 0.25)
		(keepout
			(tracks not_allowed)
			(vias allowed)
			(pads allowed)
			(copperpour not_allowed)
			(footprints allowed)
		)
		(placement
			(enabled no)
			(sheetname "")
		)
		(fill
			(thermal_gap 0.5)
			(thermal_bridge_width 0.5)
			(island_removal_mode 0)
		)
		(polygon
			(pts
				(arc
					(start 229.650036 -44.500038)
					(mid 228.650038 -43.50004)
					(end 227.65004 -44.500038)
				)
				(arc
					(start 227.65004 -44.500038)
					(mid 228.650038 -45.500036)
					(end 229.650036 -44.500038)
				)
			)
		)
	)
	(zone
		(layer "B.Cu")
		(hatch none 0.5)
		(connect_pads
			(clearance 0)
		)
		(min_thickness 0.25)
		(keepout
			(tracks not_allowed)
			(vias allowed)
			(pads allowed)
			(copperpour not_allowed)
			(footprints allowed)
		)
		(placement
			(enabled no)
			(sheetname "")
		)
		(fill
			(thermal_gap 0.5)
			(thermal_bridge_width 0.5)
			(island_removal_mode 0)
		)
		(polygon
			(pts
				(arc
					(start 337.174078 -407.00452)
					(mid 336.470498 -407.00452)
					(end 337.174078 -407.00452)
				)
			)
		)
	)
	(zone
		(layer "B.Cu")
		(hatch none 0.5)
		(connect_pads
			(clearance 0)
		)
		(min_thickness 0.25)
		(keepout
			(tracks allowed)
			(vias allowed)
			(pads allowed)
			(copperpour allowed)
			(footprints not_allowed)
		)
		(placement
			(enabled no)
			(sheetname "")
		)
		(fill
			(thermal_gap 0.5)
			(thermal_bridge_width 0.5)
			(island_removal_mode 0)
		)
		(polygon
			(pts
				(arc
					(start 198.399908 -22.29993)
					(mid 203.399898 -27.29992)
					(end 208.399888 -22.29993)
				)
				(arc
					(start 208.399888 -22.29993)
					(mid 203.399898 -17.29994)
					(end 198.399908 -22.29993)
				)
			)
		)
	)
	(zone
		(layer "B.Cu")
		(hatch none 0.5)
		(connect_pads
			(clearance 0)
		)
		(min_thickness 0.25)
		(keepout
			(tracks not_allowed)
			(vias allowed)
			(pads allowed)
			(copperpour not_allowed)
			(footprints allowed)
		)
		(placement
			(enabled no)
			(sheetname "")
		)
		(fill
			(thermal_gap 0.5)
			(thermal_bridge_width 0.5)
			(island_removal_mode 0)
		)
		(polygon
			(pts
				(arc
					(start 319.401952 -68.449952)
					(mid 314.398152 -68.449952)
					(end 319.401952 -68.449952)
				)
			)
		)
	)
	(zone
		(layer "B.Cu")
		(hatch none 0.5)
		(connect_pads
			(clearance 0)
		)
		(min_thickness 0.25)
		(keepout
			(tracks allowed)
			(vias allowed)
			(pads allowed)
			(copperpour allowed)
			(footprints allowed)
		)
		(placement
			(enabled no)
			(sheetname "")
		)
		(fill
			(thermal_gap 0.5)
			(thermal_bridge_width 0.5)
			(island_removal_mode 0)
		)
		(polygon
			(pts
				(xy 300.779688 -361.194096) (xy 302.118268 -361.194096) (xy 302.511968 -361.587796) (xy 302.511968 -363.802676)
				(xy 302.702468 -363.993176) (xy 306.248308 -363.993176) (xy 306.464208 -364.209076) (xy 306.464208 -366.370616)
				(xy 306.304188 -366.530636) (xy 300.868588 -366.530636) (xy 300.424088 -366.086136) (xy 300.424088 -361.549696)
			)
		)
	)
	(zone
		(layer "B.Cu")
		(hatch none 0.5)
		(connect_pads
			(clearance 0)
		)
		(min_thickness 0.25)
		(keepout
			(tracks allowed)
			(vias allowed)
			(pads allowed)
			(copperpour allowed)
			(footprints allowed)
		)
		(placement
			(enabled no)
			(sheetname "")
		)
		(fill
			(thermal_gap 0.5)
			(thermal_bridge_width 0.5)
			(island_removal_mode 0)
		)
		(polygon
			(pts
				(xy 93.545406 -333.45755) (xy 94.883986 -333.45755) (xy 95.277686 -333.85125) (xy 95.277686 -336.06613)
				(xy 95.468186 -336.25663) (xy 99.014026 -336.25663) (xy 99.229926 -336.47253) (xy 99.229926 -338.63407)
				(xy 99.069906 -338.79409) (xy 93.634306 -338.79409) (xy 93.189806 -338.34959) (xy 93.189806 -333.81315)
			)
		)
	)
	(zone
		(layer "B.Cu")
		(hatch none 0.5)
		(connect_pads
			(clearance 0)
		)
		(min_thickness 0.25)
		(keepout
			(tracks not_allowed)
			(vias allowed)
			(pads allowed)
			(copperpour not_allowed)
			(footprints allowed)
		)
		(placement
			(enabled no)
			(sheetname "")
		)
		(fill
			(thermal_gap 0.5)
			(thermal_bridge_width 0.5)
			(island_removal_mode 0)
		)
		(polygon
			(pts
				(arc
					(start 124.653802 -223.575626)
					(mid 124.001022 -223.575626)
					(end 124.653802 -223.575626)
				)
			)
		)
	)
	(zone
		(layer "B.Cu")
		(hatch none 0.5)
		(connect_pads
			(clearance 0)
		)
		(min_thickness 0.25)
		(keepout
			(tracks allowed)
			(vias allowed)
			(pads allowed)
			(copperpour allowed)
			(footprints not_allowed)
		)
		(placement
			(enabled no)
			(sheetname "")
		)
		(fill
			(thermal_gap 0.5)
			(thermal_bridge_width 0.5)
			(island_removal_mode 0)
		)
		(polygon
			(pts
				(arc
					(start 108.374942 -431.360072)
					(mid 112.024922 -435.010052)
					(end 115.674902 -431.360072)
				)
				(arc
					(start 115.674902 -431.360072)
					(mid 112.024922 -427.710092)
					(end 108.374942 -431.360072)
				)
			)
		)
	)
	(zone
		(layer "B.Cu")
		(hatch none 0.5)
		(connect_pads
			(clearance 0)
		)
		(min_thickness 0.25)
		(keepout
			(tracks not_allowed)
			(vias allowed)
			(pads allowed)
			(copperpour not_allowed)
			(footprints allowed)
		)
		(placement
			(enabled no)
			(sheetname "")
		)
		(fill
			(thermal_gap 0.5)
			(thermal_bridge_width 0.5)
			(island_removal_mode 0)
		)
		(polygon
			(pts
				(arc
					(start 132.518912 -354.434902)
					(mid 136.518904 -358.434894)
					(end 140.518896 -354.434902)
				)
				(arc
					(start 140.518896 -354.434902)
					(mid 136.518904 -350.43491)
					(end 132.518912 -354.434902)
				)
			)
		)
	)
	(zone
		(layer "B.Cu")
		(hatch none 0.5)
		(connect_pads
			(clearance 0)
		)
		(min_thickness 0.25)
		(keepout
			(tracks allowed)
			(vias allowed)
			(pads allowed)
			(copperpour allowed)
			(footprints not_allowed)
		)
		(placement
			(enabled no)
			(sheetname "")
		)
		(fill
			(thermal_gap 0.5)
			(thermal_bridge_width 0.5)
			(island_removal_mode 0)
		)
		(polygon
			(pts
				(arc
					(start 57.079642 -421.120062)
					(mid 45.036994 -405.27014)
					(end 32.994346 -421.120062)
				)
				(arc
					(start 32.994346 -421.120062)
					(mid 45.036994 -436.969984)
					(end 57.079642 -421.120062)
				)
			)
		)
	)
	(zone
		(layer "B.Cu")
		(hatch none 0.5)
		(connect_pads
			(clearance 0)
		)
		(min_thickness 0.25)
		(keepout
			(tracks not_allowed)
			(vias allowed)
			(pads allowed)
			(copperpour not_allowed)
			(footprints allowed)
		)
		(placement
			(enabled no)
			(sheetname "")
		)
		(fill
			(thermal_gap 0.5)
			(thermal_bridge_width 0.5)
			(island_removal_mode 0)
		)
		(polygon
			(pts
				(arc
					(start 92.099892 -22.29993)
					(mid 94.899988 -25.100026)
					(end 97.700084 -22.29993)
				)
				(arc
					(start 97.700084 -22.29993)
					(mid 94.899988 -19.499834)
					(end 92.099892 -22.29993)
				)
			)
		)
	)
	(zone
		(layer "B.Cu")
		(hatch none 0.5)
		(connect_pads
			(clearance 0)
		)
		(min_thickness 0.25)
		(keepout
			(tracks allowed)
			(vias allowed)
			(pads allowed)
			(copperpour allowed)
			(footprints not_allowed)
		)
		(placement
			(enabled no)
			(sheetname "")
		)
		(fill
			(thermal_gap 0.5)
			(thermal_bridge_width 0.5)
			(island_removal_mode 0)
		)
		(polygon
			(pts
				(arc
					(start 1.999996 -22.29993)
					(mid 6.999986 -27.29992)
					(end 11.999976 -22.29993)
				)
				(arc
					(start 11.999976 -22.29993)
					(mid 6.999986 -17.29994)
					(end 1.999996 -22.29993)
				)
			)
		)
	)
	(zone
		(layer "B.Cu")
		(hatch none 0.5)
		(connect_pads
			(clearance 0)
		)
		(min_thickness 0.25)
		(keepout
			(tracks not_allowed)
			(vias allowed)
			(pads allowed)
			(copperpour not_allowed)
			(footprints allowed)
		)
		(placement
			(enabled no)
			(sheetname "")
		)
		(fill
			(thermal_gap 0.5)
			(thermal_bridge_width 0.5)
			(island_removal_mode 0)
		)
		(polygon
			(pts
				(arc
					(start 93.170756 -224.389442)
					(mid 92.517976 -224.389442)
					(end 93.170756 -224.389442)
				)
			)
		)
	)
	(zone
		(layer "B.Cu")
		(hatch none 0.5)
		(connect_pads
			(clearance 0)
		)
		(min_thickness 0.25)
		(keepout
			(tracks not_allowed)
			(vias allowed)
			(pads allowed)
			(copperpour not_allowed)
			(footprints allowed)
		)
		(placement
			(enabled no)
			(sheetname "")
		)
		(fill
			(thermal_gap 0.5)
			(thermal_bridge_width 0.5)
			(island_removal_mode 0)
		)
		(polygon
			(pts
				(arc
					(start 343.930224 -224.389442)
					(mid 343.277444 -224.389442)
					(end 343.930224 -224.389442)
				)
			)
		)
	)
	(zone
		(layer "B.Cu")
		(hatch none 0.5)
		(connect_pads
			(clearance 0)
		)
		(min_thickness 0.25)
		(keepout
			(tracks not_allowed)
			(vias allowed)
			(pads allowed)
			(copperpour not_allowed)
			(footprints allowed)
		)
		(placement
			(enabled no)
			(sheetname "")
		)
		(fill
			(thermal_gap 0.5)
			(thermal_bridge_width 0.5)
			(island_removal_mode 0)
		)
		(polygon
			(pts
				(arc
					(start 350.03867 -223.575626)
					(mid 349.38589 -223.575626)
					(end 350.03867 -223.575626)
				)
			)
		)
	)
	(zone
		(layer "B.Cu")
		(hatch none 0.5)
		(connect_pads
			(clearance 0)
		)
		(min_thickness 0.25)
		(keepout
			(tracks not_allowed)
			(vias allowed)
			(pads allowed)
			(copperpour not_allowed)
			(footprints allowed)
		)
		(placement
			(enabled no)
			(sheetname "")
		)
		(fill
			(thermal_gap 0.5)
			(thermal_bridge_width 0.5)
			(island_removal_mode 0)
		)
		(polygon
			(pts
				(arc
					(start 386.058918 -354.434902)
					(mid 384.458972 -352.834956)
					(end 382.858772 -354.434902)
				)
				(arc
					(start 382.858772 -354.434902)
					(mid 384.458972 -356.035102)
					(end 386.058918 -354.434902)
				)
			)
		)
	)
	(zone
		(layer "B.Cu")
		(hatch none 0.5)
		(connect_pads
			(clearance 0)
		)
		(min_thickness 0.25)
		(keepout
			(tracks allowed)
			(vias allowed)
			(pads allowed)
			(copperpour allowed)
			(footprints not_allowed)
		)
		(placement
			(enabled no)
			(sheetname "")
		)
		(fill
			(thermal_gap 0.5)
			(thermal_bridge_width 0.5)
			(island_removal_mode 0)
		)
		(polygon
			(pts
				(arc
					(start 2.999994 -81.328514)
					(mid 2.771716 -80.180412)
					(end 2.121408 -79.207106)
				)
				(arc
					(start 1.29286 -78.378558)
					(mid 1.076156 -78.054238)
					(end 0.999998 -77.671676)
				)
				(arc
					(start 0.999998 -33.265872)
					(mid 2.097679 -33.798539)
					(end 3.242056 -34.221674)
				)
				(arc
					(start 3.242056 -34.221674)
					(mid 24.015289 -38.217469)
					(end 18.64487 -17.756378)
				)
				(arc
					(start 18.64487 -17.756378)
					(mid 16.568832 -14.257205)
					(end 13.479018 -11.610086)
				)
				(arc
					(start 13.479018 -11.610086)
					(mid 13.941996 -10.746613)
					(end 14.10208 -9.780016)
				)
				(xy 14.10208 -0.999998) (xy 80.701896 -0.999998)
				(arc
					(start 80.701896 -9.780016)
					(mid 81.580574 -11.901332)
					(end 83.70189 -12.78001)
				)
				(arc
					(start 86.79942 -12.78001)
					(mid 94.899988 -34.799853)
					(end 103.000556 -12.78001)
				)
				(arc
					(start 124.102114 -12.78001)
					(mid 126.22343 -11.901332)
					(end 127.102108 -9.780016)
				)
				(xy 127.102108 -6.279896) (xy 193.701924 -6.279896)
				(arc
					(start 193.701924 -9.780016)
					(mid 194.211853 -11.453198)
					(end 195.568316 -12.557506)
				)
				(arc
					(start 195.568316 -12.557506)
					(mid 203.225355 -34.798651)
					(end 211.500466 -12.78001)
				)
				(arc
					(start 221.30004 -12.78001)
					(mid 222.007145 -13.072903)
					(end 222.300038 -13.780008)
				)
				(arc
					(start 222.300038 -33.275016)
					(mid 223.178716 -35.396332)
					(end 225.300032 -36.27501)
				)
				(arc
					(start 232.596182 -36.27501)
					(mid 232.391979 -36.802741)
					(end 232.225596 -37.343588)
				)
				(arc
					(start 232.225596 -37.343588)
					(mid 221.352268 -47.777528)
					(end 236.374432 -46.581568)
				)
				(arc
					(start 236.374432 -46.581568)
					(mid 245.438573 -45.245329)
					(end 247.303798 -36.27501)
				)
				(arc
					(start 256.800096 -36.27501)
					(mid 258.896115 -35.421331)
					(end 259.799074 -33.346136)
				)
				(arc
					(start 259.799074 -33.346136)
					(mid 275.994424 -29.317318)
					(end 273.750532 -12.78001)
				)
				(arc
					(start 372.799356 -12.78001)
					(mid 381.670278 -34.776093)
					(end 387.76783 -11.855704)
				)
				(arc
					(start 387.76783 -11.855704)
					(mid 388.385566 -10.89851)
					(end 388.601966 -9.780016)
				)
				(xy 388.601966 -0.999998) (xy 455.202036 -0.999998)
				(arc
					(start 455.202036 -9.780016)
					(mid 455.692301 -11.423556)
					(end 457.002896 -12.52982)
				)
				(arc
					(start 457.002896 -12.52982)
					(mid 452.61588 -19.507898)
					(end 453.526652 -27.69997)
				)
				(arc
					(start 453.526652 -27.69997)
					(mid 456.202713 -42.17388)
					(end 470.799922 -44.065952)
				)
				(arc
					(start 470.799922 -77.671676)
					(mid 470.723821 -78.054261)
					(end 470.50706 -78.378558)
				)
				(arc
					(start 468.178642 -80.70723)
					(mid 467.528375 -81.680424)
					(end 467.300056 -82.828384)
				)
				(xy 467.300056 -87.199978)
				(arc
					(start 428.105062 -87.199978)
					(mid 437.423519 -81.360094)
					(end 438.521602 -70.417944)
				)
				(arc
					(start 438.521602 -70.417944)
					(mid 426.803102 -53.568068)
					(end 415.08426 -70.417944)
				)
				(arc
					(start 415.08426 -70.417944)
					(mid 416.182546 -81.360177)
					(end 425.501054 -87.199978)
				)
				(arc
					(start 294.236394 -87.199978)
					(mid 303.605081 -81.382457)
					(end 304.721768 -70.411086)
				)
				(arc
					(start 304.721768 -70.411086)
					(mid 293.003268 -53.56121)
					(end 281.284426 -70.411086)
				)
				(arc
					(start 281.284426 -70.411086)
					(mid 282.400851 -81.38241)
					(end 291.769546 -87.199978)
				)
				(arc
					(start 180.164994 -87.199978)
					(mid 189.483428 -81.360131)
					(end 190.581788 -70.417944)
				)
				(arc
					(start 190.581788 -70.417944)
					(mid 178.863288 -53.568068)
					(end 167.144446 -70.417944)
				)
				(arc
					(start 167.144446 -70.417944)
					(mid 168.242657 -81.360014)
					(end 177.560986 -87.199978)
				)
				(arc
					(start 46.296326 -87.199978)
					(mid 55.665013 -81.382457)
					(end 56.7817 -70.411086)
				)
				(arc
					(start 56.7817 -70.411086)
					(mid 45.0632 -53.56121)
					(end 33.344358 -70.411086)
				)
				(arc
					(start 33.344358 -70.411086)
					(mid 34.460783 -81.38241)
					(end 43.829478 -87.199978)
				)
				(xy 2.999994 -87.199978)
			)
		)
	)
	(zone
		(layer "B.Cu")
		(hatch none 0.5)
		(connect_pads
			(clearance 0)
		)
		(min_thickness 0.25)
		(keepout
			(tracks not_allowed)
			(vias allowed)
			(pads allowed)
			(copperpour not_allowed)
			(footprints allowed)
		)
		(placement
			(enabled no)
			(sheetname "")
		)
		(fill
			(thermal_gap 0.5)
			(thermal_bridge_width 0.5)
			(island_removal_mode 0)
		)
		(polygon
			(pts
				(arc
					(start 381.05207 -225.203258)
					(mid 380.39929 -225.203258)
					(end 381.05207 -225.203258)
				)
			)
		)
	)
	(zone
		(layer "B.Cu")
		(hatch none 0.5)
		(connect_pads
			(clearance 0)
		)
		(min_thickness 0.25)
		(keepout
			(tracks allowed)
			(vias allowed)
			(pads allowed)
			(copperpour allowed)
			(footprints allowed)
		)
		(placement
			(enabled no)
			(sheetname "")
		)
		(fill
			(thermal_gap 0.5)
			(thermal_bridge_width 0.5)
			(island_removal_mode 0)
		)
		(polygon
			(pts
				(xy 321.59956 -348.976188) (xy 321.59956 -347.327728) (xy 322.90004 -347.327728) (xy 322.90004 -348.976188)
			)
		)
	)
	(zone
		(layer "B.Cu")
		(hatch none 0.5)
		(connect_pads
			(clearance 0)
		)
		(min_thickness 0.25)
		(keepout
			(tracks allowed)
			(vias allowed)
			(pads allowed)
			(copperpour allowed)
			(footprints allowed)
		)
		(placement
			(enabled no)
			(sheetname "")
		)
		(fill
			(thermal_gap 0.5)
			(thermal_bridge_width 0.5)
			(island_removal_mode 0)
		)
		(polygon
			(pts
				(xy 97.65538 -338.366608) (xy 97.65538 -334.719168) (xy 92.88272 -334.719168) (xy 92.88272 -338.366608)
			)
		)
	)
	(zone
		(layer "B.Cu")
		(hatch none 0.5)
		(connect_pads
			(clearance 0)
		)
		(min_thickness 0.25)
		(keepout
			(tracks allowed)
			(vias allowed)
			(pads allowed)
			(copperpour allowed)
			(footprints allowed)
		)
		(placement
			(enabled no)
			(sheetname "")
		)
		(fill
			(thermal_gap 0.5)
			(thermal_bridge_width 0.5)
			(island_removal_mode 0)
		)
		(polygon
			(pts
				(xy 351.624646 -360.250232) (xy 351.624646 -358.751632) (xy 352.805746 -358.751632) (xy 352.805746 -360.250232)
			)
		)
	)
	(zone
		(layer "B.Cu")
		(hatch none 0.5)
		(connect_pads
			(clearance 0)
		)
		(min_thickness 0.25)
		(keepout
			(tracks not_allowed)
			(vias allowed)
			(pads allowed)
			(copperpour not_allowed)
			(footprints allowed)
		)
		(placement
			(enabled no)
			(sheetname "")
		)
		(fill
			(thermal_gap 0.5)
			(thermal_bridge_width 0.5)
			(island_removal_mode 0)
		)
		(polygon
			(pts
				(arc
					(start 164.255704 -400.858228)
					(mid 163.552124 -400.858228)
					(end 164.255704 -400.858228)
				)
			)
		)
	)
	(zone
		(layer "B.Cu")
		(hatch none 0.5)
		(connect_pads
			(clearance 0)
		)
		(min_thickness 0.25)
		(keepout
			(tracks not_allowed)
			(vias allowed)
			(pads allowed)
			(copperpour not_allowed)
			(footprints allowed)
		)
		(placement
			(enabled no)
			(sheetname "")
		)
		(fill
			(thermal_gap 0.5)
			(thermal_bridge_width 0.5)
			(island_removal_mode 0)
		)
		(polygon
			(pts
				(arc
					(start 177.749962 -435.59984)
					(mid 179.749958 -437.599836)
					(end 181.749954 -435.59984)
				)
				(arc
					(start 181.749954 -435.59984)
					(mid 179.749958 -433.599844)
					(end 177.749962 -435.59984)
				)
			)
		)
	)
	(zone
		(layer "B.Cu")
		(hatch none 0.5)
		(connect_pads
			(clearance 0)
		)
		(min_thickness 0.25)
		(keepout
			(tracks not_allowed)
			(vias allowed)
			(pads allowed)
			(copperpour not_allowed)
			(footprints allowed)
		)
		(placement
			(enabled no)
			(sheetname "")
		)
		(fill
			(thermal_gap 0.5)
			(thermal_bridge_width 0.5)
			(island_removal_mode 0)
		)
		(polygon
			(pts
				(xy 127.07874 -25.591008) (xy 127.07874 -25.354788) (xy 126.920498 -25.354788) (xy 126.920498 -25.74925)
				(xy 127.07874 -25.74925)
			)
		)
	)
	(zone
		(layer "B.Cu")
		(hatch none 0.5)
		(connect_pads
			(clearance 0)
		)
		(min_thickness 0.25)
		(keepout
			(tracks not_allowed)
			(vias allowed)
			(pads allowed)
			(copperpour not_allowed)
			(footprints allowed)
		)
		(placement
			(enabled no)
			(sheetname "")
		)
		(fill
			(thermal_gap 0.5)
			(thermal_bridge_width 0.5)
			(island_removal_mode 0)
		)
		(polygon
			(pts
				(arc
					(start 240.949988 -39.424864)
					(mid 239.94999 -38.424866)
					(end 238.949992 -39.424864)
				)
				(arc
					(start 238.949992 -39.424864)
					(mid 239.94999 -40.424862)
					(end 240.949988 -39.424864)
				)
			)
		)
	)
	(zone
		(layer "B.Cu")
		(hatch none 0.5)
		(connect_pads
			(clearance 0)
		)
		(min_thickness 0.25)
		(keepout
			(tracks not_allowed)
			(vias allowed)
			(pads allowed)
			(copperpour not_allowed)
			(footprints allowed)
		)
		(placement
			(enabled no)
			(sheetname "")
		)
		(fill
			(thermal_gap 0.5)
			(thermal_bridge_width 0.5)
			(island_removal_mode 0)
		)
		(polygon
			(pts
				(arc
					(start 359.49509 -46.802802)
					(mid 358.79151 -46.802802)
					(end 359.49509 -46.802802)
				)
			)
		)
	)
	(zone
		(layer "B.Cu")
		(hatch none 0.5)
		(connect_pads
			(clearance 0)
		)
		(min_thickness 0.25)
		(keepout
			(tracks not_allowed)
			(vias allowed)
			(pads allowed)
			(copperpour not_allowed)
			(footprints allowed)
		)
		(placement
			(enabled no)
			(sheetname "")
		)
		(fill
			(thermal_gap 0.5)
			(thermal_bridge_width 0.5)
			(island_removal_mode 0)
		)
		(polygon
			(pts
				(arc
					(start 463.460084 -347.699838)
					(mid 461.460088 -345.699842)
					(end 459.460092 -347.699838)
				)
				(arc
					(start 459.460092 -347.699838)
					(mid 461.460088 -349.699834)
					(end 463.460084 -347.699838)
				)
			)
		)
	)
	(zone
		(layer "B.Cu")
		(hatch none 0.5)
		(connect_pads
			(clearance 0)
		)
		(min_thickness 0.25)
		(keepout
			(tracks allowed)
			(vias allowed)
			(pads allowed)
			(copperpour allowed)
			(footprints not_allowed)
		)
		(placement
			(enabled no)
			(sheetname "")
		)
		(fill
			(thermal_gap 0.5)
			(thermal_bridge_width 0.5)
			(island_removal_mode 0)
		)
		(polygon
			(pts
				(arc
					(start 325.854822 -353.525074)
					(mid 329.854814 -357.525066)
					(end 333.854806 -353.525074)
				)
				(arc
					(start 333.854806 -353.525074)
					(mid 329.854814 -349.525082)
					(end 325.854822 -353.525074)
				)
			)
		)
	)
	(zone
		(layer "B.Cu")
		(hatch none 0.5)
		(connect_pads
			(clearance 0)
		)
		(min_thickness 0.25)
		(keepout
			(tracks allowed)
			(vias allowed)
			(pads allowed)
			(copperpour allowed)
			(footprints allowed)
		)
		(placement
			(enabled no)
			(sheetname "")
		)
		(fill
			(thermal_gap 0.5)
			(thermal_bridge_width 0.5)
			(island_removal_mode 0)
		)
		(polygon
			(pts
				(xy 140.0429 -32.26562) (xy 140.0429 -31.04642) (xy 142.3035 -31.04642) (xy 142.3035 -32.26562)
			)
		)
	)
	(zone
		(layer "B.Cu")
		(hatch none 0.5)
		(connect_pads
			(clearance 0)
		)
		(min_thickness 0.25)
		(keepout
			(tracks allowed)
			(vias allowed)
			(pads allowed)
			(copperpour allowed)
			(footprints not_allowed)
		)
		(placement
			(enabled no)
			(sheetname "")
		)
		(fill
			(thermal_gap 0.5)
			(thermal_bridge_width 0.5)
			(island_removal_mode 0)
		)
		(polygon
			(pts
				(arc
					(start 86.79942 -12.78001)
					(mid 94.899988 -34.799853)
					(end 103.000556 -12.78001)
				)
			)
		)
	)
	(zone
		(layer "B.Cu")
		(hatch none 0.5)
		(connect_pads
			(clearance 0)
		)
		(min_thickness 0.25)
		(keepout
			(tracks allowed)
			(vias allowed)
			(pads allowed)
			(copperpour allowed)
			(footprints allowed)
		)
		(placement
			(enabled no)
			(sheetname "")
		)
		(fill
			(thermal_gap 0.5)
			(thermal_bridge_width 0.5)
			(island_removal_mode 0)
		)
		(polygon
			(pts
				(xy 89.46388 -341.996268) (xy 89.46388 -338.252308) (xy 84.86902 -338.252308) (xy 84.86902 -341.996268)
			)
		)
	)
	(zone
		(layer "B.Cu")
		(hatch none 0.5)
		(connect_pads
			(clearance 0)
		)
		(min_thickness 0.25)
		(keepout
			(tracks allowed)
			(vias allowed)
			(pads allowed)
			(copperpour allowed)
			(footprints not_allowed)
		)
		(placement
			(enabled no)
			(sheetname "")
		)
		(fill
			(thermal_gap 0.5)
			(thermal_bridge_width 0.5)
			(island_removal_mode 0)
		)
		(polygon
			(pts
				(arc
					(start 21.954998 -153.766012)
					(mid 29.954982 -161.765996)
					(end 37.954966 -153.766012)
				)
				(arc
					(start 37.954966 -153.766012)
					(mid 29.954982 -145.766028)
					(end 21.954998 -153.766012)
				)
			)
		)
	)
	(zone
		(layer "B.Cu")
		(hatch none 0.5)
		(connect_pads
			(clearance 0)
		)
		(min_thickness 0.25)
		(keepout
			(tracks not_allowed)
			(vias allowed)
			(pads allowed)
			(copperpour not_allowed)
			(footprints allowed)
		)
		(placement
			(enabled no)
			(sheetname "")
		)
		(fill
			(thermal_gap 0.5)
			(thermal_bridge_width 0.5)
			(island_removal_mode 0)
		)
		(polygon
			(pts
				(arc
					(start 466.300058 -32.29991)
					(mid 464.75015 -30.750002)
					(end 463.199988 -32.29991)
				)
				(arc
					(start 463.199988 -33.90011)
					(mid 464.75015 -35.450272)
					(end 466.300058 -33.90011)
				)
			)
		)
	)
	(zone
		(layer "B.Cu")
		(hatch none 0.5)
		(connect_pads
			(clearance 0)
		)
		(min_thickness 0.25)
		(keepout
			(tracks allowed)
			(vias allowed)
			(pads allowed)
			(copperpour allowed)
			(footprints not_allowed)
		)
		(placement
			(enabled no)
			(sheetname "")
		)
		(fill
			(thermal_gap 0.5)
			(thermal_bridge_width 0.5)
			(island_removal_mode 0)
		)
		(polygon
			(pts
				(xy 401.376896 -240.191036) (xy 401.376896 -191.77) (xy 351.165922 -191.77) (xy 351.165922 -208.88706)
				(arc
					(start 370.771928 -208.88706)
					(mid 371.83275 -209.326257)
					(end 372.272052 -210.38693)
				)
				(arc
					(start 372.272052 -211.676996)
					(mid 371.832676 -212.737744)
					(end 370.771928 -213.17712)
				)
				(arc
					(start 348.98203 -213.17712)
					(mid 347.921282 -212.737744)
					(end 347.481906 -211.676996)
				)
				(arc
					(start 347.481906 -210.38693)
					(mid 347.921372 -209.326346)
					(end 348.98203 -208.88706)
				)
				(xy 351.0661 -208.88706) (xy 351.0661 -191.77) (xy 318.377062 -191.77) (xy 318.377062 -240.191036)
				(xy 350.80702 -240.191036)
				(arc
					(start 350.80702 -237.06455)
					(mid 351.246306 -236.003892)
					(end 352.30689 -235.564426)
				)
				(arc
					(start 354.896928 -235.564426)
					(mid 355.957676 -236.003802)
					(end 356.397052 -237.06455)
				)
				(arc
					(start 356.397052 -261.5946)
					(mid 355.95766 -262.655258)
					(end 354.896928 -263.09447)
				)
				(arc
					(start 352.30689 -263.09447)
					(mid 351.246322 -262.655168)
					(end 350.80702 -261.5946)
				)
				(xy 350.80702 -240.291112) (xy 318.377062 -240.291112) (xy 318.377062 -311.770014) (xy 351.0661 -311.770014)
				(xy 351.0661 -297.065954)
				(arc
					(start 349.69196 -297.065954)
					(mid 348.631392 -296.626652)
					(end 348.19209 -295.566084)
				)
				(arc
					(start 348.19209 -294.276018)
					(mid 348.631376 -293.21536)
					(end 349.69196 -292.775894)
				)
				(arc
					(start 370.061998 -292.775894)
					(mid 371.122746 -293.21527)
					(end 371.562122 -294.276018)
				)
				(arc
					(start 371.562122 -295.566084)
					(mid 371.12273 -296.626742)
					(end 370.061998 -297.065954)
				)
				(xy 351.165922 -297.065954) (xy 351.165922 -311.770014) (xy 401.376896 -311.770014) (xy 401.376896 -240.291112)
				(xy 368.946938 -240.291112)
				(arc
					(start 368.946938 -261.5946)
					(mid 368.507636 -262.655168)
					(end 367.447068 -263.09447)
				)
				(arc
					(start 364.85703 -263.09447)
					(mid 363.796462 -262.655168)
					(end 363.356906 -261.5946)
				)
				(arc
					(start 363.356906 -237.06455)
					(mid 363.796282 -236.003802)
					(end 364.85703 -235.564426)
				)
				(arc
					(start 367.447068 -235.564426)
					(mid 368.507816 -236.003802)
					(end 368.946938 -237.06455)
				)
				(xy 368.946938 -240.191036)
			)
		)
	)
	(zone
		(layer "B.Cu")
		(hatch none 0.5)
		(connect_pads
			(clearance 0)
		)
		(min_thickness 0.25)
		(keepout
			(tracks allowed)
			(vias allowed)
			(pads allowed)
			(copperpour allowed)
			(footprints not_allowed)
		)
		(placement
			(enabled no)
			(sheetname "")
		)
		(fill
			(thermal_gap 0.5)
			(thermal_bridge_width 0.5)
			(island_removal_mode 0)
		)
		(polygon
			(pts
				(arc
					(start 290.079938 -419.999922)
					(mid 287.98012 -417.900104)
					(end 285.880048 -419.999922)
				)
				(arc
					(start 285.880048 -419.999922)
					(mid 287.98012 -422.099994)
					(end 290.079938 -419.999922)
				)
			)
		)
	)
	(zone
		(layer "B.Cu")
		(hatch none 0.5)
		(connect_pads
			(clearance 0)
		)
		(min_thickness 0.25)
		(keepout
			(tracks allowed)
			(vias allowed)
			(pads allowed)
			(copperpour allowed)
			(footprints allowed)
		)
		(placement
			(enabled no)
			(sheetname "")
		)
		(fill
			(thermal_gap 0.5)
			(thermal_bridge_width 0.5)
			(island_removal_mode 0)
		)
		(polygon
			(pts
				(xy 310.46801 -361.194096) (xy 311.80659 -361.194096) (xy 312.20029 -361.587796) (xy 312.20029 -363.802676)
				(xy 312.39079 -363.993176) (xy 315.93663 -363.993176) (xy 316.15253 -364.209076) (xy 316.15253 -366.370616)
				(xy 315.99251 -366.530636) (xy 310.55691 -366.530636) (xy 310.11241 -366.086136) (xy 310.11241 -361.549696)
			)
		)
	)
	(zone
		(layer "B.Cu")
		(hatch none 0.5)
		(connect_pads
			(clearance 0)
		)
		(min_thickness 0.25)
		(keepout
			(tracks allowed)
			(vias allowed)
			(pads allowed)
			(copperpour allowed)
			(footprints not_allowed)
		)
		(placement
			(enabled no)
			(sheetname "")
		)
		(fill
			(thermal_gap 0.5)
			(thermal_bridge_width 0.5)
			(island_removal_mode 0)
		)
		(polygon
			(pts
				(arc
					(start 375.899934 -22.29993)
					(mid 380.899924 -27.29992)
					(end 385.899914 -22.29993)
				)
				(arc
					(start 385.899914 -22.29993)
					(mid 380.899924 -17.29994)
					(end 375.899934 -22.29993)
				)
			)
		)
	)
	(zone
		(layer "B.Cu")
		(hatch none 0.5)
		(connect_pads
			(clearance 0)
		)
		(min_thickness 0.25)
		(keepout
			(tracks not_allowed)
			(vias allowed)
			(pads allowed)
			(copperpour not_allowed)
			(footprints allowed)
		)
		(placement
			(enabled no)
			(sheetname "")
		)
		(fill
			(thermal_gap 0.5)
			(thermal_bridge_width 0.5)
			(island_removal_mode 0)
		)
		(polygon
			(pts
				(arc
					(start 288.550096 -435.600094)
					(mid 293.550086 -440.600084)
					(end 298.550076 -435.600094)
				)
				(arc
					(start 298.550076 -435.600094)
					(mid 293.550086 -430.600104)
					(end 288.550096 -435.600094)
				)
			)
		)
	)
	(zone
		(layer "B.Cu")
		(hatch none 0.5)
		(connect_pads
			(clearance 0)
		)
		(min_thickness 0.25)
		(keepout
			(tracks not_allowed)
			(vias allowed)
			(pads allowed)
			(copperpour not_allowed)
			(footprints allowed)
		)
		(placement
			(enabled no)
			(sheetname "")
		)
		(fill
			(thermal_gap 0.5)
			(thermal_bridge_width 0.5)
			(island_removal_mode 0)
		)
		(polygon
			(pts
				(arc
					(start 20.613116 -382.893824)
					(mid 19.909536 -382.893824)
					(end 20.613116 -382.893824)
				)
			)
		)
	)
	(zone
		(layer "B.Cu")
		(hatch none 0.5)
		(connect_pads
			(clearance 0)
		)
		(min_thickness 0.25)
		(keepout
			(tracks not_allowed)
			(vias allowed)
			(pads allowed)
			(copperpour not_allowed)
			(footprints allowed)
		)
		(placement
			(enabled no)
			(sheetname "")
		)
		(fill
			(thermal_gap 0.5)
			(thermal_bridge_width 0.5)
			(island_removal_mode 0)
		)
		(polygon
			(pts
				(arc
					(start 373.064024 -224.389442)
					(mid 372.411244 -224.389442)
					(end 373.064024 -224.389442)
				)
			)
		)
	)
	(zone
		(layer "B.Cu")
		(hatch none 0.5)
		(connect_pads
			(clearance 0)
		)
		(min_thickness 0.25)
		(keepout
			(tracks allowed)
			(vias allowed)
			(pads allowed)
			(copperpour allowed)
			(footprints not_allowed)
		)
		(placement
			(enabled no)
			(sheetname "")
		)
		(fill
			(thermal_gap 0.5)
			(thermal_bridge_width 0.5)
			(island_removal_mode 0)
		)
		(polygon
			(pts
				(arc
					(start 260.645402 -51.999896)
					(mid 268.645386 -59.99988)
					(end 276.64537 -51.999896)
				)
				(arc
					(start 276.64537 -51.999896)
					(mid 268.645386 -43.999912)
					(end 260.645402 -51.999896)
				)
			)
		)
	)
	(zone
		(layer "B.Cu")
		(hatch none 0.5)
		(connect_pads
			(clearance 0)
		)
		(min_thickness 0.25)
		(keepout
			(tracks not_allowed)
			(vias allowed)
			(pads allowed)
			(copperpour not_allowed)
			(footprints allowed)
		)
		(placement
			(enabled no)
			(sheetname "")
		)
		(fill
			(thermal_gap 0.5)
			(thermal_bridge_width 0.5)
			(island_removal_mode 0)
		)
		(polygon
			(pts
				(arc
					(start 390.15416 -400.858228)
					(mid 389.45058 -400.858228)
					(end 390.15416 -400.858228)
				)
			)
		)
	)
	(zone
		(layer "B.Cu")
		(hatch none 0.5)
		(connect_pads
			(clearance 0)
		)
		(min_thickness 0.25)
		(keepout
			(tracks not_allowed)
			(vias allowed)
			(pads allowed)
			(copperpour not_allowed)
			(footprints allowed)
		)
		(placement
			(enabled no)
			(sheetname "")
		)
		(fill
			(thermal_gap 0.5)
			(thermal_bridge_width 0.5)
			(island_removal_mode 0)
		)
		(polygon
			(pts
				(arc
					(start 69.05498 -421.089836)
					(mid 68.245228 -421.089836)
					(end 69.05498 -421.089836)
				)
			)
		)
	)
	(zone
		(layer "B.Cu")
		(hatch none 0.5)
		(connect_pads
			(clearance 0)
		)
		(min_thickness 0.25)
		(keepout
			(tracks not_allowed)
			(vias allowed)
			(pads allowed)
			(copperpour not_allowed)
			(footprints allowed)
		)
		(placement
			(enabled no)
			(sheetname "")
		)
		(fill
			(thermal_gap 0.5)
			(thermal_bridge_width 0.5)
			(island_removal_mode 0)
		)
		(polygon
			(pts
				(arc
					(start 369.304824 -224.389442)
					(mid 368.652044 -224.389442)
					(end 369.304824 -224.389442)
				)
			)
		)
	)
	(zone
		(layer "B.Cu")
		(hatch none 0.5)
		(connect_pads
			(clearance 0)
		)
		(min_thickness 0.25)
		(keepout
			(tracks not_allowed)
			(vias allowed)
			(pads allowed)
			(copperpour not_allowed)
			(footprints allowed)
		)
		(placement
			(enabled no)
			(sheetname "")
		)
		(fill
			(thermal_gap 0.5)
			(thermal_bridge_width 0.5)
			(island_removal_mode 0)
		)
		(polygon
			(pts
				(arc
					(start 381.522224 -224.389442)
					(mid 380.869444 -224.389442)
					(end 381.522224 -224.389442)
				)
			)
		)
	)
	(zone
		(layer "B.Cu")
		(hatch none 0.5)
		(connect_pads
			(clearance 0)
		)
		(min_thickness 0.25)
		(keepout
			(tracks allowed)
			(vias allowed)
			(pads allowed)
			(copperpour allowed)
			(footprints not_allowed)
		)
		(placement
			(enabled no)
			(sheetname "")
		)
		(fill
			(thermal_gap 0.5)
			(thermal_bridge_width 0.5)
			(island_removal_mode 0)
		)
		(polygon
			(pts
				(arc
					(start 368.498628 -435.600094)
					(mid 371.298724 -438.40019)
					(end 374.098566 -435.600094)
				)
				(arc
					(start 374.098566 -435.600094)
					(mid 371.298724 -432.800252)
					(end 368.498628 -435.600094)
				)
			)
		)
	)
	(zone
		(layer "B.Cu")
		(hatch none 0.5)
		(connect_pads
			(clearance 0)
		)
		(min_thickness 0.25)
		(keepout
			(tracks allowed)
			(vias allowed)
			(pads allowed)
			(copperpour allowed)
			(footprints not_allowed)
		)
		(placement
			(enabled no)
			(sheetname "")
		)
		(fill
			(thermal_gap 0.5)
			(thermal_bridge_width 0.5)
			(island_removal_mode 0)
		)
		(polygon
			(pts
				(arc
					(start 181.45506 -153.774902)
					(mid 193.955162 -166.275004)
					(end 206.45501 -153.774902)
				)
				(arc
					(start 206.45501 -153.774902)
					(mid 193.955162 -141.275054)
					(end 181.45506 -153.774902)
				)
			)
		)
	)
	(zone
		(layer "B.Cu")
		(hatch none 0.5)
		(connect_pads
			(clearance 0)
		)
		(min_thickness 0.25)
		(keepout
			(tracks not_allowed)
			(vias allowed)
			(pads allowed)
			(copperpour not_allowed)
			(footprints allowed)
		)
		(placement
			(enabled no)
			(sheetname "")
		)
		(fill
			(thermal_gap 0.5)
			(thermal_bridge_width 0.5)
			(island_removal_mode 0)
		)
		(polygon
			(pts
				(arc
					(start 262.850122 -22.29993)
					(mid 265.650218 -25.100026)
					(end 268.45006 -22.29993)
				)
				(arc
					(start 268.45006 -22.29993)
					(mid 265.650218 -19.500088)
					(end 262.850122 -22.29993)
				)
			)
		)
	)
	(zone
		(layer "B.Cu")
		(hatch none 0.5)
		(connect_pads
			(clearance 0)
		)
		(min_thickness 0.25)
		(keepout
			(tracks allowed)
			(vias allowed)
			(pads allowed)
			(copperpour allowed)
			(footprints allowed)
		)
		(placement
			(enabled no)
			(sheetname "")
		)
		(fill
			(thermal_gap 0.5)
			(thermal_bridge_width 0.5)
			(island_removal_mode 0)
		)
		(polygon
			(pts
				(xy 416.09264 -172.507148) (xy 416.09264 -174.879508) (xy 420.15918 -174.879508) (xy 420.15918 -170.310048)
				(xy 417.96208 -172.507148)
			)
		)
	)
	(zone
		(layer "B.Cu")
		(hatch none 0.5)
		(connect_pads
			(clearance 0)
		)
		(min_thickness 0.25)
		(keepout
			(tracks not_allowed)
			(vias allowed)
			(pads allowed)
			(copperpour not_allowed)
			(footprints allowed)
		)
		(placement
			(enabled no)
			(sheetname "")
		)
		(fill
			(thermal_gap 0.5)
			(thermal_bridge_width 0.5)
			(island_removal_mode 0)
		)
		(polygon
			(pts
				(arc
					(start 128.883156 -224.389442)
					(mid 128.230376 -224.389442)
					(end 128.883156 -224.389442)
				)
			)
		)
	)
	(zone
		(layer "B.Cu")
		(hatch none 0.5)
		(connect_pads
			(clearance 0)
		)
		(min_thickness 0.25)
		(keepout
			(tracks not_allowed)
			(vias allowed)
			(pads allowed)
			(copperpour not_allowed)
			(footprints allowed)
		)
		(placement
			(enabled no)
			(sheetname "")
		)
		(fill
			(thermal_gap 0.5)
			(thermal_bridge_width 0.5)
			(island_removal_mode 0)
		)
		(polygon
			(pts
				(arc
					(start 158.129224 -400.858228)
					(mid 157.425644 -400.858228)
					(end 158.129224 -400.858228)
				)
			)
		)
	)
	(zone
		(layer "B.Cu")
		(hatch none 0.5)
		(connect_pads
			(clearance 0)
		)
		(min_thickness 0.25)
		(keepout
			(tracks allowed)
			(vias allowed)
			(pads allowed)
			(copperpour allowed)
			(footprints not_allowed)
		)
		(placement
			(enabled no)
			(sheetname "")
		)
		(fill
			(thermal_gap 0.5)
			(thermal_bridge_width 0.5)
			(island_removal_mode 0)
		)
		(polygon
			(pts
				(arc
					(start 354.000054 -28.450032)
					(mid 356.899972 -31.34995)
					(end 359.79989 -28.450032)
				)
				(arc
					(start 359.79989 -28.450032)
					(mid 356.899972 -25.550114)
					(end 354.000054 -28.450032)
				)
			)
		)
	)
	(zone
		(layer "B.Cu")
		(hatch none 0.5)
		(connect_pads
			(clearance 0)
		)
		(min_thickness 0.25)
		(keepout
			(tracks not_allowed)
			(vias allowed)
			(pads allowed)
			(copperpour not_allowed)
			(footprints allowed)
		)
		(placement
			(enabled no)
			(sheetname "")
		)
		(fill
			(thermal_gap 0.5)
			(thermal_bridge_width 0.5)
			(island_removal_mode 0)
		)
		(polygon
			(pts
				(arc
					(start 103.978202 -223.575626)
					(mid 103.325422 -223.575626)
					(end 103.978202 -223.575626)
				)
			)
		)
	)
	(zone
		(layer "B.Cu")
		(hatch none 0.5)
		(connect_pads
			(clearance 0)
		)
		(min_thickness 0.25)
		(keepout
			(tracks allowed)
			(vias allowed)
			(pads allowed)
			(copperpour allowed)
			(footprints not_allowed)
		)
		(placement
			(enabled no)
			(sheetname "")
		)
		(fill
			(thermal_gap 0.5)
			(thermal_bridge_width 0.5)
			(island_removal_mode 0)
		)
		(polygon
			(pts
				(arc
					(start 458.659992 -347.700092)
					(mid 461.460088 -350.500188)
					(end 464.25993 -347.700092)
				)
				(arc
					(start 464.25993 -347.700092)
					(mid 461.460088 -344.90025)
					(end 458.659992 -347.700092)
				)
			)
		)
	)
	(zone
		(layer "B.Cu")
		(hatch none 0.5)
		(connect_pads
			(clearance 0)
		)
		(min_thickness 0.25)
		(keepout
			(tracks allowed)
			(vias allowed)
			(pads allowed)
			(copperpour allowed)
			(footprints not_allowed)
		)
		(placement
			(enabled no)
			(sheetname "")
		)
		(fill
			(thermal_gap 0.5)
			(thermal_bridge_width 0.5)
			(island_removal_mode 0)
		)
		(polygon
			(pts
				(arc
					(start 260.124956 -360.764074)
					(mid 258.12496 -358.764078)
					(end 256.124964 -360.764074)
				)
				(arc
					(start 256.124964 -360.764074)
					(mid 258.12496 -362.76407)
					(end 260.124956 -360.764074)
				)
			)
		)
	)
	(zone
		(layer "B.Cu")
		(hatch none 0.5)
		(connect_pads
			(clearance 0)
		)
		(min_thickness 0.25)
		(keepout
			(tracks allowed)
			(vias allowed)
			(pads allowed)
			(copperpour allowed)
			(footprints not_allowed)
		)
		(placement
			(enabled no)
			(sheetname "")
		)
		(fill
			(thermal_gap 0.5)
			(thermal_bridge_width 0.5)
			(island_removal_mode 0)
		)
		(polygon
			(pts
				(arc
					(start 354.896928 -263.09447)
					(mid 355.95766 -262.655258)
					(end 356.397052 -261.5946)
				)
				(arc
					(start 356.397052 -237.06455)
					(mid 355.957676 -236.003802)
					(end 354.896928 -235.564426)
				)
				(arc
					(start 352.30689 -235.564426)
					(mid 351.246306 -236.003892)
					(end 350.80702 -237.06455)
				)
				(arc
					(start 350.80702 -261.5946)
					(mid 351.246322 -262.655168)
					(end 352.30689 -263.09447)
				)
			)
		)
	)
	(zone
		(layer "B.Cu")
		(hatch none 0.5)
		(connect_pads
			(clearance 0)
		)
		(min_thickness 0.25)
		(keepout
			(tracks not_allowed)
			(vias allowed)
			(pads allowed)
			(copperpour not_allowed)
			(footprints allowed)
		)
		(placement
			(enabled no)
			(sheetname "")
		)
		(fill
			(thermal_gap 0.5)
			(thermal_bridge_width 0.5)
			(island_removal_mode 0)
		)
		(polygon
			(pts
				(arc
					(start 95.520002 -225.203258)
					(mid 94.867222 -225.203258)
					(end 95.520002 -225.203258)
				)
			)
		)
	)
	(zone
		(layer "B.Cu")
		(hatch none 0.5)
		(connect_pads
			(clearance 0)
		)
		(min_thickness 0.25)
		(keepout
			(tracks not_allowed)
			(vias allowed)
			(pads allowed)
			(copperpour not_allowed)
			(footprints allowed)
		)
		(placement
			(enabled no)
			(sheetname "")
		)
		(fill
			(thermal_gap 0.5)
			(thermal_bridge_width 0.5)
			(island_removal_mode 0)
		)
		(polygon
			(pts
				(arc
					(start 51.394868 -400.858228)
					(mid 50.691288 -400.858228)
					(end 51.394868 -400.858228)
				)
			)
		)
	)
	(zone
		(layer "B.Cu")
		(hatch none 0.5)
		(connect_pads
			(clearance 0)
		)
		(min_thickness 0.25)
		(keepout
			(tracks allowed)
			(vias allowed)
			(pads allowed)
			(copperpour allowed)
			(footprints allowed)
		)
		(placement
			(enabled no)
			(sheetname "")
		)
		(fill
			(thermal_gap 0.5)
			(thermal_bridge_width 0.5)
			(island_removal_mode 0)
		)
		(polygon
			(pts
				(xy 142.149576 -210.736434) (xy 142.1511 -292.321234) (xy 81.4197 -292.322504) (xy 81.41843 -218.872308)
				(xy 85.826346 -214.464392) (xy 85.826346 -213.09457) (xy 88.183466 -210.73745)
			)
		)
	)
	(zone
		(layer "B.Cu")
		(hatch none 0.5)
		(connect_pads
			(clearance 0)
		)
		(min_thickness 0.25)
		(keepout
			(tracks not_allowed)
			(vias allowed)
			(pads allowed)
			(copperpour not_allowed)
			(footprints allowed)
		)
		(placement
			(enabled no)
			(sheetname "")
		)
		(fill
			(thermal_gap 0.5)
			(thermal_bridge_width 0.5)
			(island_removal_mode 0)
		)
		(polygon
			(pts
				(xy 127.07874 -27.036268) (xy 127.07874 -26.800048) (xy 126.920498 -26.800048) (xy 126.920498 -27.19451)
				(xy 127.07874 -27.19451)
			)
		)
	)
	(zone
		(layer "B.Cu")
		(hatch none 0.5)
		(connect_pads
			(clearance 0)
		)
		(min_thickness 0.25)
		(keepout
			(tracks not_allowed)
			(vias allowed)
			(pads allowed)
			(copperpour not_allowed)
			(footprints allowed)
		)
		(placement
			(enabled no)
			(sheetname "")
		)
		(fill
			(thermal_gap 0.5)
			(thermal_bridge_width 0.5)
			(island_removal_mode 0)
		)
		(polygon
			(pts
				(arc
					(start 317.931038 -407.00452)
					(mid 317.227458 -407.00452)
					(end 317.931038 -407.00452)
				)
			)
		)
	)
	(zone
		(layer "B.Cu")
		(hatch none 0.5)
		(connect_pads
			(clearance 0)
		)
		(min_thickness 0.25)
		(keepout
			(tracks allowed)
			(vias allowed)
			(pads allowed)
			(copperpour allowed)
			(footprints allowed)
		)
		(placement
			(enabled no)
			(sheetname "")
		)
		(fill
			(thermal_gap 0.5)
			(thermal_bridge_width 0.5)
			(island_removal_mode 0)
		)
		(polygon
			(pts
				(xy 33.85566 -193.703448) (xy 33.85566 -192.377568) (xy 35.78352 -192.377568) (xy 35.78352 -193.703448)
			)
		)
	)
	(zone
		(layer "B.Cu")
		(hatch none 0.5)
		(connect_pads
			(clearance 0)
		)
		(min_thickness 0.25)
		(keepout
			(tracks not_allowed)
			(vias allowed)
			(pads allowed)
			(copperpour not_allowed)
			(footprints allowed)
		)
		(placement
			(enabled no)
			(sheetname "")
		)
		(fill
			(thermal_gap 0.5)
			(thermal_bridge_width 0.5)
			(island_removal_mode 0)
		)
		(polygon
			(pts
				(arc
					(start 346.363798 -407.00452)
					(mid 345.660218 -407.00452)
					(end 346.363798 -407.00452)
				)
			)
		)
	)
	(zone
		(layer "B.Cu")
		(hatch none 0.5)
		(connect_pads
			(clearance 0)
		)
		(min_thickness 0.25)
		(keepout
			(tracks allowed)
			(vias allowed)
			(pads allowed)
			(copperpour allowed)
			(footprints allowed)
		)
		(placement
			(enabled no)
			(sheetname "")
		)
		(fill
			(thermal_gap 0.5)
			(thermal_bridge_width 0.5)
			(island_removal_mode 0)
		)
		(polygon
			(pts
				(xy 81.0006 -347.734128) (xy 81.0006 -343.532968) (xy 76.61402 -343.532968) (xy 76.61402 -347.734128)
			)
		)
	)
	(zone
		(layer "B.Cu")
		(hatch none 0.5)
		(connect_pads
			(clearance 0)
		)
		(min_thickness 0.25)
		(keepout
			(tracks allowed)
			(vias allowed)
			(pads allowed)
			(copperpour allowed)
			(footprints not_allowed)
		)
		(placement
			(enabled no)
			(sheetname "")
		)
		(fill
			(thermal_gap 0.5)
			(thermal_bridge_width 0.5)
			(island_removal_mode 0)
		)
		(polygon
			(pts
				(xy 312.040016 -239.860074) (xy 312.040016 -202.360022) (xy 257.040126 -202.360022) (xy 257.040126 -239.860074)
			)
		)
	)
	(zone
		(layer "B.Cu")
		(hatch none 0.5)
		(connect_pads
			(clearance 0)
		)
		(min_thickness 0.25)
		(keepout
			(tracks allowed)
			(vias allowed)
			(pads allowed)
			(copperpour allowed)
			(footprints allowed)
		)
		(placement
			(enabled no)
			(sheetname "")
		)
		(fill
			(thermal_gap 0.5)
			(thermal_bridge_width 0.5)
			(island_removal_mode 0)
		)
		(polygon
			(pts
				(xy 31.200852 -165.698932) (xy 31.200852 -163.227512) (xy 32.450532 -163.227512) (xy 32.450532 -164.041328)
				(xy 33.87598 -165.466776) (xy 33.87598 -166.494968) (xy 33.27908 -167.091868) (xy 33.09112 -167.091868)
				(xy 31.698184 -165.698932)
			)
		)
	)
	(zone
		(layer "B.Cu")
		(hatch none 0.5)
		(connect_pads
			(clearance 0)
		)
		(min_thickness 0.25)
		(keepout
			(tracks not_allowed)
			(vias allowed)
			(pads allowed)
			(copperpour not_allowed)
			(footprints allowed)
		)
		(placement
			(enabled no)
			(sheetname "")
		)
		(fill
			(thermal_gap 0.5)
			(thermal_bridge_width 0.5)
			(island_removal_mode 0)
		)
		(polygon
			(pts
				(arc
					(start 91.291156 -224.389442)
					(mid 90.638376 -224.389442)
					(end 91.291156 -224.389442)
				)
			)
		)
	)
	(zone
		(layer "B.Cu")
		(hatch none 0.5)
		(connect_pads
			(clearance 0)
		)
		(min_thickness 0.25)
		(keepout
			(tracks not_allowed)
			(vias allowed)
			(pads allowed)
			(copperpour not_allowed)
			(footprints allowed)
		)
		(placement
			(enabled no)
			(sheetname "")
		)
		(fill
			(thermal_gap 0.5)
			(thermal_bridge_width 0.5)
			(island_removal_mode 0)
		)
		(polygon
			(pts
				(arc
					(start 372.59387 -223.575626)
					(mid 371.94109 -223.575626)
					(end 372.59387 -223.575626)
				)
			)
		)
	)
	(zone
		(layer "B.Cu")
		(hatch none 0.5)
		(connect_pads
			(clearance 0)
		)
		(min_thickness 0.25)
		(keepout
			(tracks allowed)
			(vias allowed)
			(pads allowed)
			(copperpour allowed)
			(footprints not_allowed)
		)
		(placement
			(enabled no)
			(sheetname "")
		)
		(fill
			(thermal_gap 0.5)
			(thermal_bridge_width 0.5)
			(island_removal_mode 0)
		)
		(polygon
			(pts
				(arc
					(start 233.849926 -192.499996)
					(mid 236.650022 -195.300092)
					(end 239.450118 -192.499996)
				)
				(arc
					(start 239.450118 -192.499996)
					(mid 236.650022 -189.6999)
					(end 233.849926 -192.499996)
				)
			)
		)
	)
	(zone
		(layer "B.Cu")
		(hatch none 0.5)
		(connect_pads
			(clearance 0)
		)
		(min_thickness 0.25)
		(keepout
			(tracks allowed)
			(vias allowed)
			(pads allowed)
			(copperpour allowed)
			(footprints not_allowed)
		)
		(placement
			(enabled no)
			(sheetname "")
		)
		(fill
			(thermal_gap 0.5)
			(thermal_bridge_width 0.5)
			(island_removal_mode 0)
		)
		(polygon
			(pts
				(arc
					(start 113.609882 -431.360072)
					(mid 112.024922 -429.775112)
					(end 110.439962 -431.360072)
				)
				(arc
					(start 110.439962 -431.360072)
					(mid 112.024922 -432.945032)
					(end 113.609882 -431.360072)
				)
			)
		)
	)
	(zone
		(layer "B.Cu")
		(hatch none 0.5)
		(connect_pads
			(clearance 0)
		)
		(min_thickness 0.25)
		(keepout
			(tracks not_allowed)
			(vias allowed)
			(pads allowed)
			(copperpour not_allowed)
			(footprints allowed)
		)
		(placement
			(enabled no)
			(sheetname "")
		)
		(fill
			(thermal_gap 0.5)
			(thermal_bridge_width 0.5)
			(island_removal_mode 0)
		)
		(polygon
			(pts
				(arc
					(start 73.054972 -423.489882)
					(mid 72.24522 -423.489882)
					(end 73.054972 -423.489882)
				)
			)
		)
	)
	(zone
		(layer "B.Cu")
		(hatch none 0.5)
		(connect_pads
			(clearance 0)
		)
		(min_thickness 0.25)
		(keepout
			(tracks not_allowed)
			(vias allowed)
			(pads allowed)
			(copperpour not_allowed)
			(footprints allowed)
		)
		(placement
			(enabled no)
			(sheetname "")
		)
		(fill
			(thermal_gap 0.5)
			(thermal_bridge_width 0.5)
			(island_removal_mode 0)
		)
		(polygon
			(pts
				(arc
					(start 315.731398 -407.00452)
					(mid 315.027818 -407.00452)
					(end 315.731398 -407.00452)
				)
			)
		)
	)
	(zone
		(layer "B.Cu")
		(hatch none 0.5)
		(connect_pads
			(clearance 0)
		)
		(min_thickness 0.25)
		(keepout
			(tracks allowed)
			(vias allowed)
			(pads allowed)
			(copperpour allowed)
			(footprints allowed)
		)
		(placement
			(enabled no)
			(sheetname "")
		)
		(fill
			(thermal_gap 0.5)
			(thermal_bridge_width 0.5)
			(island_removal_mode 0)
		)
		(polygon
			(pts
				(xy 164.62248 -195.039488) (xy 164.62248 -194.567048) (xy 165.49878 -194.567048) (xy 165.49878 -195.039488)
			)
		)
	)
	(zone
		(layer "B.Cu")
		(hatch none 0.5)
		(connect_pads
			(clearance 0)
		)
		(min_thickness 0.25)
		(keepout
			(tracks not_allowed)
			(vias allowed)
			(pads allowed)
			(copperpour not_allowed)
			(footprints allowed)
		)
		(placement
			(enabled no)
			(sheetname "")
		)
		(fill
			(thermal_gap 0.5)
			(thermal_bridge_width 0.5)
			(island_removal_mode 0)
		)
		(polygon
			(pts
				(arc
					(start 309.604918 -407.00452)
					(mid 308.901338 -407.00452)
					(end 309.604918 -407.00452)
				)
			)
		)
	)
	(zone
		(layer "B.Cu")
		(hatch none 0.5)
		(connect_pads
			(clearance 0)
		)
		(min_thickness 0.25)
		(keepout
			(tracks allowed)
			(vias allowed)
			(pads allowed)
			(copperpour allowed)
			(footprints allowed)
		)
		(placement
			(enabled no)
			(sheetname "")
		)
		(fill
			(thermal_gap 0.5)
			(thermal_bridge_width 0.5)
			(island_removal_mode 0)
		)
		(polygon
			(pts
				(xy 290.2077 -154.559508) (xy 290.2077 -149.601428) (xy 292.01618 -149.601428) (xy 292.01618 -154.559508)
			)
		)
	)
	(zone
		(layer "B.Cu")
		(hatch none 0.5)
		(connect_pads
			(clearance 0)
		)
		(min_thickness 0.25)
		(keepout
			(tracks not_allowed)
			(vias allowed)
			(pads allowed)
			(copperpour not_allowed)
			(footprints allowed)
		)
		(placement
			(enabled no)
			(sheetname "")
		)
		(fill
			(thermal_gap 0.5)
			(thermal_bridge_width 0.5)
			(island_removal_mode 0)
		)
		(polygon
			(pts
				(arc
					(start 456.460098 -160.50006)
					(mid 461.460088 -165.50005)
					(end 466.460078 -160.50006)
				)
				(arc
					(start 466.460078 -160.50006)
					(mid 461.460088 -155.50007)
					(end 456.460098 -160.50006)
				)
			)
		)
		(polygon
			(pts
				(arc
					(start 459.460092 -160.50006)
					(mid 461.460088 -162.500056)
					(end 463.460084 -160.50006)
				)
				(arc
					(start 463.460084 -160.50006)
					(mid 461.460088 -158.500064)
					(end 459.460092 -160.50006)
				)
			)
		)
	)
	(zone
		(layer "B.Cu")
		(hatch none 0.5)
		(connect_pads
			(clearance 0)
		)
		(min_thickness 0.25)
		(keepout
			(tracks not_allowed)
			(vias allowed)
			(pads allowed)
			(copperpour not_allowed)
			(footprints allowed)
		)
		(placement
			(enabled no)
			(sheetname "")
		)
		(fill
			(thermal_gap 0.5)
			(thermal_bridge_width 0.5)
			(island_removal_mode 0)
		)
		(polygon
			(pts
				(arc
					(start 343.300558 -407.00452)
					(mid 342.596978 -407.00452)
					(end 343.300558 -407.00452)
				)
			)
		)
	)
	(zone
		(layer "B.Cu")
		(hatch none 0.5)
		(connect_pads
			(clearance 0)
		)
		(min_thickness 0.25)
		(keepout
			(tracks not_allowed)
			(vias allowed)
			(pads allowed)
			(copperpour not_allowed)
			(footprints allowed)
		)
		(placement
			(enabled no)
			(sheetname "")
		)
		(fill
			(thermal_gap 0.5)
			(thermal_bridge_width 0.5)
			(island_removal_mode 0)
		)
		(polygon
			(pts
				(arc
					(start 122.304556 -224.389442)
					(mid 121.651776 -224.389442)
					(end 122.304556 -224.389442)
				)
			)
		)
	)
	(zone
		(layer "B.Cu")
		(hatch none 0.5)
		(connect_pads
			(clearance 0)
		)
		(min_thickness 0.25)
		(keepout
			(tracks not_allowed)
			(vias allowed)
			(pads allowed)
			(copperpour not_allowed)
			(footprints allowed)
		)
		(placement
			(enabled no)
			(sheetname "")
		)
		(fill
			(thermal_gap 0.5)
			(thermal_bridge_width 0.5)
			(island_removal_mode 0)
		)
		(polygon
			(pts
				(arc
					(start 462.799938 -22.29993)
					(mid 464.799934 -24.299926)
					(end 466.79993 -22.29993)
				)
				(arc
					(start 466.79993 -22.29993)
					(mid 464.799934 -20.299934)
					(end 462.799938 -22.29993)
				)
			)
		)
	)
	(zone
		(layer "B.Cu")
		(hatch none 0.5)
		(connect_pads
			(clearance 0)
		)
		(min_thickness 0.25)
		(keepout
			(tracks not_allowed)
			(vias allowed)
			(pads allowed)
			(copperpour not_allowed)
			(footprints allowed)
		)
		(placement
			(enabled no)
			(sheetname "")
		)
		(fill
			(thermal_gap 0.5)
			(thermal_bridge_width 0.5)
			(island_removal_mode 0)
		)
		(polygon
			(pts
				(arc
					(start 327.120758 -407.00452)
					(mid 326.417178 -407.00452)
					(end 327.120758 -407.00452)
				)
			)
		)
	)
	(zone
		(layer "B.Cu")
		(hatch none 0.5)
		(connect_pads
			(clearance 0)
		)
		(min_thickness 0.25)
		(keepout
			(tracks not_allowed)
			(vias allowed)
			(pads allowed)
			(copperpour not_allowed)
			(footprints allowed)
		)
		(placement
			(enabled no)
			(sheetname "")
		)
		(fill
			(thermal_gap 0.5)
			(thermal_bridge_width 0.5)
			(island_removal_mode 0)
		)
		(polygon
			(pts
				(arc
					(start 93.640402 -225.203258)
					(mid 92.987622 -225.203258)
					(end 93.640402 -225.203258)
				)
			)
		)
	)
	(zone
		(layer "B.Cu")
		(hatch none 0.5)
		(connect_pads
			(clearance 0)
		)
		(min_thickness 0.25)
		(keepout
			(tracks not_allowed)
			(vias allowed)
			(pads allowed)
			(copperpour not_allowed)
			(footprints allowed)
		)
		(placement
			(enabled no)
			(sheetname "")
		)
		(fill
			(thermal_gap 0.5)
			(thermal_bridge_width 0.5)
			(island_removal_mode 0)
		)
		(polygon
			(pts
				(arc
					(start 141.949424 -400.858228)
					(mid 141.245844 -400.858228)
					(end 141.949424 -400.858228)
				)
			)
		)
	)
	(zone
		(layer "B.Cu")
		(hatch none 0.5)
		(connect_pads
			(clearance 0)
		)
		(min_thickness 0.25)
		(keepout
			(tracks not_allowed)
			(vias allowed)
			(pads allowed)
			(copperpour not_allowed)
			(footprints allowed)
		)
		(placement
			(enabled no)
			(sheetname "")
		)
		(fill
			(thermal_gap 0.5)
			(thermal_bridge_width 0.5)
			(island_removal_mode 0)
		)
		(polygon
			(pts
				(arc
					(start 453.799956 -435.59984)
					(mid 458.799946 -440.59983)
					(end 463.799936 -435.59984)
				)
				(arc
					(start 463.799936 -435.59984)
					(mid 458.799946 -430.59985)
					(end 453.799956 -435.59984)
				)
			)
		)
	)
	(zone
		(layer "B.Cu")
		(hatch none 0.5)
		(connect_pads
			(clearance 0)
		)
		(min_thickness 0.25)
		(keepout
			(tracks allowed)
			(vias allowed)
			(pads allowed)
			(copperpour allowed)
			(footprints not_allowed)
		)
		(placement
			(enabled no)
			(sheetname "")
		)
		(fill
			(thermal_gap 0.5)
			(thermal_bridge_width 0.5)
			(island_removal_mode 0)
		)
		(polygon
			(pts
				(arc
					(start 155.399994 -160.50006)
					(mid 167.900096 -173.000162)
					(end 180.399944 -160.50006)
				)
				(arc
					(start 180.399944 -160.50006)
					(mid 167.900096 -148.000212)
					(end 155.399994 -160.50006)
				)
			)
		)
	)
	(zone
		(layer "B.Cu")
		(hatch none 0.5)
		(connect_pads
			(clearance 0)
		)
		(min_thickness 0.25)
		(keepout
			(tracks not_allowed)
			(vias allowed)
			(pads allowed)
			(copperpour not_allowed)
			(footprints allowed)
		)
		(placement
			(enabled no)
			(sheetname "")
		)
		(fill
			(thermal_gap 0.5)
			(thermal_bridge_width 0.5)
			(island_removal_mode 0)
		)
		(polygon
			(pts
				(arc
					(start 89.017348 -400.858228)
					(mid 88.313768 -400.858228)
					(end 89.017348 -400.858228)
				)
			)
		)
	)
	(zone
		(layer "B.Cu")
		(hatch none 0.5)
		(connect_pads
			(clearance 0)
		)
		(min_thickness 0.25)
		(keepout
			(tracks allowed)
			(vias allowed)
			(pads allowed)
			(copperpour allowed)
			(footprints not_allowed)
		)
		(placement
			(enabled no)
			(sheetname "")
		)
		(fill
			(thermal_gap 0.5)
			(thermal_bridge_width 0.5)
			(island_removal_mode 0)
		)
		(polygon
			(pts
				(arc
					(start 227.65004 -44.500038)
					(mid 228.650038 -45.500036)
					(end 229.650036 -44.500038)
				)
				(arc
					(start 229.650036 -44.500038)
					(mid 228.650038 -43.50004)
					(end 227.65004 -44.500038)
				)
			)
		)
	)
	(zone
		(layer "B.Cu")
		(hatch none 0.5)
		(connect_pads
			(clearance 0)
		)
		(min_thickness 0.25)
		(keepout
			(tracks allowed)
			(vias allowed)
			(pads allowed)
			(copperpour allowed)
			(footprints allowed)
		)
		(placement
			(enabled no)
			(sheetname "")
		)
		(fill
			(thermal_gap 0.5)
			(thermal_bridge_width 0.5)
			(island_removal_mode 0)
		)
		(polygon
			(pts
				(xy 294.05834 -19.40306) (xy 294.05834 -18.3007) (xy 293.22776 -18.3007) (xy 293.22776 -19.40306)
			)
		)
	)
	(zone
		(layer "B.Cu")
		(hatch none 0.5)
		(connect_pads
			(clearance 0)
		)
		(min_thickness 0.25)
		(keepout
			(tracks allowed)
			(vias allowed)
			(pads allowed)
			(copperpour allowed)
			(footprints allowed)
		)
		(placement
			(enabled no)
			(sheetname "")
		)
		(fill
			(thermal_gap 0.5)
			(thermal_bridge_width 0.5)
			(island_removal_mode 0)
		)
		(polygon
			(pts
				(xy 14.85392 -109.20984) (xy 14.85392 -108.0008) (xy 16.9926 -108.0008) (xy 16.9926 -109.20984)
			)
		)
	)
	(zone
		(layer "B.Cu")
		(hatch none 0.5)
		(connect_pads
			(clearance 0)
		)
		(min_thickness 0.25)
		(keepout
			(tracks not_allowed)
			(vias allowed)
			(pads allowed)
			(copperpour not_allowed)
			(footprints allowed)
		)
		(placement
			(enabled no)
			(sheetname "")
		)
		(fill
			(thermal_gap 0.5)
			(thermal_bridge_width 0.5)
			(island_removal_mode 0)
		)
		(polygon
			(pts
				(arc
					(start 133.582156 -224.389442)
					(mid 132.929376 -224.389442)
					(end 133.582156 -224.389442)
				)
			)
		)
	)
	(zone
		(layer "B.Cu")
		(hatch none 0.5)
		(connect_pads
			(clearance 0)
		)
		(min_thickness 0.25)
		(keepout
			(tracks allowed)
			(vias allowed)
			(pads allowed)
			(copperpour allowed)
			(footprints not_allowed)
		)
		(placement
			(enabled no)
			(sheetname "")
		)
		(fill
			(thermal_gap 0.5)
			(thermal_bridge_width 0.5)
			(island_removal_mode 0)
		)
		(polygon
			(pts
				(arc
					(start 359.79989 -28.450032)
					(mid 356.899972 -25.550114)
					(end 354.000054 -28.450032)
				)
				(arc
					(start 354.000054 -28.450032)
					(mid 356.899972 -31.34995)
					(end 359.79989 -28.450032)
				)
			)
		)
	)
	(zone
		(layer "B.Cu")
		(hatch none 0.5)
		(connect_pads
			(clearance 0)
		)
		(min_thickness 0.25)
		(keepout
			(tracks not_allowed)
			(vias allowed)
			(pads allowed)
			(copperpour not_allowed)
			(footprints allowed)
		)
		(placement
			(enabled no)
			(sheetname "")
		)
		(fill
			(thermal_gap 0.5)
			(thermal_bridge_width 0.5)
			(island_removal_mode 0)
		)
		(polygon
			(pts
				(arc
					(start 330.183998 -407.00452)
					(mid 329.480418 -407.00452)
					(end 330.183998 -407.00452)
				)
			)
		)
	)
	(zone
		(layer "B.Cu")
		(hatch none 0.5)
		(connect_pads
			(clearance 0)
		)
		(min_thickness 0.25)
		(keepout
			(tracks not_allowed)
			(vias allowed)
			(pads allowed)
			(copperpour not_allowed)
			(footprints allowed)
		)
		(placement
			(enabled no)
			(sheetname "")
		)
		(fill
			(thermal_gap 0.5)
			(thermal_bridge_width 0.5)
			(island_removal_mode 0)
		)
		(polygon
			(pts
				(arc
					(start 26.323544 -400.432016)
					(mid 25.619964 -400.432016)
					(end 26.323544 -400.432016)
				)
			)
		)
	)
	(zone
		(layer "B.Cu")
		(hatch none 0.5)
		(connect_pads
			(clearance 0)
		)
		(min_thickness 0.25)
		(keepout
			(tracks allowed)
			(vias allowed)
			(pads allowed)
			(copperpour allowed)
			(footprints not_allowed)
		)
		(placement
			(enabled no)
			(sheetname "")
		)
		(fill
			(thermal_gap 0.5)
			(thermal_bridge_width 0.5)
			(island_removal_mode 0)
		)
		(polygon
			(pts
				(arc
					(start 262.850122 -22.29993)
					(mid 265.650218 -25.100026)
					(end 268.45006 -22.29993)
				)
				(arc
					(start 268.45006 -22.29993)
					(mid 265.650218 -19.500088)
					(end 262.850122 -22.29993)
				)
			)
		)
	)
	(zone
		(layer "B.Cu")
		(hatch none 0.5)
		(connect_pads
			(clearance 0)
		)
		(min_thickness 0.25)
		(keepout
			(tracks not_allowed)
			(vias allowed)
			(pads allowed)
			(copperpour not_allowed)
			(footprints allowed)
		)
		(placement
			(enabled no)
			(sheetname "")
		)
		(fill
			(thermal_gap 0.5)
			(thermal_bridge_width 0.5)
			(island_removal_mode 0)
		)
		(polygon
			(pts
				(arc
					(start 347.21927 -225.203258)
					(mid 346.56649 -225.203258)
					(end 347.21927 -225.203258)
				)
			)
		)
	)
	(zone
		(layer "B.Cu")
		(hatch none 0.5)
		(connect_pads
			(clearance 0)
		)
		(min_thickness 0.25)
		(keepout
			(tracks allowed)
			(vias allowed)
			(pads allowed)
			(copperpour allowed)
			(footprints not_allowed)
		)
		(placement
			(enabled no)
			(sheetname "")
		)
		(fill
			(thermal_gap 0.5)
			(thermal_bridge_width 0.5)
			(island_removal_mode 0)
		)
		(polygon
			(pts
				(arc
					(start 89.899998 -22.29993)
					(mid 94.899988 -27.29992)
					(end 99.899978 -22.29993)
				)
				(arc
					(start 99.899978 -22.29993)
					(mid 94.899988 -17.29994)
					(end 89.899998 -22.29993)
				)
			)
		)
	)
	(zone
		(layer "B.Cu")
		(hatch none 0.5)
		(connect_pads
			(clearance 0)
		)
		(min_thickness 0.25)
		(keepout
			(tracks allowed)
			(vias allowed)
			(pads allowed)
			(copperpour allowed)
			(footprints not_allowed)
		)
		(placement
			(enabled no)
			(sheetname "")
		)
		(fill
			(thermal_gap 0.5)
			(thermal_bridge_width 0.5)
			(island_removal_mode 0)
		)
		(polygon
			(pts
				(arc
					(start 7.500112 -335.526888)
					(mid 5.147363 -336.329587)
					(end 2.999994 -337.582002)
				)
				(arc
					(start 2.999994 -163.681918)
					(mid 4.815203 -166.285783)
					(end 7.500112 -167.978836)
				)
			)
		)
	)
	(zone
		(layer "B.Cu")
		(hatch none 0.5)
		(connect_pads
			(clearance 0)
		)
		(min_thickness 0.25)
		(keepout
			(tracks not_allowed)
			(vias allowed)
			(pads allowed)
			(copperpour not_allowed)
			(footprints allowed)
		)
		(placement
			(enabled no)
			(sheetname "")
		)
		(fill
			(thermal_gap 0.5)
			(thermal_bridge_width 0.5)
			(island_removal_mode 0)
		)
		(polygon
			(pts
				(arc
					(start 7.53999 -160.50006)
					(mid 10.340086 -163.300156)
					(end 13.139928 -160.50006)
				)
				(arc
					(start 13.139928 -160.50006)
					(mid 10.340086 -157.700218)
					(end 7.53999 -160.50006)
				)
			)
		)
	)
	(zone
		(layer "B.Cu")
		(hatch none 0.5)
		(connect_pads
			(clearance 0)
		)
		(min_thickness 0.25)
		(keepout
			(tracks allowed)
			(vias allowed)
			(pads allowed)
			(copperpour allowed)
			(footprints not_allowed)
		)
		(placement
			(enabled no)
			(sheetname "")
		)
		(fill
			(thermal_gap 0.5)
			(thermal_bridge_width 0.5)
			(island_removal_mode 0)
		)
		(polygon
			(pts
				(arc
					(start 132.518912 -354.434902)
					(mid 136.518904 -358.434894)
					(end 140.518896 -354.434902)
				)
				(arc
					(start 140.518896 -354.434902)
					(mid 136.518904 -350.43491)
					(end 132.518912 -354.434902)
				)
			)
		)
	)
	(zone
		(layer "B.Cu")
		(hatch none 0.5)
		(connect_pads
			(clearance 0)
		)
		(min_thickness 0.25)
		(keepout
			(tracks not_allowed)
			(vias allowed)
			(pads allowed)
			(copperpour not_allowed)
			(footprints allowed)
		)
		(placement
			(enabled no)
			(sheetname "")
		)
		(fill
			(thermal_gap 0.5)
			(thermal_bridge_width 0.5)
			(island_removal_mode 0)
		)
		(polygon
			(pts
				(arc
					(start 376.35307 -223.575626)
					(mid 375.70029 -223.575626)
					(end 376.35307 -223.575626)
				)
			)
		)
	)
	(zone
		(layer "B.Cu")
		(hatch none 0.5)
		(connect_pads
			(clearance 0)
		)
		(min_thickness 0.25)
		(keepout
			(tracks not_allowed)
			(vias allowed)
			(pads allowed)
			(copperpour not_allowed)
			(footprints allowed)
		)
		(placement
			(enabled no)
			(sheetname "")
		)
		(fill
			(thermal_gap 0.5)
			(thermal_bridge_width 0.5)
			(island_removal_mode 0)
		)
		(polygon
			(pts
				(arc
					(start 90.821002 -223.575626)
					(mid 90.168222 -223.575626)
					(end 90.821002 -223.575626)
				)
			)
		)
	)
	(zone
		(layer "B.Cu")
		(hatch none 0.5)
		(connect_pads
			(clearance 0)
		)
		(min_thickness 0.25)
		(keepout
			(tracks not_allowed)
			(vias allowed)
			(pads allowed)
			(copperpour not_allowed)
			(footprints allowed)
		)
		(placement
			(enabled no)
			(sheetname "")
		)
		(fill
			(thermal_gap 0.5)
			(thermal_bridge_width 0.5)
			(island_removal_mode 0)
		)
		(polygon
			(pts
				(arc
					(start 380.11227 -223.575626)
					(mid 379.45949 -223.575626)
					(end 380.11227 -223.575626)
				)
			)
		)
	)
	(zone
		(layer "B.Cu")
		(hatch none 0.5)
		(connect_pads
			(clearance 0)
		)
		(min_thickness 0.25)
		(keepout
			(tracks allowed)
			(vias allowed)
			(pads allowed)
			(copperpour allowed)
			(footprints allowed)
		)
		(placement
			(enabled no)
			(sheetname "")
		)
		(fill
			(thermal_gap 0.5)
			(thermal_bridge_width 0.5)
			(island_removal_mode 0)
		)
		(polygon
			(pts
				(xy 227.31222 -86.9696) (xy 227.31222 -85.88756) (xy 229.12578 -85.88756) (xy 229.12578 -86.9696)
			)
		)
	)
	(zone
		(layer "B.Cu")
		(hatch none 0.5)
		(connect_pads
			(clearance 0)
		)
		(min_thickness 0.25)
		(keepout
			(tracks allowed)
			(vias allowed)
			(pads allowed)
			(copperpour allowed)
			(footprints allowed)
		)
		(placement
			(enabled no)
			(sheetname "")
		)
		(fill
			(thermal_gap 0.5)
			(thermal_bridge_width 0.5)
			(island_removal_mode 0)
		)
		(polygon
			(pts
				(xy 134.92226 -18.07718) (xy 134.92226 -17.3736) (xy 137.21842 -17.3736) (xy 137.21842 -18.07718)
			)
		)
	)
	(zone
		(layer "B.Cu")
		(hatch none 0.5)
		(connect_pads
			(clearance 0)
		)
		(min_thickness 0.25)
		(keepout
			(tracks not_allowed)
			(vias allowed)
			(pads allowed)
			(copperpour not_allowed)
			(footprints allowed)
		)
		(placement
			(enabled no)
			(sheetname "")
		)
		(fill
			(thermal_gap 0.5)
			(thermal_bridge_width 0.5)
			(island_removal_mode 0)
		)
		(polygon
			(pts
				(arc
					(start 199.64527 -51.999896)
					(mid 204.64526 -56.999886)
					(end 209.64525 -51.999896)
				)
				(arc
					(start 209.64525 -51.999896)
					(mid 204.64526 -46.999906)
					(end 199.64527 -51.999896)
				)
			)
		)
	)
	(zone
		(layer "B.Cu")
		(hatch none 0.5)
		(connect_pads
			(clearance 0)
		)
		(min_thickness 0.25)
		(keepout
			(tracks not_allowed)
			(vias allowed)
			(pads allowed)
			(copperpour not_allowed)
			(footprints allowed)
		)
		(placement
			(enabled no)
			(sheetname "")
		)
		(fill
			(thermal_gap 0.5)
			(thermal_bridge_width 0.5)
			(island_removal_mode 0)
		)
		(polygon
			(pts
				(arc
					(start 94.580202 -223.575626)
					(mid 93.927422 -223.575626)
					(end 94.580202 -223.575626)
				)
			)
		)
	)
	(zone
		(layer "B.Cu")
		(hatch none 0.5)
		(connect_pads
			(clearance 0)
		)
		(min_thickness 0.25)
		(keepout
			(tracks not_allowed)
			(vias allowed)
			(pads allowed)
			(copperpour not_allowed)
			(footprints allowed)
		)
		(placement
			(enabled no)
			(sheetname "")
		)
		(fill
			(thermal_gap 0.5)
			(thermal_bridge_width 0.5)
			(island_removal_mode 0)
		)
		(polygon
			(pts
				(arc
					(start 328.254614 -353.525074)
					(mid 329.854814 -355.125274)
					(end 331.45476 -353.525074)
				)
				(arc
					(start 331.45476 -353.525074)
					(mid 329.854814 -351.925128)
					(end 328.254614 -353.525074)
				)
			)
		)
	)
	(zone
		(layer "B.Cu")
		(hatch none 0.5)
		(connect_pads
			(clearance 0)
		)
		(min_thickness 0.25)
		(keepout
			(tracks not_allowed)
			(vias allowed)
			(pads allowed)
			(copperpour not_allowed)
			(footprints allowed)
		)
		(placement
			(enabled no)
			(sheetname "")
		)
		(fill
			(thermal_gap 0.5)
			(thermal_bridge_width 0.5)
			(island_removal_mode 0)
		)
		(polygon
			(pts
				(arc
					(start 325.854822 -353.525074)
					(mid 329.854814 -357.525066)
					(end 333.854806 -353.525074)
				)
				(arc
					(start 333.854806 -353.525074)
					(mid 329.854814 -349.525082)
					(end 325.854822 -353.525074)
				)
			)
		)
	)
	(zone
		(layer "B.Cu")
		(hatch none 0.5)
		(connect_pads
			(clearance 0)
		)
		(min_thickness 0.25)
		(keepout
			(tracks not_allowed)
			(vias allowed)
			(pads allowed)
			(copperpour not_allowed)
			(footprints allowed)
		)
		(placement
			(enabled no)
			(sheetname "")
		)
		(fill
			(thermal_gap 0.5)
			(thermal_bridge_width 0.5)
			(island_removal_mode 0)
		)
		(polygon
			(pts
				(arc
					(start 342.050624 -224.389442)
					(mid 341.397844 -224.389442)
					(end 342.050624 -224.389442)
				)
			)
		)
	)
	(zone
		(layer "B.Cu")
		(hatch none 0.5)
		(connect_pads
			(clearance 0)
		)
		(min_thickness 0.25)
		(keepout
			(tracks allowed)
			(vias allowed)
			(pads allowed)
			(copperpour allowed)
			(footprints not_allowed)
		)
		(placement
			(enabled no)
			(sheetname "")
		)
		(fill
			(thermal_gap 0.5)
			(thermal_bridge_width 0.5)
			(island_removal_mode 0)
		)
		(polygon
			(pts
				(xy 153.42997 -311.770014) (xy 153.42997 -191.77) (xy 70.429882 -191.77) (xy 70.429882 -311.770014)
			)
		)
	)
	(zone
		(layer "B.Cu")
		(hatch none 0.5)
		(connect_pads
			(clearance 0)
		)
		(min_thickness 0.25)
		(keepout
			(tracks not_allowed)
			(vias allowed)
			(pads allowed)
			(copperpour not_allowed)
			(footprints allowed)
		)
		(placement
			(enabled no)
			(sheetname "")
		)
		(fill
			(thermal_gap 0.5)
			(thermal_bridge_width 0.5)
			(island_removal_mode 0)
		)
		(polygon
			(pts
				(arc
					(start 375.41327 -225.203258)
					(mid 374.76049 -225.203258)
					(end 375.41327 -225.203258)
				)
			)
		)
	)
	(zone
		(layer "B.Cu")
		(hatch none 0.5)
		(connect_pads
			(clearance 0)
		)
		(min_thickness 0.25)
		(keepout
			(tracks allowed)
			(vias allowed)
			(pads allowed)
			(copperpour allowed)
			(footprints allowed)
		)
		(placement
			(enabled no)
			(sheetname "")
		)
		(fill
			(thermal_gap 0.5)
			(thermal_bridge_width 0.5)
			(island_removal_mode 0)
		)
		(polygon
			(pts
				(xy 111.41456 -361.287568) (xy 111.41456 -356.807008) (xy 114.16792 -356.807008) (xy 114.16792 -361.287568)
			)
		)
	)
	(zone
		(layer "B.Cu")
		(hatch none 0.5)
		(connect_pads
			(clearance 0)
		)
		(min_thickness 0.25)
		(keepout
			(tracks allowed)
			(vias allowed)
			(pads allowed)
			(copperpour allowed)
			(footprints not_allowed)
		)
		(placement
			(enabled no)
			(sheetname "")
		)
		(fill
			(thermal_gap 0.5)
			(thermal_bridge_width 0.5)
			(island_removal_mode 0)
		)
		(polygon
			(pts
				(arc
					(start 180.399944 -160.50006)
					(mid 167.900096 -148.000212)
					(end 155.399994 -160.50006)
				)
				(arc
					(start 155.399994 -160.50006)
					(mid 167.900096 -173.000162)
					(end 180.399944 -160.50006)
				)
			)
		)
	)
	(zone
		(layer "B.Cu")
		(hatch none 0.5)
		(connect_pads
			(clearance 0)
		)
		(min_thickness 0.25)
		(keepout
			(tracks not_allowed)
			(vias allowed)
			(pads allowed)
			(copperpour not_allowed)
			(footprints allowed)
		)
		(placement
			(enabled no)
			(sheetname "")
		)
		(fill
			(thermal_gap 0.5)
			(thermal_bridge_width 0.5)
			(island_removal_mode 0)
		)
		(polygon
			(pts
				(arc
					(start 336.310478 -407.00452)
					(mid 335.606898 -407.00452)
					(end 336.310478 -407.00452)
				)
			)
		)
	)
	(zone
		(layer "B.Cu")
		(hatch none 0.5)
		(connect_pads
			(clearance 0)
		)
		(min_thickness 0.25)
		(keepout
			(tracks not_allowed)
			(vias allowed)
			(pads allowed)
			(copperpour not_allowed)
			(footprints allowed)
		)
		(placement
			(enabled no)
			(sheetname "")
		)
		(fill
			(thermal_gap 0.5)
			(thermal_bridge_width 0.5)
			(island_removal_mode 0)
		)
		(polygon
			(pts
				(arc
					(start 341.58047 -225.203258)
					(mid 340.92769 -225.203258)
					(end 341.58047 -225.203258)
				)
			)
		)
	)
	(zone
		(layer "B.Cu")
		(hatch none 0.5)
		(connect_pads
			(clearance 0)
		)
		(min_thickness 0.25)
		(keepout
			(tracks allowed)
			(vias allowed)
			(pads allowed)
			(copperpour allowed)
			(footprints allowed)
		)
		(placement
			(enabled no)
			(sheetname "")
		)
		(fill
			(thermal_gap 0.5)
			(thermal_bridge_width 0.5)
			(island_removal_mode 0)
		)
		(polygon
			(pts
				(xy 309.14086 -14.71676) (xy 309.14086 -13.66012) (xy 301.54118 -13.66012) (xy 301.54118 -14.71676)
			)
		)
	)
	(zone
		(layer "B.Cu")
		(hatch none 0.5)
		(connect_pads
			(clearance 0)
		)
		(min_thickness 0.25)
		(keepout
			(tracks allowed)
			(vias allowed)
			(pads allowed)
			(copperpour allowed)
			(footprints allowed)
		)
		(placement
			(enabled no)
			(sheetname "")
		)
		(fill
			(thermal_gap 0.5)
			(thermal_bridge_width 0.5)
			(island_removal_mode 0)
		)
		(polygon
			(pts
				(xy 106.00182 -338.285328) (xy 106.00182 -334.013048) (xy 100.14966 -334.013048) (xy 100.14966 -338.285328)
			)
		)
	)
	(zone
		(layer "B.Cu")
		(hatch none 0.5)
		(connect_pads
			(clearance 0)
		)
		(min_thickness 0.25)
		(keepout
			(tracks allowed)
			(vias allowed)
			(pads allowed)
			(copperpour allowed)
			(footprints allowed)
		)
		(placement
			(enabled no)
			(sheetname "")
		)
		(fill
			(thermal_gap 0.5)
			(thermal_bridge_width 0.5)
			(island_removal_mode 0)
		)
		(polygon
			(pts
				(xy 138.03376 -12.97432) (xy 138.03376 -11.76782) (xy 137.04824 -11.76782) (xy 137.04824 -12.97432)
			)
		)
	)
	(zone
		(layer "B.Cu")
		(hatch none 0.5)
		(connect_pads
			(clearance 0)
		)
		(min_thickness 0.25)
		(keepout
			(tracks not_allowed)
			(vias allowed)
			(pads allowed)
			(copperpour not_allowed)
			(footprints allowed)
		)
		(placement
			(enabled no)
			(sheetname "")
		)
		(fill
			(thermal_gap 0.5)
			(thermal_bridge_width 0.5)
			(island_removal_mode 0)
		)
		(polygon
			(pts
				(arc
					(start 339.231224 -224.389442)
					(mid 338.578444 -224.389442)
					(end 339.231224 -224.389442)
				)
			)
		)
	)
	(zone
		(layer "B.Cu")
		(hatch none 0.5)
		(connect_pads
			(clearance 0)
		)
		(min_thickness 0.25)
		(keepout
			(tracks not_allowed)
			(vias allowed)
			(pads allowed)
			(copperpour not_allowed)
			(footprints allowed)
		)
		(placement
			(enabled no)
			(sheetname "")
		)
		(fill
			(thermal_gap 0.5)
			(thermal_bridge_width 0.5)
			(island_removal_mode 0)
		)
		(polygon
			(pts
				(arc
					(start 381.992124 -223.575626)
					(mid 381.339344 -223.575626)
					(end 381.992124 -223.575626)
				)
			)
		)
	)
	(zone
		(layer "B.Cu")
		(hatch none 0.5)
		(connect_pads
			(clearance 0)
		)
		(min_thickness 0.25)
		(keepout
			(tracks allowed)
			(vias allowed)
			(pads allowed)
			(copperpour allowed)
			(footprints allowed)
		)
		(placement
			(enabled no)
			(sheetname "")
		)
		(fill
			(thermal_gap 0.5)
			(thermal_bridge_width 0.5)
			(island_removal_mode 0)
		)
		(polygon
			(pts
				(xy 357.428546 -364.834932) (xy 357.428546 -363.026452) (xy 360.903266 -363.026452) (xy 360.903266 -364.834932)
			)
		)
	)
	(zone
		(layer "B.Cu")
		(hatch none 0.5)
		(connect_pads
			(clearance 0)
		)
		(min_thickness 0.25)
		(keepout
			(tracks allowed)
			(vias allowed)
			(pads allowed)
			(copperpour allowed)
			(footprints allowed)
		)
		(placement
			(enabled no)
			(sheetname "")
		)
		(fill
			(thermal_gap 0.5)
			(thermal_bridge_width 0.5)
			(island_removal_mode 0)
		)
		(polygon
			(pts
				(xy 178.78044 -54.70906) (xy 178.78044 -50.6603) (xy 177.80508 -50.6603) (xy 177.80508 -54.70906)
			)
		)
	)
	(zone
		(layer "B.Cu")
		(hatch none 0.5)
		(connect_pads
			(clearance 0)
		)
		(min_thickness 0.25)
		(keepout
			(tracks not_allowed)
			(vias allowed)
			(pads allowed)
			(copperpour not_allowed)
			(footprints allowed)
		)
		(placement
			(enabled no)
			(sheetname "")
		)
		(fill
			(thermal_gap 0.5)
			(thermal_bridge_width 0.5)
			(island_removal_mode 0)
		)
		(polygon
			(pts
				(arc
					(start 374.47347 -223.575626)
					(mid 373.82069 -223.575626)
					(end 374.47347 -223.575626)
				)
			)
		)
	)
	(zone
		(layer "B.Cu")
		(hatch none 0.5)
		(connect_pads
			(clearance 0)
		)
		(min_thickness 0.25)
		(keepout
			(tracks allowed)
			(vias allowed)
			(pads allowed)
			(copperpour allowed)
			(footprints not_allowed)
		)
		(placement
			(enabled no)
			(sheetname "")
		)
		(fill
			(thermal_gap 0.5)
			(thermal_bridge_width 0.5)
			(island_removal_mode 0)
		)
		(polygon
			(pts
				(arc
					(start 358.44988 -28.450032)
					(mid 356.899972 -26.900124)
					(end 355.350064 -28.450032)
				)
				(arc
					(start 355.350064 -28.450032)
					(mid 356.899972 -29.99994)
					(end 358.44988 -28.450032)
				)
			)
		)
	)
	(zone
		(layer "B.Cu")
		(hatch none 0.5)
		(connect_pads
			(clearance 0)
		)
		(min_thickness 0.25)
		(keepout
			(tracks allowed)
			(vias allowed)
			(pads allowed)
			(copperpour allowed)
			(footprints allowed)
		)
		(placement
			(enabled no)
			(sheetname "")
		)
		(fill
			(thermal_gap 0.5)
			(thermal_bridge_width 0.5)
			(island_removal_mode 0)
		)
		(polygon
			(pts
				(xy 364.8837 -54.06898) (xy 364.8837 -53.2765) (xy 366.81664 -53.2765) (xy 366.81664 -54.06898)
			)
		)
	)
	(zone
		(layer "B.Cu")
		(hatch none 0.5)
		(connect_pads
			(clearance 0)
		)
		(min_thickness 0.25)
		(keepout
			(tracks not_allowed)
			(vias allowed)
			(pads allowed)
			(copperpour not_allowed)
			(footprints allowed)
		)
		(placement
			(enabled no)
			(sheetname "")
		)
		(fill
			(thermal_gap 0.5)
			(thermal_bridge_width 0.5)
			(island_removal_mode 0)
		)
		(polygon
			(pts
				(arc
					(start 148.075904 -400.858228)
					(mid 147.372324 -400.858228)
					(end 148.075904 -400.858228)
				)
			)
		)
	)
	(zone
		(layer "B.Cu")
		(hatch none 0.5)
		(connect_pads
			(clearance 0)
		)
		(min_thickness 0.25)
		(keepout
			(tracks not_allowed)
			(vias allowed)
			(pads allowed)
			(copperpour not_allowed)
			(footprints allowed)
		)
		(placement
			(enabled no)
			(sheetname "")
		)
		(fill
			(thermal_gap 0.5)
			(thermal_bridge_width 0.5)
			(island_removal_mode 0)
		)
		(polygon
			(pts
				(arc
					(start 134.918958 -354.434902)
					(mid 136.518904 -356.034848)
					(end 138.11885 -354.434902)
				)
				(arc
					(start 138.11885 -354.434902)
					(mid 136.518904 -352.834956)
					(end 134.918958 -354.434902)
				)
			)
		)
	)
	(zone
		(layer "B.Cu")
		(hatch none 0.5)
		(connect_pads
			(clearance 0)
		)
		(min_thickness 0.25)
		(keepout
			(tracks allowed)
			(vias allowed)
			(pads allowed)
			(copperpour allowed)
			(footprints allowed)
		)
		(placement
			(enabled no)
			(sheetname "")
		)
		(fill
			(thermal_gap 0.5)
			(thermal_bridge_width 0.5)
			(island_removal_mode 0)
		)
		(polygon
			(pts
				(xy 136.91616 -18.6309) (xy 136.91616 -17.90954) (xy 138.54938 -17.90954) (xy 138.54938 -18.6309)
			)
		)
	)
	(zone
		(layer "B.Cu")
		(hatch none 0.5)
		(connect_pads
			(clearance 0)
		)
		(min_thickness 0.25)
		(keepout
			(tracks not_allowed)
			(vias allowed)
			(pads allowed)
			(copperpour not_allowed)
			(footprints allowed)
		)
		(placement
			(enabled no)
			(sheetname "")
		)
		(fill
			(thermal_gap 0.5)
			(thermal_bridge_width 0.5)
			(island_removal_mode 0)
		)
		(polygon
			(pts
				(arc
					(start 92.899992 -22.29993)
					(mid 94.899988 -24.299926)
					(end 96.899984 -22.29993)
				)
				(arc
					(start 96.899984 -22.29993)
					(mid 94.899988 -20.299934)
					(end 92.899992 -22.29993)
				)
			)
		)
	)
	(zone
		(layer "B.Cu")
		(hatch none 0.5)
		(connect_pads
			(clearance 0)
		)
		(min_thickness 0.25)
		(keepout
			(tracks allowed)
			(vias allowed)
			(pads allowed)
			(copperpour allowed)
			(footprints allowed)
		)
		(placement
			(enabled no)
			(sheetname "")
		)
		(fill
			(thermal_gap 0.5)
			(thermal_bridge_width 0.5)
			(island_removal_mode 0)
		)
		(polygon
			(pts
				(xy 10.96518 -115.0239) (xy 10.96518 -113.91392) (xy 12.96924 -113.91392) (xy 12.96924 -115.0239)
			)
		)
	)
	(zone
		(layer "B.Cu")
		(hatch none 0.5)
		(connect_pads
			(clearance 0)
		)
		(min_thickness 0.25)
		(keepout
			(tracks not_allowed)
			(vias allowed)
			(pads allowed)
			(copperpour not_allowed)
			(footprints allowed)
		)
		(placement
			(enabled no)
			(sheetname "")
		)
		(fill
			(thermal_gap 0.5)
			(thermal_bridge_width 0.5)
			(island_removal_mode 0)
		)
		(polygon
			(pts
				(arc
					(start 325.699882 -160.50006)
					(mid 322.90004 -157.700218)
					(end 320.099944 -160.50006)
				)
				(arc
					(start 320.099944 -160.50006)
					(mid 322.90004 -163.300156)
					(end 325.699882 -160.50006)
				)
			)
		)
	)
	(zone
		(layer "B.Cu")
		(hatch none 0.5)
		(connect_pads
			(clearance 0)
		)
		(min_thickness 0.25)
		(keepout
			(tracks not_allowed)
			(vias allowed)
			(pads allowed)
			(copperpour not_allowed)
			(footprints allowed)
		)
		(placement
			(enabled no)
			(sheetname "")
		)
		(fill
			(thermal_gap 0.5)
			(thermal_bridge_width 0.5)
			(island_removal_mode 0)
		)
		(polygon
			(pts
				(arc
					(start 74.382884 -47.049944)
					(mid 71.402724 -43.182144)
					(end 66.902838 -45.077634)
				)
				(arc
					(start 66.902838 -45.077634)
					(mid 65.784431 -44.173275)
					(end 64.382904 -43.850052)
				)
				(arc
					(start 62.782958 -43.850052)
					(mid 59.583066 -47.049944)
					(end 62.782958 -50.249836)
				)
				(arc
					(start 64.382904 -50.249836)
					(mid 65.784467 -49.926686)
					(end 66.902838 -49.022254)
				)
				(arc
					(start 66.902838 -49.022254)
					(mid 71.402751 -50.917846)
					(end 74.382884 -47.049944)
				)
			)
		)
		(polygon
			(pts
				(arc
					(start 72.282812 -47.049944)
					(mid 70.382892 -45.150024)
					(end 68.482972 -47.049944)
				)
				(arc
					(start 68.482972 -47.049944)
					(mid 70.382892 -48.949864)
					(end 72.282812 -47.049944)
				)
			)
		)
		(polygon
			(pts
				(arc
					(start 64.382904 -48.64989)
					(mid 65.98285 -47.049944)
					(end 64.382904 -45.449998)
				)
				(arc
					(start 62.782958 -45.449998)
					(mid 61.183012 -47.049944)
					(end 62.782958 -48.64989)
				)
			)
		)
	)
	(zone
		(layer "B.Cu")
		(hatch none 0.5)
		(connect_pads
			(clearance 0)
		)
		(min_thickness 0.25)
		(keepout
			(tracks allowed)
			(vias allowed)
			(pads allowed)
			(copperpour allowed)
			(footprints allowed)
		)
		(placement
			(enabled no)
			(sheetname "")
		)
		(fill
			(thermal_gap 0.5)
			(thermal_bridge_width 0.5)
			(island_removal_mode 0)
		)
		(polygon
			(pts
				(xy 294.5892 -367.619788) (xy 294.5892 -364.063788) (xy 298.78782 -364.063788) (xy 298.78782 -367.619788)
			)
		)
	)
	(zone
		(layer "B.Cu")
		(hatch none 0.5)
		(connect_pads
			(clearance 0)
		)
		(min_thickness 0.25)
		(keepout
			(tracks allowed)
			(vias allowed)
			(pads allowed)
			(copperpour allowed)
			(footprints not_allowed)
		)
		(placement
			(enabled no)
			(sheetname "")
		)
		(fill
			(thermal_gap 0.5)
			(thermal_bridge_width 0.5)
			(island_removal_mode 0)
		)
		(polygon
			(pts
				(arc
					(start 359.37444 -439.349896)
					(mid 359.668453 -440.181336)
					(end 360.020362 -440.989974)
				)
				(arc
					(start 382.576832 -440.989974)
					(mid 379.614138 -426.267334)
					(end 364.648496 -425.015914)
				)
				(arc
					(start 364.648496 -425.015914)
					(mid 366.950899 -427.823722)
					(end 367.774982 -431.360072)
				)
				(arc
					(start 367.774982 -431.360072)
					(mid 365.288401 -437.156806)
					(end 359.37444 -439.349896)
				)
			)
		)
	)
	(zone
		(layer "B.Cu")
		(hatch none 0.5)
		(connect_pads
			(clearance 0)
		)
		(min_thickness 0.25)
		(keepout
			(tracks not_allowed)
			(vias allowed)
			(pads allowed)
			(copperpour not_allowed)
			(footprints allowed)
		)
		(placement
			(enabled no)
			(sheetname "")
		)
		(fill
			(thermal_gap 0.5)
			(thermal_bridge_width 0.5)
			(island_removal_mode 0)
		)
		(polygon
			(pts
				(arc
					(start 357.156004 -44.998386)
					(mid 356.452424 -44.998386)
					(end 357.156004 -44.998386)
				)
			)
		)
	)
	(zone
		(layer "B.Cu")
		(hatch none 0.5)
		(connect_pads
			(clearance 0)
		)
		(min_thickness 0.25)
		(keepout
			(tracks allowed)
			(vias allowed)
			(pads allowed)
			(copperpour allowed)
			(footprints allowed)
		)
		(placement
			(enabled no)
			(sheetname "")
		)
		(fill
			(thermal_gap 0.5)
			(thermal_bridge_width 0.5)
			(island_removal_mode 0)
		)
		(polygon
			(pts
				(xy 31.55442 -316.212728) (xy 31.55442 -315.590428) (xy 32.1818 -315.590428) (xy 32.1818 -316.212728)
			)
		)
	)
	(zone
		(layer "B.Cu")
		(hatch none 0.5)
		(connect_pads
			(clearance 0)
		)
		(min_thickness 0.25)
		(keepout
			(tracks not_allowed)
			(vias allowed)
			(pads allowed)
			(copperpour not_allowed)
			(footprints allowed)
		)
		(placement
			(enabled no)
			(sheetname "")
		)
		(fill
			(thermal_gap 0.5)
			(thermal_bridge_width 0.5)
			(island_removal_mode 0)
		)
		(polygon
			(pts
				(arc
					(start 311.804558 -407.00452)
					(mid 311.100978 -407.00452)
					(end 311.804558 -407.00452)
				)
			)
		)
	)
	(zone
		(layer "B.Cu")
		(hatch none 0.5)
		(connect_pads
			(clearance 0)
		)
		(min_thickness 0.25)
		(keepout
			(tracks allowed)
			(vias allowed)
			(pads allowed)
			(copperpour allowed)
			(footprints allowed)
		)
		(placement
			(enabled no)
			(sheetname "")
		)
		(fill
			(thermal_gap 0.5)
			(thermal_bridge_width 0.5)
			(island_removal_mode 0)
		)
		(polygon
			(pts
				(xy 359.77576 -361.724448) (xy 359.77576 -354.117148) (xy 362.70692 -354.117148) (xy 362.70692 -361.724448)
			)
		)
	)
	(zone
		(layer "B.Cu")
		(hatch none 0.5)
		(connect_pads
			(clearance 0)
		)
		(min_thickness 0.25)
		(keepout
			(tracks allowed)
			(vias allowed)
			(pads allowed)
			(copperpour allowed)
			(footprints allowed)
		)
		(placement
			(enabled no)
			(sheetname "")
		)
		(fill
			(thermal_gap 0.5)
			(thermal_bridge_width 0.5)
			(island_removal_mode 0)
		)
		(polygon
			(pts
				(xy 140.14704 -20.06092) (xy 140.14704 -18.98396) (xy 141.5669 -18.98396) (xy 141.5669 -20.06092)
			)
		)
	)
	(zone
		(layer "B.Cu")
		(hatch none 0.5)
		(connect_pads
			(clearance 0)
		)
		(min_thickness 0.25)
		(keepout
			(tracks not_allowed)
			(vias allowed)
			(pads allowed)
			(copperpour not_allowed)
			(footprints allowed)
		)
		(placement
			(enabled no)
			(sheetname "")
		)
		(fill
			(thermal_gap 0.5)
			(thermal_bridge_width 0.5)
			(island_removal_mode 0)
		)
		(polygon
			(pts
				(arc
					(start 200.600056 -22.29993)
					(mid 203.400152 -25.100026)
					(end 206.199994 -22.29993)
				)
				(arc
					(start 206.199994 -22.29993)
					(mid 203.400152 -19.500088)
					(end 200.600056 -22.29993)
				)
			)
		)
	)
	(zone
		(layer "B.Cu")
		(hatch none 0.5)
		(connect_pads
			(clearance 0)
		)
		(min_thickness 0.25)
		(keepout
			(tracks not_allowed)
			(vias allowed)
			(pads allowed)
			(copperpour not_allowed)
			(footprints allowed)
		)
		(placement
			(enabled no)
			(sheetname "")
		)
		(fill
			(thermal_gap 0.5)
			(thermal_bridge_width 0.5)
			(island_removal_mode 0)
		)
		(polygon
			(pts
				(arc
					(start 380.96444 -400.858228)
					(mid 380.26086 -400.858228)
					(end 380.96444 -400.858228)
				)
			)
		)
	)
	(zone
		(layer "B.Cu")
		(hatch none 0.5)
		(connect_pads
			(clearance 0)
		)
		(min_thickness 0.25)
		(keepout
			(tracks not_allowed)
			(vias allowed)
			(pads allowed)
			(copperpour not_allowed)
			(footprints allowed)
		)
		(placement
			(enabled no)
			(sheetname "")
		)
		(fill
			(thermal_gap 0.5)
			(thermal_bridge_width 0.5)
			(island_removal_mode 0)
		)
		(polygon
			(pts
				(arc
					(start 360.35869 -46.802802)
					(mid 359.65511 -46.802802)
					(end 360.35869 -46.802802)
				)
			)
		)
	)
	(zone
		(layer "B.Cu")
		(hatch none 0.5)
		(connect_pads
			(clearance 0)
		)
		(min_thickness 0.25)
		(keepout
			(tracks allowed)
			(vias allowed)
			(pads allowed)
			(copperpour allowed)
			(footprints not_allowed)
		)
		(placement
			(enabled no)
			(sheetname "")
		)
		(fill
			(thermal_gap 0.5)
			(thermal_bridge_width 0.5)
			(island_removal_mode 0)
		)
		(polygon
			(pts
				(arc
					(start 5.340096 -347.700092)
					(mid 10.340086 -352.700082)
					(end 15.340076 -347.700092)
				)
				(arc
					(start 15.340076 -347.700092)
					(mid 10.340086 -342.700102)
					(end 5.340096 -347.700092)
				)
			)
		)
	)
	(zone
		(layer "B.Cu")
		(hatch none 0.5)
		(connect_pads
			(clearance 0)
		)
		(min_thickness 0.25)
		(keepout
			(tracks not_allowed)
			(vias allowed)
			(pads allowed)
			(copperpour not_allowed)
			(footprints allowed)
		)
		(placement
			(enabled no)
			(sheetname "")
		)
		(fill
			(thermal_gap 0.5)
			(thermal_bridge_width 0.5)
			(island_removal_mode 0)
		)
		(polygon
			(pts
				(arc
					(start 64.511428 -400.858228)
					(mid 63.807848 -400.858228)
					(end 64.511428 -400.858228)
				)
			)
		)
	)
	(zone
		(layer "B.Cu")
		(hatch none 0.5)
		(connect_pads
			(clearance 0)
		)
		(min_thickness 0.25)
		(keepout
			(tracks not_allowed)
			(vias allowed)
			(pads allowed)
			(copperpour not_allowed)
			(footprints allowed)
		)
		(placement
			(enabled no)
			(sheetname "")
		)
		(fill
			(thermal_gap 0.5)
			(thermal_bridge_width 0.5)
			(island_removal_mode 0)
		)
		(polygon
			(pts
				(arc
					(start 92.080588 -400.858228)
					(mid 91.377008 -400.858228)
					(end 92.080588 -400.858228)
				)
			)
		)
	)
	(zone
		(layer "B.Cu")
		(hatch none 0.5)
		(connect_pads
			(clearance 0)
		)
		(min_thickness 0.25)
		(keepout
			(tracks not_allowed)
			(vias allowed)
			(pads allowed)
			(copperpour not_allowed)
			(footprints allowed)
		)
		(placement
			(enabled no)
			(sheetname "")
		)
		(fill
			(thermal_gap 0.5)
			(thermal_bridge_width 0.5)
			(island_removal_mode 0)
		)
		(polygon
			(pts
				(arc
					(start 43.05173 -385.575556)
					(mid 42.34815 -385.575556)
					(end 43.05173 -385.575556)
				)
			)
		)
	)
	(zone
		(layer "B.Cu")
		(hatch none 0.5)
		(connect_pads
			(clearance 0)
		)
		(min_thickness 0.25)
		(keepout
			(tracks not_allowed)
			(vias allowed)
			(pads allowed)
			(copperpour not_allowed)
			(footprints allowed)
		)
		(placement
			(enabled no)
			(sheetname "")
		)
		(fill
			(thermal_gap 0.5)
			(thermal_bridge_width 0.5)
			(island_removal_mode 0)
		)
		(polygon
			(pts
				(arc
					(start 61.448188 -400.858228)
					(mid 60.744608 -400.858228)
					(end 61.448188 -400.858228)
				)
			)
		)
	)
	(zone
		(layer "B.Cu")
		(hatch none 0.5)
		(connect_pads
			(clearance 0)
		)
		(min_thickness 0.25)
		(keepout
			(tracks allowed)
			(vias allowed)
			(pads allowed)
			(copperpour allowed)
			(footprints allowed)
		)
		(placement
			(enabled no)
			(sheetname "")
		)
		(fill
			(thermal_gap 0.5)
			(thermal_bridge_width 0.5)
			(island_removal_mode 0)
		)
		(polygon
			(pts
				(xy 132.7658 -29.3116) (xy 132.7658 -26.2128) (xy 133.5786 -26.2128) (xy 133.5786 -29.3116)
			)
		)
	)
	(zone
		(layer "B.Cu")
		(hatch none 0.5)
		(connect_pads
			(clearance 0)
		)
		(min_thickness 0.25)
		(keepout
			(tracks allowed)
			(vias allowed)
			(pads allowed)
			(copperpour allowed)
			(footprints not_allowed)
		)
		(placement
			(enabled no)
			(sheetname "")
		)
		(fill
			(thermal_gap 0.5)
			(thermal_bridge_width 0.5)
			(island_removal_mode 0)
		)
		(polygon
			(pts
				(arc
					(start 7.53999 -347.700092)
					(mid 10.340086 -350.500188)
					(end 13.139928 -347.700092)
				)
				(arc
					(start 13.139928 -347.700092)
					(mid 10.340086 -344.90025)
					(end 7.53999 -347.700092)
				)
			)
		)
	)
	(zone
		(layer "B.Cu")
		(hatch none 0.5)
		(connect_pads
			(clearance 0)
		)
		(min_thickness 0.25)
		(keepout
			(tracks allowed)
			(vias allowed)
			(pads allowed)
			(copperpour allowed)
			(footprints not_allowed)
		)
		(placement
			(enabled no)
			(sheetname "")
		)
		(fill
			(thermal_gap 0.5)
			(thermal_bridge_width 0.5)
			(island_removal_mode 0)
		)
		(polygon
			(pts
				(arc
					(start 102.283006 -47.049944)
					(mid 100.383086 -45.150024)
					(end 98.482912 -47.049944)
				)
				(arc
					(start 98.482912 -47.049944)
					(mid 100.383086 -48.950118)
					(end 102.283006 -47.049944)
				)
			)
		)
	)
	(zone
		(layer "B.Cu")
		(hatch none 0.5)
		(connect_pads
			(clearance 0)
		)
		(min_thickness 0.25)
		(keepout
			(tracks not_allowed)
			(vias allowed)
			(pads allowed)
			(copperpour not_allowed)
			(footprints allowed)
		)
		(placement
			(enabled no)
			(sheetname "")
		)
		(fill
			(thermal_gap 0.5)
			(thermal_bridge_width 0.5)
			(island_removal_mode 0)
		)
		(polygon
			(pts
				(arc
					(start 346.27947 -223.575626)
					(mid 345.62669 -223.575626)
					(end 346.27947 -223.575626)
				)
			)
		)
	)
	(zone
		(layer "B.Cu")
		(hatch none 0.5)
		(connect_pads
			(clearance 0)
		)
		(min_thickness 0.25)
		(keepout
			(tracks allowed)
			(vias allowed)
			(pads allowed)
			(copperpour allowed)
			(footprints not_allowed)
		)
		(placement
			(enabled no)
			(sheetname "")
		)
		(fill
			(thermal_gap 0.5)
			(thermal_bridge_width 0.5)
			(island_removal_mode 0)
		)
		(polygon
			(pts
				(arc
					(start 284.35554 -427.131734)
					(mid 281.188939 -433.741375)
					(end 282.271724 -440.989974)
				)
				(arc
					(start 304.828194 -440.989974)
					(mid 304.566245 -429.693253)
					(end 295.301924 -423.223436)
				)
				(arc
					(start 295.301924 -423.223436)
					(mid 285.290131 -412.465745)
					(end 284.35554 -427.131734)
				)
			)
		)
	)
	(zone
		(layer "B.Cu")
		(hatch none 0.5)
		(connect_pads
			(clearance 0)
		)
		(min_thickness 0.25)
		(keepout
			(tracks not_allowed)
			(vias allowed)
			(pads allowed)
			(copperpour not_allowed)
			(footprints allowed)
		)
		(placement
			(enabled no)
			(sheetname "")
		)
		(fill
			(thermal_gap 0.5)
			(thermal_bridge_width 0.5)
			(island_removal_mode 0)
		)
		(polygon
			(pts
				(arc
					(start 333.247238 -407.00452)
					(mid 332.543658 -407.00452)
					(end 333.247238 -407.00452)
				)
			)
		)
	)
	(zone
		(layer "B.Cu")
		(hatch none 0.5)
		(connect_pads
			(clearance 0)
		)
		(min_thickness 0.25)
		(keepout
			(tracks allowed)
			(vias allowed)
			(pads allowed)
			(copperpour allowed)
			(footprints allowed)
		)
		(placement
			(enabled no)
			(sheetname "")
		)
		(fill
			(thermal_gap 0.5)
			(thermal_bridge_width 0.5)
			(island_removal_mode 0)
		)
		(polygon
			(pts
				(xy 144.23898 -26.54046) (xy 144.23898 -25.55748) (xy 145.72742 -25.55748) (xy 145.72742 -26.54046)
			)
		)
	)
	(zone
		(layer "B.Cu")
		(hatch none 0.5)
		(connect_pads
			(clearance 0)
		)
		(min_thickness 0.25)
		(keepout
			(tracks allowed)
			(vias allowed)
			(pads allowed)
			(copperpour allowed)
			(footprints allowed)
		)
		(placement
			(enabled no)
			(sheetname "")
		)
		(fill
			(thermal_gap 0.5)
			(thermal_bridge_width 0.5)
			(island_removal_mode 0)
		)
		(polygon
			(pts
				(xy 328.193908 -39.315136) (xy 328.193908 -53.495956) (xy 327.685908 -54.003956) (xy 327.685908 -56.734456)
				(xy 328.193908 -57.242456) (xy 329.740768 -58.789316) (xy 337.233768 -58.789316) (xy 337.848448 -59.403996)
				(xy 347.442028 -59.403996) (xy 348.841568 -58.004456) (xy 348.841568 -54.816756) (xy 348.841568 -53.63464)
				(xy 349.04172 -53.434488) (xy 350.65716 -53.434488) (xy 351.08388 -53.007768) (xy 351.08388 -52.197508)
				(xy 350.75876 -51.872388) (xy 348.971108 -51.872388) (xy 348.841568 -51.742848) (xy 348.841568 -39.899336)
				(xy 348.176088 -39.233856) (xy 346.042488 -39.233856) (xy 345.481148 -39.795196) (xy 344.361008 -39.795196)
				(xy 343.799668 -39.233856) (xy 337.381088 -39.233856) (xy 335.918048 -37.770816) (xy 331.460348 -37.770816)
				(xy 331.460348 -37.806376) (xy 330.832968 -38.433756) (xy 329.075288 -38.433756)
			)
		)
	)
	(zone
		(layer "B.Cu")
		(hatch none 0.5)
		(connect_pads
			(clearance 0)
		)
		(min_thickness 0.25)
		(keepout
			(tracks allowed)
			(vias allowed)
			(pads allowed)
			(copperpour allowed)
			(footprints allowed)
		)
		(placement
			(enabled no)
			(sheetname "")
		)
		(fill
			(thermal_gap 0.5)
			(thermal_bridge_width 0.5)
			(island_removal_mode 0)
		)
		(polygon
			(pts
				(xy 356.17404 -44.45762) (xy 356.17404 -43.2562) (xy 361.19308 -43.2562) (xy 361.19308 -44.45762)
			)
		)
	)
	(zone
		(layer "B.Cu")
		(hatch none 0.5)
		(connect_pads
			(clearance 0)
		)
		(min_thickness 0.25)
		(keepout
			(tracks allowed)
			(vias allowed)
			(pads allowed)
			(copperpour allowed)
			(footprints not_allowed)
		)
		(placement
			(enabled no)
			(sheetname "")
		)
		(fill
			(thermal_gap 0.5)
			(thermal_bridge_width 0.5)
			(island_removal_mode 0)
		)
		(polygon
			(pts
				(arc
					(start 231.650032 -192.499996)
					(mid 236.650022 -197.499986)
					(end 241.650012 -192.499996)
				)
				(arc
					(start 241.650012 -192.499996)
					(mid 236.650022 -187.500006)
					(end 231.650032 -192.499996)
				)
			)
		)
	)
	(zone
		(layer "B.Cu")
		(hatch none 0.5)
		(connect_pads
			(clearance 0)
		)
		(min_thickness 0.25)
		(keepout
			(tracks allowed)
			(vias allowed)
			(pads allowed)
			(copperpour allowed)
			(footprints not_allowed)
		)
		(placement
			(enabled no)
			(sheetname "")
		)
		(fill
			(thermal_gap 0.5)
			(thermal_bridge_width 0.5)
			(island_removal_mode 0)
		)
		(polygon
			(pts
				(arc
					(start 361.359958 -431.360072)
					(mid 359.774998 -429.775112)
					(end 358.190038 -431.360072)
				)
				(arc
					(start 358.190038 -431.360072)
					(mid 359.774998 -432.945032)
					(end 361.359958 -431.360072)
				)
			)
		)
	)
	(zone
		(layer "B.Cu")
		(hatch none 0.5)
		(connect_pads
			(clearance 0)
		)
		(min_thickness 0.25)
		(keepout
			(tracks allowed)
			(vias allowed)
			(pads allowed)
			(copperpour allowed)
			(footprints allowed)
		)
		(placement
			(enabled no)
			(sheetname "")
		)
		(fill
			(thermal_gap 0.5)
			(thermal_bridge_width 0.5)
			(island_removal_mode 0)
		)
		(polygon
			(pts
				(xy 381.999744 -342.797892) (xy 383.338324 -342.797892) (xy 383.732024 -343.191592) (xy 383.732024 -345.406472)
				(xy 383.922524 -345.596972) (xy 387.468364 -345.596972) (xy 387.684264 -345.812872) (xy 387.684264 -347.974412)
				(xy 387.524244 -348.134432) (xy 382.088644 -348.134432) (xy 381.644144 -347.689932) (xy 381.644144 -343.153492)
			)
		)
	)
	(zone
		(layer "B.Cu")
		(hatch none 0.5)
		(connect_pads
			(clearance 0)
		)
		(min_thickness 0.25)
		(keepout
			(tracks not_allowed)
			(vias allowed)
			(pads allowed)
			(copperpour not_allowed)
			(footprints allowed)
		)
		(placement
			(enabled no)
			(sheetname "")
		)
		(fill
			(thermal_gap 0.5)
			(thermal_bridge_width 0.5)
			(island_removal_mode 0)
		)
		(polygon
			(pts
				(arc
					(start 96.929956 -224.389442)
					(mid 96.277176 -224.389442)
					(end 96.929956 -224.389442)
				)
			)
		)
	)
	(zone
		(layer "B.Cu")
		(hatch none 0.5)
		(connect_pads
			(clearance 0)
		)
		(min_thickness 0.25)
		(keepout
			(tracks allowed)
			(vias allowed)
			(pads allowed)
			(copperpour allowed)
			(footprints allowed)
		)
		(placement
			(enabled no)
			(sheetname "")
		)
		(fill
			(thermal_gap 0.5)
			(thermal_bridge_width 0.5)
			(island_removal_mode 0)
		)
		(polygon
			(pts
				(xy 126.09322 -27.673808) (xy 126.09322 -24.889968) (xy 126.9619 -24.889968) (xy 126.9619 -27.673808)
			)
		)
	)
	(zone
		(layer "B.Cu")
		(hatch none 0.5)
		(connect_pads
			(clearance 0)
		)
		(min_thickness 0.25)
		(keepout
			(tracks not_allowed)
			(vias allowed)
			(pads allowed)
			(copperpour not_allowed)
			(footprints allowed)
		)
		(placement
			(enabled no)
			(sheetname "")
		)
		(fill
			(thermal_gap 0.5)
			(thermal_bridge_width 0.5)
			(island_removal_mode 0)
		)
		(polygon
			(pts
				(arc
					(start 130.292602 -223.575626)
					(mid 129.639822 -223.575626)
					(end 130.292602 -223.575626)
				)
			)
		)
	)
	(zone
		(layer "B.Cu")
		(hatch none 0.5)
		(connect_pads
			(clearance 0)
		)
		(min_thickness 0.25)
		(keepout
			(tracks allowed)
			(vias allowed)
			(pads allowed)
			(copperpour allowed)
			(footprints allowed)
		)
		(placement
			(enabled no)
			(sheetname "")
		)
		(fill
			(thermal_gap 0.5)
			(thermal_bridge_width 0.5)
			(island_removal_mode 0)
		)
		(polygon
			(pts
				(xy 364.08106 -64.3509) (xy 364.08106 -63.0682) (xy 362.7628 -63.0682) (xy 362.7628 -64.3509)
			)
		)
	)
	(zone
		(layer "B.Cu")
		(hatch none 0.5)
		(connect_pads
			(clearance 0)
		)
		(min_thickness 0.25)
		(keepout
			(tracks not_allowed)
			(vias allowed)
			(pads allowed)
			(copperpour not_allowed)
			(footprints allowed)
		)
		(placement
			(enabled no)
			(sheetname "")
		)
		(fill
			(thermal_gap 0.5)
			(thermal_bridge_width 0.5)
			(island_removal_mode 0)
		)
		(polygon
			(pts
				(arc
					(start 394.081 -400.858228)
					(mid 393.37742 -400.858228)
					(end 394.081 -400.858228)
				)
			)
		)
	)
	(zone
		(layer "B.Cu")
		(hatch none 0.5)
		(connect_pads
			(clearance 0)
		)
		(min_thickness 0.25)
		(keepout
			(tracks not_allowed)
			(vias allowed)
			(pads allowed)
			(copperpour not_allowed)
			(footprints allowed)
		)
		(placement
			(enabled no)
			(sheetname "")
		)
		(fill
			(thermal_gap 0.5)
			(thermal_bridge_width 0.5)
			(island_removal_mode 0)
		)
		(polygon
			(pts
				(arc
					(start 23.024846 -382.933194)
					(mid 22.321266 -382.933194)
					(end 23.024846 -382.933194)
				)
			)
		)
	)
	(zone
		(layer "B.Cu")
		(hatch none 0.5)
		(connect_pads
			(clearance 0)
		)
		(min_thickness 0.25)
		(keepout
			(tracks allowed)
			(vias allowed)
			(pads allowed)
			(copperpour allowed)
			(footprints allowed)
		)
		(placement
			(enabled no)
			(sheetname "")
		)
		(fill
			(thermal_gap 0.5)
			(thermal_bridge_width 0.5)
			(island_removal_mode 0)
		)
		(polygon
			(pts
				(xy 104.152446 -366.099852) (xy 115.003326 -366.099852) (xy 117.134386 -363.968792) (xy 117.134386 -353.524312)
				(xy 103.794306 -353.524312) (xy 101.957886 -355.360732) (xy 101.957886 -363.905292)
			)
		)
	)
	(zone
		(layer "B.Cu")
		(hatch none 0.5)
		(connect_pads
			(clearance 0)
		)
		(min_thickness 0.25)
		(keepout
			(tracks not_allowed)
			(vias allowed)
			(pads allowed)
			(copperpour not_allowed)
			(footprints allowed)
		)
		(placement
			(enabled no)
			(sheetname "")
		)
		(fill
			(thermal_gap 0.5)
			(thermal_bridge_width 0.5)
			(island_removal_mode 0)
		)
		(polygon
			(pts
				(arc
					(start 130.560064 -400.858228)
					(mid 129.856484 -400.858228)
					(end 130.560064 -400.858228)
				)
			)
		)
	)
	(zone
		(layer "B.Cu")
		(hatch none 0.5)
		(connect_pads
			(clearance 0)
		)
		(min_thickness 0.25)
		(keepout
			(tracks allowed)
			(vias allowed)
			(pads allowed)
			(copperpour allowed)
			(footprints allowed)
		)
		(placement
			(enabled no)
			(sheetname "")
		)
		(fill
			(thermal_gap 0.5)
			(thermal_bridge_width 0.5)
			(island_removal_mode 0)
		)
		(polygon
			(pts
				(xy 386.70992 -347.734128) (xy 386.70992 -343.865708) (xy 381.80264 -343.865708) (xy 381.80264 -347.734128)
			)
		)
	)
	(zone
		(layer "B.Cu")
		(hatch none 0.5)
		(connect_pads
			(clearance 0)
		)
		(min_thickness 0.25)
		(keepout
			(tracks allowed)
			(vias allowed)
			(pads allowed)
			(copperpour allowed)
			(footprints allowed)
		)
		(placement
			(enabled no)
			(sheetname "")
		)
		(fill
			(thermal_gap 0.5)
			(thermal_bridge_width 0.5)
			(island_removal_mode 0)
		)
		(polygon
			(pts
				(xy 416.17646 -163.904168) (xy 416.17646 -166.276528) (xy 420.243 -166.276528) (xy 420.243 -161.707068)
				(xy 418.0459 -163.904168)
			)
		)
	)
	(zone
		(layer "B.Cu")
		(hatch none 0.5)
		(connect_pads
			(clearance 0)
		)
		(min_thickness 0.25)
		(keepout
			(tracks allowed)
			(vias allowed)
			(pads allowed)
			(copperpour allowed)
			(footprints allowed)
		)
		(placement
			(enabled no)
			(sheetname "")
		)
		(fill
			(thermal_gap 0.5)
			(thermal_bridge_width 0.5)
			(island_removal_mode 0)
		)
		(polygon
			(pts
				(xy 244.02034 -80.30972) (xy 244.02034 -79.27848) (xy 245.71706 -79.27848) (xy 245.71706 -80.30972)
			)
		)
	)
	(zone
		(layer "B.Cu")
		(hatch none 0.5)
		(connect_pads
			(clearance 0)
		)
		(min_thickness 0.25)
		(keepout
			(tracks not_allowed)
			(vias allowed)
			(pads allowed)
			(copperpour not_allowed)
			(footprints allowed)
		)
		(placement
			(enabled no)
			(sheetname "")
		)
		(fill
			(thermal_gap 0.5)
			(thermal_bridge_width 0.5)
			(island_removal_mode 0)
		)
		(polygon
			(pts
				(arc
					(start 411.59684 -400.858228)
					(mid 410.89326 -400.858228)
					(end 411.59684 -400.858228)
				)
			)
		)
	)
	(zone
		(layer "B.Cu")
		(hatch none 0.5)
		(connect_pads
			(clearance 0)
		)
		(min_thickness 0.25)
		(keepout
			(tracks allowed)
			(vias allowed)
			(pads allowed)
			(copperpour allowed)
			(footprints not_allowed)
		)
		(placement
			(enabled no)
			(sheetname "")
		)
		(fill
			(thermal_gap 0.5)
			(thermal_bridge_width 0.5)
			(island_removal_mode 0)
		)
		(polygon
			(pts
				(xy 462.639918 -239.860074) (xy 462.639918 -202.360022) (xy 407.640028 -202.360022) (xy 407.640028 -239.860074)
			)
		)
	)
	(zone
		(layer "B.Cu")
		(hatch none 0.5)
		(connect_pads
			(clearance 0)
		)
		(min_thickness 0.25)
		(keepout
			(tracks not_allowed)
			(vias allowed)
			(pads allowed)
			(copperpour not_allowed)
			(footprints allowed)
		)
		(placement
			(enabled no)
			(sheetname "")
		)
		(fill
			(thermal_gap 0.5)
			(thermal_bridge_width 0.5)
			(island_removal_mode 0)
		)
		(polygon
			(pts
				(arc
					(start 37.318442 -385.412996)
					(mid 36.614862 -385.412996)
					(end 37.318442 -385.412996)
				)
			)
		)
	)
	(zone
		(layer "B.Cu")
		(hatch none 0.5)
		(connect_pads
			(clearance 0)
		)
		(min_thickness 0.25)
		(keepout
			(tracks not_allowed)
			(vias allowed)
			(pads allowed)
			(copperpour not_allowed)
			(footprints allowed)
		)
		(placement
			(enabled no)
			(sheetname "")
		)
		(fill
			(thermal_gap 0.5)
			(thermal_bridge_width 0.5)
			(island_removal_mode 0)
		)
		(polygon
			(pts
				(arc
					(start 198.399908 -22.29993)
					(mid 203.399898 -27.29992)
					(end 208.399888 -22.29993)
				)
				(arc
					(start 208.399888 -22.29993)
					(mid 203.399898 -17.29994)
					(end 198.399908 -22.29993)
				)
			)
		)
	)
	(zone
		(layer "B.Cu")
		(hatch none 0.5)
		(connect_pads
			(clearance 0)
		)
		(min_thickness 0.25)
		(keepout
			(tracks allowed)
			(vias allowed)
			(pads allowed)
			(copperpour allowed)
			(footprints not_allowed)
		)
		(placement
			(enabled no)
			(sheetname "")
		)
		(fill
			(thermal_gap 0.5)
			(thermal_bridge_width 0.5)
			(island_removal_mode 0)
		)
		(polygon
			(pts
				(xy 8.839962 -239.860074) (xy 63.840106 -239.860074) (xy 63.840106 -202.360022) (xy 8.839962 -202.360022)
			)
		)
	)
	(zone
		(layer "B.Cu")
		(hatch none 0.5)
		(connect_pads
			(clearance 0)
		)
		(min_thickness 0.25)
		(keepout
			(tracks allowed)
			(vias allowed)
			(pads allowed)
			(copperpour allowed)
			(footprints not_allowed)
		)
		(placement
			(enabled no)
			(sheetname "")
		)
		(fill
			(thermal_gap 0.5)
			(thermal_bridge_width 0.5)
			(island_removal_mode 0)
		)
		(polygon
			(pts
				(arc
					(start 456.000104 -435.600094)
					(mid 458.8002 -438.40019)
					(end 461.600042 -435.600094)
				)
				(arc
					(start 461.600042 -435.600094)
					(mid 458.8002 -432.800252)
					(end 456.000104 -435.600094)
				)
			)
		)
	)
	(zone
		(layer "B.Cu")
		(hatch none 0.5)
		(connect_pads
			(clearance 0)
		)
		(min_thickness 0.25)
		(keepout
			(tracks allowed)
			(vias allowed)
			(pads allowed)
			(copperpour allowed)
			(footprints allowed)
		)
		(placement
			(enabled no)
			(sheetname "")
		)
		(fill
			(thermal_gap 0.5)
			(thermal_bridge_width 0.5)
			(island_removal_mode 0)
		)
		(polygon
			(pts
				(xy 361.77982 -58.64352) (xy 361.77982 -56.85282) (xy 363.32922 -56.85282) (xy 363.32922 -58.64352)
			)
		)
	)
	(zone
		(layer "B.Cu")
		(hatch none 0.5)
		(connect_pads
			(clearance 0)
		)
		(min_thickness 0.25)
		(keepout
			(tracks not_allowed)
			(vias allowed)
			(pads allowed)
			(copperpour not_allowed)
			(footprints allowed)
		)
		(placement
			(enabled no)
			(sheetname "")
		)
		(fill
			(thermal_gap 0.5)
			(thermal_bridge_width 0.5)
			(island_removal_mode 0)
		)
		(polygon
			(pts
				(arc
					(start 19.635978 -396.842996)
					(mid 18.932398 -396.842996)
					(end 19.635978 -396.842996)
				)
			)
		)
	)
	(zone
		(layer "B.Cu")
		(hatch none 0.5)
		(connect_pads
			(clearance 0)
		)
		(min_thickness 0.25)
		(keepout
			(tracks not_allowed)
			(vias allowed)
			(pads allowed)
			(copperpour not_allowed)
			(footprints allowed)
		)
		(placement
			(enabled no)
			(sheetname "")
		)
		(fill
			(thermal_gap 0.5)
			(thermal_bridge_width 0.5)
			(island_removal_mode 0)
		)
		(polygon
			(pts
				(arc
					(start 344.870024 -224.389442)
					(mid 344.217244 -224.389442)
					(end 344.870024 -224.389442)
				)
			)
		)
	)
	(zone
		(layer "B.Cu")
		(hatch none 0.5)
		(connect_pads
			(clearance 0)
		)
		(min_thickness 0.25)
		(keepout
			(tracks allowed)
			(vias allowed)
			(pads allowed)
			(copperpour allowed)
			(footprints allowed)
		)
		(placement
			(enabled no)
			(sheetname "")
		)
		(fill
			(thermal_gap 0.5)
			(thermal_bridge_width 0.5)
			(island_removal_mode 0)
		)
		(polygon
			(pts
				(xy 352.734626 -367.849912) (xy 352.734626 -367.105692) (xy 353.951286 -367.105692) (xy 353.951286 -367.849912)
			)
		)
	)
	(zone
		(layer "B.Cu")
		(hatch none 0.5)
		(connect_pads
			(clearance 0)
		)
		(min_thickness 0.25)
		(keepout
			(tracks not_allowed)
			(vias allowed)
			(pads allowed)
			(copperpour not_allowed)
			(footprints allowed)
		)
		(placement
			(enabled no)
			(sheetname "")
		)
		(fill
			(thermal_gap 0.5)
			(thermal_bridge_width 0.5)
			(island_removal_mode 0)
		)
		(polygon
			(pts
				(arc
					(start 82.890868 -400.858228)
					(mid 82.187288 -400.858228)
					(end 82.890868 -400.858228)
				)
			)
		)
	)
	(zone
		(layer "B.Cu")
		(hatch none 0.5)
		(connect_pads
			(clearance 0)
		)
		(min_thickness 0.25)
		(keepout
			(tracks not_allowed)
			(vias allowed)
			(pads allowed)
			(copperpour not_allowed)
			(footprints allowed)
		)
		(placement
			(enabled no)
			(sheetname "")
		)
		(fill
			(thermal_gap 0.5)
			(thermal_bridge_width 0.5)
			(island_removal_mode 0)
		)
		(polygon
			(pts
				(arc
					(start 99.279202 -225.203258)
					(mid 98.626422 -225.203258)
					(end 99.279202 -225.203258)
				)
			)
		)
	)
	(zone
		(layer "B.Cu")
		(hatch none 0.5)
		(connect_pads
			(clearance 0)
		)
		(min_thickness 0.25)
		(keepout
			(tracks not_allowed)
			(vias allowed)
			(pads allowed)
			(copperpour not_allowed)
			(footprints allowed)
		)
		(placement
			(enabled no)
			(sheetname "")
		)
		(fill
			(thermal_gap 0.5)
			(thermal_bridge_width 0.5)
			(island_removal_mode 0)
		)
		(polygon
			(pts
				(arc
					(start 384.89128 -400.858228)
					(mid 384.1877 -400.858228)
					(end 384.89128 -400.858228)
				)
			)
		)
	)
	(zone
		(layer "B.Cu")
		(hatch none 0.5)
		(connect_pads
			(clearance 0)
		)
		(min_thickness 0.25)
		(keepout
			(tracks not_allowed)
			(vias allowed)
			(pads allowed)
			(copperpour not_allowed)
			(footprints allowed)
		)
		(placement
			(enabled no)
			(sheetname "")
		)
		(fill
			(thermal_gap 0.5)
			(thermal_bridge_width 0.5)
			(island_removal_mode 0)
		)
		(polygon
			(pts
				(arc
					(start 342.436958 -407.00452)
					(mid 341.733378 -407.00452)
					(end 342.436958 -407.00452)
				)
			)
		)
	)
	(zone
		(layer "B.Cu")
		(hatch none 0.5)
		(connect_pads
			(clearance 0)
		)
		(min_thickness 0.25)
		(keepout
			(tracks allowed)
			(vias allowed)
			(pads allowed)
			(copperpour allowed)
			(footprints allowed)
		)
		(placement
			(enabled no)
			(sheetname "")
		)
		(fill
			(thermal_gap 0.5)
			(thermal_bridge_width 0.5)
			(island_removal_mode 0)
		)
		(polygon
			(pts
				(xy 128.6256 -27.775408) (xy 128.6256 -24.991568) (xy 129.49428 -24.991568) (xy 129.49428 -27.775408)
			)
		)
	)
	(zone
		(layer "B.Cu")
		(hatch none 0.5)
		(connect_pads
			(clearance 0)
		)
		(min_thickness 0.25)
		(keepout
			(tracks allowed)
			(vias allowed)
			(pads allowed)
			(copperpour allowed)
			(footprints not_allowed)
		)
		(placement
			(enabled no)
			(sheetname "")
		)
		(fill
			(thermal_gap 0.5)
			(thermal_bridge_width 0.5)
			(island_removal_mode 0)
		)
		(polygon
			(pts
				(arc
					(start 85.914738 -353.525074)
					(mid 81.914746 -349.525082)
					(end 77.914754 -353.525074)
				)
				(arc
					(start 77.914754 -353.525074)
					(mid 81.914746 -357.525066)
					(end 85.914738 -353.525074)
				)
			)
		)
	)
	(zone
		(layer "B.Cu")
		(hatch none 0.5)
		(connect_pads
			(clearance 0)
		)
		(min_thickness 0.25)
		(keepout
			(tracks not_allowed)
			(vias allowed)
			(pads allowed)
			(copperpour not_allowed)
			(footprints allowed)
		)
		(placement
			(enabled no)
			(sheetname "")
		)
		(fill
			(thermal_gap 0.5)
			(thermal_bridge_width 0.5)
			(island_removal_mode 0)
		)
		(polygon
			(pts
				(arc
					(start 405.47036 -400.858228)
					(mid 404.76678 -400.858228)
					(end 405.47036 -400.858228)
				)
			)
		)
	)
	(zone
		(layer "B.Cu")
		(hatch none 0.5)
		(connect_pads
			(clearance 0)
		)
		(min_thickness 0.25)
		(keepout
			(tracks allowed)
			(vias allowed)
			(pads allowed)
			(copperpour allowed)
			(footprints allowed)
		)
		(placement
			(enabled no)
			(sheetname "")
		)
		(fill
			(thermal_gap 0.5)
			(thermal_bridge_width 0.5)
			(island_removal_mode 0)
		)
		(polygon
			(pts
				(xy 143.60906 -23.98776) (xy 143.60906 -22.90064) (xy 145.36166 -22.90064) (xy 145.36166 -23.98776)
			)
		)
	)
	(zone
		(layer "B.Cu")
		(hatch none 0.5)
		(connect_pads
			(clearance 0)
		)
		(min_thickness 0.25)
		(keepout
			(tracks not_allowed)
			(vias allowed)
			(pads allowed)
			(copperpour not_allowed)
			(footprints allowed)
		)
		(placement
			(enabled no)
			(sheetname "")
		)
		(fill
			(thermal_gap 0.5)
			(thermal_bridge_width 0.5)
			(island_removal_mode 0)
		)
		(polygon
			(pts
				(arc
					(start 351.448624 -224.389442)
					(mid 350.795844 -224.389442)
					(end 351.448624 -224.389442)
				)
			)
		)
	)
	(zone
		(layer "B.Cu")
		(hatch none 0.5)
		(connect_pads
			(clearance 0)
		)
		(min_thickness 0.25)
		(keepout
			(tracks allowed)
			(vias allowed)
			(pads allowed)
			(copperpour allowed)
			(footprints not_allowed)
		)
		(placement
			(enabled no)
			(sheetname "")
		)
		(fill
			(thermal_gap 0.5)
			(thermal_bridge_width 0.5)
			(island_removal_mode 0)
		)
		(polygon
			(pts
				(xy 312.040016 -273.02206) (xy 257.040126 -273.02206) (xy 257.040126 -310.522112) (xy 312.040016 -310.522112)
			)
		)
	)
	(zone
		(layer "B.Cu")
		(hatch none 0.5)
		(connect_pads
			(clearance 0)
		)
		(min_thickness 0.25)
		(keepout
			(tracks allowed)
			(vias allowed)
			(pads allowed)
			(copperpour allowed)
			(footprints not_allowed)
		)
		(placement
			(enabled no)
			(sheetname "")
		)
		(fill
			(thermal_gap 0.5)
			(thermal_bridge_width 0.5)
			(island_removal_mode 0)
		)
		(polygon
			(pts
				(arc
					(start 366.298734 -435.600094)
					(mid 371.298724 -440.600084)
					(end 376.298714 -435.600094)
				)
				(arc
					(start 376.298714 -435.600094)
					(mid 371.298724 -430.600104)
					(end 366.298734 -435.600094)
				)
			)
		)
	)
	(zone
		(layer "B.Cu")
		(hatch none 0.5)
		(connect_pads
			(clearance 0)
		)
		(min_thickness 0.25)
		(keepout
			(tracks not_allowed)
			(vias allowed)
			(pads allowed)
			(copperpour not_allowed)
			(footprints allowed)
		)
		(placement
			(enabled no)
			(sheetname "")
		)
		(fill
			(thermal_gap 0.5)
			(thermal_bridge_width 0.5)
			(island_removal_mode 0)
		)
		(polygon
			(pts
				(arc
					(start 375.899934 -22.29993)
					(mid 380.899924 -27.29992)
					(end 385.899914 -22.29993)
				)
				(arc
					(start 385.899914 -22.29993)
					(mid 380.899924 -17.29994)
					(end 375.899934 -22.29993)
				)
			)
		)
	)
	(zone
		(layer "B.Cu")
		(hatch none 0.5)
		(connect_pads
			(clearance 0)
		)
		(min_thickness 0.25)
		(keepout
			(tracks not_allowed)
			(vias allowed)
			(pads allowed)
			(copperpour not_allowed)
			(footprints allowed)
		)
		(placement
			(enabled no)
			(sheetname "")
		)
		(fill
			(thermal_gap 0.5)
			(thermal_bridge_width 0.5)
			(island_removal_mode 0)
		)
		(polygon
			(pts
				(arc
					(start 5.340096 -160.50006)
					(mid 10.340086 -165.50005)
					(end 15.340076 -160.50006)
				)
				(arc
					(start 15.340076 -160.50006)
					(mid 10.340086 -155.50007)
					(end 5.340096 -160.50006)
				)
			)
		)
	)
	(zone
		(layer "B.Cu")
		(hatch none 0.5)
		(connect_pads
			(clearance 0)
		)
		(min_thickness 0.25)
		(keepout
			(tracks not_allowed)
			(vias allowed)
			(pads allowed)
			(copperpour not_allowed)
			(footprints allowed)
		)
		(placement
			(enabled no)
			(sheetname "")
		)
		(fill
			(thermal_gap 0.5)
			(thermal_bridge_width 0.5)
			(island_removal_mode 0)
		)
		(polygon
			(pts
				(arc
					(start 263.649968 -22.29993)
					(mid 265.649964 -24.299926)
					(end 267.64996 -22.29993)
				)
				(arc
					(start 267.64996 -22.29993)
					(mid 265.649964 -20.299934)
					(end 263.649968 -22.29993)
				)
			)
		)
	)
	(zone
		(layer "B.Cu")
		(hatch none 0.5)
		(connect_pads
			(clearance 0)
		)
		(min_thickness 0.25)
		(keepout
			(tracks allowed)
			(vias allowed)
			(pads allowed)
			(copperpour allowed)
			(footprints not_allowed)
		)
		(placement
			(enabled no)
			(sheetname "")
		)
		(fill
			(thermal_gap 0.5)
			(thermal_bridge_width 0.5)
			(island_removal_mode 0)
		)
		(polygon
			(pts
				(arc
					(start 95.500444 -435.600094)
					(mid 100.500434 -440.600084)
					(end 105.500424 -435.600094)
				)
				(arc
					(start 105.500424 -435.600094)
					(mid 100.500434 -430.600104)
					(end 95.500444 -435.600094)
				)
			)
		)
	)
	(zone
		(layer "B.Cu")
		(hatch none 0.5)
		(connect_pads
			(clearance 0)
		)
		(min_thickness 0.25)
		(keepout
			(tracks not_allowed)
			(vias allowed)
			(pads allowed)
			(copperpour not_allowed)
			(footprints allowed)
		)
		(placement
			(enabled no)
			(sheetname "")
		)
		(fill
			(thermal_gap 0.5)
			(thermal_bridge_width 0.5)
			(island_removal_mode 0)
		)
		(polygon
			(pts
				(arc
					(start 48.331628 -400.858228)
					(mid 47.628048 -400.858228)
					(end 48.331628 -400.858228)
				)
			)
		)
	)
	(zone
		(layer "B.Cu")
		(hatch none 0.5)
		(connect_pads
			(clearance 0)
		)
		(min_thickness 0.25)
		(keepout
			(tracks not_allowed)
			(vias allowed)
			(pads allowed)
			(copperpour not_allowed)
			(footprints allowed)
		)
		(placement
			(enabled no)
			(sheetname "")
		)
		(fill
			(thermal_gap 0.5)
			(thermal_bridge_width 0.5)
			(island_removal_mode 0)
		)
		(polygon
			(pts
				(arc
					(start 338.291424 -224.389442)
					(mid 337.638644 -224.389442)
					(end 338.291424 -224.389442)
				)
			)
		)
	)
	(zone
		(layer "B.Cu")
		(hatch none 0.5)
		(connect_pads
			(clearance 0)
		)
		(min_thickness 0.25)
		(keepout
			(tracks allowed)
			(vias allowed)
			(pads allowed)
			(copperpour allowed)
			(footprints not_allowed)
		)
		(placement
			(enabled no)
			(sheetname "")
		)
		(fill
			(thermal_gap 0.5)
			(thermal_bridge_width 0.5)
			(island_removal_mode 0)
		)
		(polygon
			(pts
				(arc
					(start 224.14992 -192.499996)
					(mid 236.650022 -205.000098)
					(end 249.150124 -192.499996)
				)
				(arc
					(start 249.150124 -192.499996)
					(mid 236.650022 -179.999894)
					(end 224.14992 -192.499996)
				)
			)
		)
	)
	(zone
		(layer "B.Cu")
		(hatch none 0.5)
		(connect_pads
			(clearance 0)
		)
		(min_thickness 0.25)
		(keepout
			(tracks not_allowed)
			(vias allowed)
			(pads allowed)
			(copperpour not_allowed)
			(footprints allowed)
		)
		(placement
			(enabled no)
			(sheetname "")
		)
		(fill
			(thermal_gap 0.5)
			(thermal_bridge_width 0.5)
			(island_removal_mode 0)
		)
		(polygon
			(pts
				(arc
					(start 125.123956 -224.389442)
					(mid 124.471176 -224.389442)
					(end 125.123956 -224.389442)
				)
			)
		)
	)
	(zone
		(layer "B.Cu")
		(hatch none 0.5)
		(connect_pads
			(clearance 0)
		)
		(min_thickness 0.25)
		(keepout
			(tracks not_allowed)
			(vias allowed)
			(pads allowed)
			(copperpour not_allowed)
			(footprints allowed)
		)
		(placement
			(enabled no)
			(sheetname "")
		)
		(fill
			(thermal_gap 0.5)
			(thermal_bridge_width 0.5)
			(island_removal_mode 0)
		)
		(polygon
			(pts
				(arc
					(start 340.237318 -407.00452)
					(mid 339.533738 -407.00452)
					(end 340.237318 -407.00452)
				)
			)
		)
	)
	(zone
		(layer "B.Cu")
		(hatch none 0.5)
		(connect_pads
			(clearance 0)
		)
		(min_thickness 0.25)
		(keepout
			(tracks not_allowed)
			(vias allowed)
			(pads allowed)
			(copperpour not_allowed)
			(footprints allowed)
		)
		(placement
			(enabled no)
			(sheetname "")
		)
		(fill
			(thermal_gap 0.5)
			(thermal_bridge_width 0.5)
			(island_removal_mode 0)
		)
		(polygon
			(pts
				(arc
					(start 350.97847 -225.203258)
					(mid 350.32569 -225.203258)
					(end 350.97847 -225.203258)
				)
			)
		)
	)
	(zone
		(layer "B.Cu")
		(hatch none 0.5)
		(connect_pads
			(clearance 0)
		)
		(min_thickness 0.25)
		(keepout
			(tracks allowed)
			(vias allowed)
			(pads allowed)
			(copperpour allowed)
			(footprints allowed)
		)
		(placement
			(enabled no)
			(sheetname "")
		)
		(fill
			(thermal_gap 0.5)
			(thermal_bridge_width 0.5)
			(island_removal_mode 0)
		)
		(polygon
			(pts
				(xy 182.25262 -53.16728) (xy 182.25262 -52.16144) (xy 183.58104 -52.16144) (xy 183.58104 -53.16728)
			)
		)
	)
	(zone
		(layer "B.Cu")
		(hatch none 0.5)
		(connect_pads
			(clearance 0)
		)
		(min_thickness 0.25)
		(keepout
			(tracks allowed)
			(vias allowed)
			(pads allowed)
			(copperpour allowed)
			(footprints not_allowed)
		)
		(placement
			(enabled no)
			(sheetname "")
		)
		(fill
			(thermal_gap 0.5)
			(thermal_bridge_width 0.5)
			(island_removal_mode 0)
		)
		(polygon
			(pts
				(arc
					(start 200.600056 -22.29993)
					(mid 203.400152 -25.100026)
					(end 206.199994 -22.29993)
				)
				(arc
					(start 206.199994 -22.29993)
					(mid 203.400152 -19.500088)
					(end 200.600056 -22.29993)
				)
			)
		)
	)
	(zone
		(layer "B.Cu")
		(hatch none 0.5)
		(connect_pads
			(clearance 0)
		)
		(min_thickness 0.25)
		(keepout
			(tracks allowed)
			(vias allowed)
			(pads allowed)
			(copperpour allowed)
			(footprints not_allowed)
		)
		(placement
			(enabled no)
			(sheetname "")
		)
		(fill
			(thermal_gap 0.5)
			(thermal_bridge_width 0.5)
			(island_removal_mode 0)
		)
		(polygon
			(pts
				(arc
					(start 238.949992 -39.425118)
					(mid 239.94999 -40.425116)
					(end 240.949988 -39.425118)
				)
				(arc
					(start 240.949988 -39.425118)
					(mid 239.94999 -38.42512)
					(end 238.949992 -39.425118)
				)
			)
		)
	)
	(zone
		(layer "B.Cu")
		(hatch none 0.5)
		(connect_pads
			(clearance 0)
		)
		(min_thickness 0.25)
		(keepout
			(tracks allowed)
			(vias allowed)
			(pads allowed)
			(copperpour allowed)
			(footprints not_allowed)
		)
		(placement
			(enabled no)
			(sheetname "")
		)
		(fill
			(thermal_gap 0.5)
			(thermal_bridge_width 0.5)
			(island_removal_mode 0)
		)
		(polygon
			(pts
				(arc
					(start 101.745034 -292.775894)
					(mid 100.684286 -293.21527)
					(end 100.24491 -294.276018)
				)
				(arc
					(start 100.24491 -295.566084)
					(mid 100.684286 -296.626832)
					(end 101.745034 -297.065954)
				)
				(arc
					(start 122.115072 -297.065954)
					(mid 123.17564 -296.626652)
					(end 123.614942 -295.566084)
				)
				(arc
					(start 123.614942 -294.276018)
					(mid 123.17564 -293.21545)
					(end 122.115072 -292.775894)
				)
			)
		)
	)
	(zone
		(layer "B.Cu")
		(hatch none 0.5)
		(connect_pads
			(clearance 0)
		)
		(min_thickness 0.25)
		(keepout
			(tracks allowed)
			(vias allowed)
			(pads allowed)
			(copperpour allowed)
			(footprints allowed)
		)
		(placement
			(enabled no)
			(sheetname "")
		)
		(fill
			(thermal_gap 0.5)
			(thermal_bridge_width 0.5)
			(island_removal_mode 0)
		)
		(polygon
			(pts
				(xy 181.13502 -56.73344) (xy 181.13502 -55.69458) (xy 183.23052 -55.69458) (xy 183.23052 -56.73344)
			)
		)
	)
	(zone
		(layer "B.Cu")
		(hatch none 0.5)
		(connect_pads
			(clearance 0)
		)
		(min_thickness 0.25)
		(keepout
			(tracks allowed)
			(vias allowed)
			(pads allowed)
			(copperpour allowed)
			(footprints not_allowed)
		)
		(placement
			(enabled no)
			(sheetname "")
		)
		(fill
			(thermal_gap 0.5)
			(thermal_bridge_width 0.5)
			(island_removal_mode 0)
		)
		(polygon
			(pts
				(arc
					(start 328.254868 -353.525074)
					(mid 329.854814 -355.12502)
					(end 331.45476 -353.525074)
				)
				(arc
					(start 331.45476 -353.525074)
					(mid 329.854814 -351.925128)
					(end 328.254868 -353.525074)
				)
			)
		)
	)
	(zone
		(layer "B.Cu")
		(hatch none 0.5)
		(connect_pads
			(clearance 0)
		)
		(min_thickness 0.25)
		(keepout
			(tracks allowed)
			(vias allowed)
			(pads allowed)
			(copperpour allowed)
			(footprints not_allowed)
		)
		(placement
			(enabled no)
			(sheetname "")
		)
		(fill
			(thermal_gap 0.5)
			(thermal_bridge_width 0.5)
			(island_removal_mode 0)
		)
		(polygon
			(pts
				(arc
					(start 233.849926 -272.50009)
					(mid 236.650022 -275.300186)
					(end 239.450118 -272.50009)
				)
				(arc
					(start 239.450118 -272.50009)
					(mid 236.650022 -269.699994)
					(end 233.849926 -272.50009)
				)
			)
		)
	)
	(zone
		(layer "B.Cu")
		(hatch none 0.5)
		(connect_pads
			(clearance 0)
		)
		(min_thickness 0.25)
		(keepout
			(tracks allowed)
			(vias allowed)
			(pads allowed)
			(copperpour allowed)
			(footprints not_allowed)
		)
		(placement
			(enabled no)
			(sheetname "")
		)
		(fill
			(thermal_gap 0.5)
			(thermal_bridge_width 0.5)
			(island_removal_mode 0)
		)
		(polygon
			(pts
				(xy 214.739982 -273.02206) (xy 159.740092 -273.02206) (xy 159.740092 -310.522112) (xy 214.739982 -310.522112)
			)
		)
	)
	(zone
		(layer "B.Cu")
		(hatch none 0.5)
		(connect_pads
			(clearance 0)
		)
		(min_thickness 0.25)
		(keepout
			(tracks allowed)
			(vias allowed)
			(pads allowed)
			(copperpour allowed)
			(footprints allowed)
		)
		(placement
			(enabled no)
			(sheetname "")
		)
		(fill
			(thermal_gap 0.5)
			(thermal_bridge_width 0.5)
			(island_removal_mode 0)
		)
		(polygon
			(pts
				(xy 51.55184 -358.315768) (xy 51.55184 -355.112828) (xy 47.45736 -355.112828) (xy 47.45736 -358.315768)
			)
		)
	)
	(zone
		(layer "B.Cu")
		(hatch none 0.5)
		(connect_pads
			(clearance 0)
		)
		(min_thickness 0.25)
		(keepout
			(tracks allowed)
			(vias allowed)
			(pads allowed)
			(copperpour allowed)
			(footprints not_allowed)
		)
		(placement
			(enabled no)
			(sheetname "")
		)
		(fill
			(thermal_gap 0.5)
			(thermal_bridge_width 0.5)
			(island_removal_mode 0)
		)
		(polygon
			(pts
				(arc
					(start 378.100082 -22.29993)
					(mid 380.900178 -25.100026)
					(end 383.70002 -22.29993)
				)
				(arc
					(start 383.70002 -22.29993)
					(mid 380.900178 -19.500088)
					(end 378.100082 -22.29993)
				)
			)
		)
	)
	(zone
		(layer "B.Cu")
		(hatch none 0.5)
		(connect_pads
			(clearance 0)
		)
		(min_thickness 0.25)
		(keepout
			(tracks not_allowed)
			(vias allowed)
			(pads allowed)
			(copperpour not_allowed)
			(footprints allowed)
		)
		(placement
			(enabled no)
			(sheetname "")
		)
		(fill
			(thermal_gap 0.5)
			(thermal_bridge_width 0.5)
			(island_removal_mode 0)
		)
		(polygon
			(pts
				(arc
					(start 101.158802 -225.203258)
					(mid 100.506022 -225.203258)
					(end 101.158802 -225.203258)
				)
			)
		)
	)
	(zone
		(layer "B.Cu")
		(hatch none 0.5)
		(connect_pads
			(clearance 0)
		)
		(min_thickness 0.25)
		(keepout
			(tracks not_allowed)
			(vias allowed)
			(pads allowed)
			(copperpour not_allowed)
			(footprints allowed)
		)
		(placement
			(enabled no)
			(sheetname "")
		)
		(fill
			(thermal_gap 0.5)
			(thermal_bridge_width 0.5)
			(island_removal_mode 0)
		)
		(polygon
			(pts
				(arc
					(start 113.609882 -431.360072)
					(mid 112.024922 -429.775112)
					(end 110.439962 -431.360072)
				)
				(arc
					(start 110.439962 -431.360072)
					(mid 112.024922 -432.945032)
					(end 113.609882 -431.360072)
				)
			)
		)
	)
	(zone
		(layer "B.Cu")
		(hatch none 0.5)
		(connect_pads
			(clearance 0)
		)
		(min_thickness 0.25)
		(keepout
			(tracks allowed)
			(vias allowed)
			(pads allowed)
			(copperpour allowed)
			(footprints allowed)
		)
		(placement
			(enabled no)
			(sheetname "")
		)
		(fill
			(thermal_gap 0.5)
			(thermal_bridge_width 0.5)
			(island_removal_mode 0)
		)
		(polygon
			(pts
				(xy 358.92994 -59.1566) (xy 358.92994 -58.22188) (xy 357.67264 -58.22188) (xy 357.67264 -59.1566)
			)
		)
	)
	(zone
		(layer "B.Cu")
		(hatch none 0.5)
		(connect_pads
			(clearance 0)
		)
		(min_thickness 0.25)
		(keepout
			(tracks not_allowed)
			(vias allowed)
			(pads allowed)
			(copperpour not_allowed)
			(footprints allowed)
		)
		(placement
			(enabled no)
			(sheetname "")
		)
		(fill
			(thermal_gap 0.5)
			(thermal_bridge_width 0.5)
			(island_removal_mode 0)
		)
		(polygon
			(pts
				(xy 127.07874 -25.512268) (xy 128.60274 -25.512268) (xy 128.760982 -25.512268) (xy 128.760982 -25.354026)
				(xy 126.920498 -25.354026) (xy 126.920498 -25.512268)
			)
		)
	)
	(zone
		(layer "B.Cu")
		(hatch none 0.5)
		(connect_pads
			(clearance 0)
		)
		(min_thickness 0.25)
		(keepout
			(tracks allowed)
			(vias allowed)
			(pads allowed)
			(copperpour allowed)
			(footprints not_allowed)
		)
		(placement
			(enabled no)
			(sheetname "")
		)
		(fill
			(thermal_gap 0.5)
			(thermal_bridge_width 0.5)
			(island_removal_mode 0)
		)
		(polygon
			(pts
				(arc
					(start 66.903092 -49.022254)
					(mid 71.402756 -50.917617)
					(end 74.382884 -47.049944)
				)
				(arc
					(start 74.382884 -47.049944)
					(mid 71.402678 -43.182132)
					(end 66.903092 -45.077888)
				)
				(arc
					(start 66.903092 -45.077888)
					(mid 65.784607 -44.173293)
					(end 64.382904 -43.850052)
				)
				(arc
					(start 62.782958 -43.850052)
					(mid 59.582812 -47.050198)
					(end 62.782958 -50.25009)
				)
				(arc
					(start 64.382904 -50.25009)
					(mid 65.784579 -49.92679)
					(end 66.903092 -49.022254)
				)
			)
		)
	)
	(zone
		(layer "B.Cu")
		(hatch none 0.5)
		(connect_pads
			(clearance 0)
		)
		(min_thickness 0.25)
		(keepout
			(tracks not_allowed)
			(vias allowed)
			(pads allowed)
			(copperpour not_allowed)
			(footprints allowed)
		)
		(placement
			(enabled no)
			(sheetname "")
		)
		(fill
			(thermal_gap 0.5)
			(thermal_bridge_width 0.5)
			(island_removal_mode 0)
		)
		(polygon
			(pts
				(arc
					(start 79.827628 -400.858228)
					(mid 79.124048 -400.858228)
					(end 79.827628 -400.858228)
				)
			)
		)
	)
	(zone
		(layer "B.Cu")
		(hatch none 0.5)
		(connect_pads
			(clearance 0)
		)
		(min_thickness 0.25)
		(keepout
			(tracks not_allowed)
			(vias allowed)
			(pads allowed)
			(copperpour not_allowed)
			(footprints allowed)
		)
		(placement
			(enabled no)
			(sheetname "")
		)
		(fill
			(thermal_gap 0.5)
			(thermal_bridge_width 0.5)
			(island_removal_mode 0)
		)
		(polygon
			(pts
				(arc
					(start 354.000054 -28.450032)
					(mid 356.899972 -31.34995)
					(end 359.79989 -28.450032)
				)
				(arc
					(start 359.79989 -28.450032)
					(mid 356.899972 -25.550114)
					(end 354.000054 -28.450032)
				)
			)
		)
	)
	(zone
		(layer "B.Cu")
		(hatch none 0.5)
		(connect_pads
			(clearance 0)
		)
		(min_thickness 0.25)
		(keepout
			(tracks not_allowed)
			(vias allowed)
			(pads allowed)
			(copperpour not_allowed)
			(footprints allowed)
		)
		(placement
			(enabled no)
			(sheetname "")
		)
		(fill
			(thermal_gap 0.5)
			(thermal_bridge_width 0.5)
			(island_removal_mode 0)
		)
		(polygon
			(pts
				(arc
					(start 349.427038 -407.00452)
					(mid 348.723458 -407.00452)
					(end 349.427038 -407.00452)
				)
			)
		)
	)
	(zone
		(layer "B.Cu")
		(hatch none 0.5)
		(connect_pads
			(clearance 0)
		)
		(min_thickness 0.25)
		(keepout
			(tracks not_allowed)
			(vias allowed)
			(pads allowed)
			(copperpour not_allowed)
			(footprints allowed)
		)
		(placement
			(enabled no)
			(sheetname "")
		)
		(fill
			(thermal_gap 0.5)
			(thermal_bridge_width 0.5)
			(island_removal_mode 0)
		)
		(polygon
			(pts
				(arc
					(start 75.900788 -400.858228)
					(mid 75.197208 -400.858228)
					(end 75.900788 -400.858228)
				)
			)
		)
	)
	(zone
		(layer "B.Cu")
		(hatch none 0.5)
		(connect_pads
			(clearance 0)
		)
		(min_thickness 0.25)
		(keepout
			(tracks allowed)
			(vias allowed)
			(pads allowed)
			(copperpour allowed)
			(footprints not_allowed)
		)
		(placement
			(enabled no)
			(sheetname "")
		)
		(fill
			(thermal_gap 0.5)
			(thermal_bridge_width 0.5)
			(island_removal_mode 0)
		)
		(polygon
			(pts
				(arc
					(start 134.918958 -354.434902)
					(mid 136.518904 -356.034848)
					(end 138.11885 -354.434902)
				)
				(arc
					(start 138.11885 -354.434902)
					(mid 136.518904 -352.834956)
					(end 134.918958 -354.434902)
				)
			)
		)
	)
	(zone
		(layer "B.Cu")
		(hatch none 0.5)
		(connect_pads
			(clearance 0)
		)
		(min_thickness 0.25)
		(keepout
			(tracks allowed)
			(vias allowed)
			(pads allowed)
			(copperpour allowed)
			(footprints allowed)
		)
		(placement
			(enabled no)
			(sheetname "")
		)
		(fill
			(thermal_gap 0.5)
			(thermal_bridge_width 0.5)
			(island_removal_mode 0)
		)
		(polygon
			(pts
				(xy 215.3793 -23.50008) (xy 215.3793 -21.62302) (xy 218.01582 -21.62302) (xy 218.01582 -23.50008)
			)
		)
	)
	(zone
		(layer "B.Cu")
		(hatch none 0.5)
		(connect_pads
			(clearance 0)
		)
		(min_thickness 0.25)
		(keepout
			(tracks allowed)
			(vias allowed)
			(pads allowed)
			(copperpour allowed)
			(footprints not_allowed)
		)
		(placement
			(enabled no)
			(sheetname "")
		)
		(fill
			(thermal_gap 0.5)
			(thermal_bridge_width 0.5)
			(island_removal_mode 0)
		)
		(polygon
			(pts
				(xy 2.999994 -87.199978) (xy 2.999994 -96.19996) (xy 468.799926 -96.19996) (xy 468.799926 -87.199978)
			)
		)
	)
	(zone
		(layer "B.Cu")
		(hatch none 0.5)
		(connect_pads
			(clearance 0)
		)
		(min_thickness 0.25)
		(keepout
			(tracks not_allowed)
			(vias allowed)
			(pads allowed)
			(copperpour not_allowed)
			(footprints allowed)
		)
		(placement
			(enabled no)
			(sheetname "")
		)
		(fill
			(thermal_gap 0.5)
			(thermal_bridge_width 0.5)
			(island_removal_mode 0)
		)
		(polygon
			(pts
				(arc
					(start 38.378638 -398.65935)
					(mid 37.675058 -398.65935)
					(end 38.378638 -398.65935)
				)
			)
		)
	)
	(zone
		(layer "B.Cu")
		(hatch none 0.5)
		(connect_pads
			(clearance 0)
		)
		(min_thickness 0.25)
		(keepout
			(tracks not_allowed)
			(vias allowed)
			(pads allowed)
			(copperpour not_allowed)
			(footprints allowed)
		)
		(placement
			(enabled no)
			(sheetname "")
		)
		(fill
			(thermal_gap 0.5)
			(thermal_bridge_width 0.5)
			(island_removal_mode 0)
		)
		(polygon
			(pts
				(arc
					(start 129.822956 -224.389442)
					(mid 129.170176 -224.389442)
					(end 129.822956 -224.389442)
				)
			)
		)
	)
	(zone
		(layer "B.Cu")
		(hatch none 0.5)
		(connect_pads
			(clearance 0)
		)
		(min_thickness 0.25)
		(keepout
			(tracks not_allowed)
			(vias allowed)
			(pads allowed)
			(copperpour not_allowed)
			(footprints allowed)
		)
		(placement
			(enabled no)
			(sheetname "")
		)
		(fill
			(thermal_gap 0.5)
			(thermal_bridge_width 0.5)
			(island_removal_mode 0)
		)
		(polygon
			(pts
				(arc
					(start 358.44988 -28.450032)
					(mid 356.899972 -26.900124)
					(end 355.350064 -28.450032)
				)
				(arc
					(start 355.350064 -28.450032)
					(mid 356.899972 -29.99994)
					(end 358.44988 -28.450032)
				)
			)
		)
	)
	(zone
		(layer "B.Cu")
		(hatch none 0.5)
		(connect_pads
			(clearance 0)
		)
		(min_thickness 0.25)
		(keepout
			(tracks allowed)
			(vias allowed)
			(pads allowed)
			(copperpour allowed)
			(footprints not_allowed)
		)
		(placement
			(enabled no)
			(sheetname "")
		)
		(fill
			(thermal_gap 0.5)
			(thermal_bridge_width 0.5)
			(island_removal_mode 0)
		)
		(polygon
			(pts
				(arc
					(start 92.099892 -22.29993)
					(mid 94.899988 -25.100026)
					(end 97.700084 -22.29993)
				)
				(arc
					(start 97.700084 -22.29993)
					(mid 94.899988 -19.499834)
					(end 92.099892 -22.29993)
				)
			)
		)
	)
	(zone
		(layer "B.Cu")
		(hatch none 0.5)
		(connect_pads
			(clearance 0)
		)
		(min_thickness 0.25)
		(keepout
			(tracks not_allowed)
			(vias allowed)
			(pads allowed)
			(copperpour not_allowed)
			(footprints allowed)
		)
		(placement
			(enabled no)
			(sheetname "")
		)
		(fill
			(thermal_gap 0.5)
			(thermal_bridge_width 0.5)
			(island_removal_mode 0)
		)
		(polygon
			(pts
				(arc
					(start 371.77472 -400.858228)
					(mid 371.07114 -400.858228)
					(end 371.77472 -400.858228)
				)
			)
		)
	)
	(zone
		(layer "B.Cu")
		(hatch none 0.5)
		(connect_pads
			(clearance 0)
		)
		(min_thickness 0.25)
		(keepout
			(tracks not_allowed)
			(vias allowed)
			(pads allowed)
			(copperpour not_allowed)
			(footprints allowed)
		)
		(placement
			(enabled no)
			(sheetname "")
		)
		(fill
			(thermal_gap 0.5)
			(thermal_bridge_width 0.5)
			(island_removal_mode 0)
		)
		(polygon
			(pts
				(arc
					(start 69.774308 -400.858228)
					(mid 69.070728 -400.858228)
					(end 69.774308 -400.858228)
				)
			)
		)
	)
	(zone
		(layer "B.Cu")
		(hatch none 0.5)
		(connect_pads
			(clearance 0)
		)
		(min_thickness 0.25)
		(keepout
			(tracks not_allowed)
			(vias allowed)
			(pads allowed)
			(copperpour not_allowed)
			(footprints allowed)
		)
		(placement
			(enabled no)
			(sheetname "")
		)
		(fill
			(thermal_gap 0.5)
			(thermal_bridge_width 0.5)
			(island_removal_mode 0)
		)
		(polygon
			(pts
				(arc
					(start 234.649772 -272.499836)
					(mid 236.649768 -274.499832)
					(end 238.649764 -272.499836)
				)
				(arc
					(start 238.649764 -272.499836)
					(mid 236.649768 -270.49984)
					(end 234.649772 -272.499836)
				)
			)
		)
	)
	(zone
		(layer "B.Cu")
		(hatch none 0.5)
		(connect_pads
			(clearance 0)
		)
		(min_thickness 0.25)
		(keepout
			(tracks allowed)
			(vias allowed)
			(pads allowed)
			(copperpour allowed)
			(footprints not_allowed)
		)
		(placement
			(enabled no)
			(sheetname "")
		)
		(fill
			(thermal_gap 0.5)
			(thermal_bridge_width 0.5)
			(island_removal_mode 0)
		)
		(polygon
			(pts
				(xy 257.040126 -239.860074) (xy 312.040016 -239.860074) (xy 312.040016 -202.360022) (xy 257.040126 -202.360022)
			)
		)
	)
	(zone
		(layer "B.Cu")
		(hatch none 0.5)
		(connect_pads
			(clearance 0)
		)
		(min_thickness 0.25)
		(keepout
			(tracks allowed)
			(vias allowed)
			(pads allowed)
			(copperpour allowed)
			(footprints not_allowed)
		)
		(placement
			(enabled no)
			(sheetname "")
		)
		(fill
			(thermal_gap 0.5)
			(thermal_bridge_width 0.5)
			(island_removal_mode 0)
		)
		(polygon
			(pts
				(xy 462.639918 -310.522112) (xy 462.639918 -273.02206) (xy 407.640028 -273.02206) (xy 407.640028 -310.522112)
			)
		)
	)
	(zone
		(layer "B.Cu")
		(hatch none 0.5)
		(connect_pads
			(clearance 0)
		)
		(min_thickness 0.25)
		(keepout
			(tracks allowed)
			(vias allowed)
			(pads allowed)
			(copperpour allowed)
			(footprints not_allowed)
		)
		(placement
			(enabled no)
			(sheetname "")
		)
		(fill
			(thermal_gap 0.5)
			(thermal_bridge_width 0.5)
			(island_removal_mode 0)
		)
		(polygon
			(pts
				(xy 63.840106 -310.522112) (xy 63.840106 -273.02206) (xy 8.839962 -273.02206) (xy 8.839962 -310.522112)
			)
		)
	)
	(zone
		(layer "B.Cu")
		(hatch none 0.5)
		(connect_pads
			(clearance 0)
		)
		(min_thickness 0.25)
		(keepout
			(tracks not_allowed)
			(vias allowed)
			(pads allowed)
			(copperpour not_allowed)
			(footprints allowed)
		)
		(placement
			(enabled no)
			(sheetname "")
		)
		(fill
			(thermal_gap 0.5)
			(thermal_bridge_width 0.5)
			(island_removal_mode 0)
		)
		(polygon
			(pts
				(arc
					(start 104.448356 -224.389442)
					(mid 103.795576 -224.389442)
					(end 104.448356 -224.389442)
				)
			)
		)
	)
	(zone
		(layer "B.Cu")
		(hatch none 0.5)
		(connect_pads
			(clearance 0)
		)
		(min_thickness 0.25)
		(keepout
			(tracks not_allowed)
			(vias allowed)
			(pads allowed)
			(copperpour not_allowed)
			(footprints allowed)
		)
		(placement
			(enabled no)
			(sheetname "")
		)
		(fill
			(thermal_gap 0.5)
			(thermal_bridge_width 0.5)
			(island_removal_mode 0)
		)
		(polygon
			(pts
				(xy 127.07874 -27.196288) (xy 128.60274 -27.196288) (xy 128.760982 -27.196288) (xy 128.760982 -27.038046)
				(xy 126.920498 -27.038046) (xy 126.920498 -27.196288)
			)
		)
	)
	(zone
		(layer "B.Cu")
		(hatch none 0.5)
		(connect_pads
			(clearance 0)
		)
		(min_thickness 0.25)
		(keepout
			(tracks allowed)
			(vias allowed)
			(pads allowed)
			(copperpour allowed)
			(footprints allowed)
		)
		(placement
			(enabled no)
			(sheetname "")
		)
		(fill
			(thermal_gap 0.5)
			(thermal_bridge_width 0.5)
			(island_removal_mode 0)
		)
		(polygon
			(pts
				(xy 185.64098 -18.56232) (xy 185.64098 -17.4879) (xy 187.66282 -17.4879) (xy 187.66282 -18.56232)
			)
		)
	)
	(zone
		(layer "B.Cu")
		(hatch none 0.5)
		(connect_pads
			(clearance 0)
		)
		(min_thickness 0.25)
		(keepout
			(tracks allowed)
			(vias allowed)
			(pads allowed)
			(copperpour allowed)
			(footprints not_allowed)
		)
		(placement
			(enabled no)
			(sheetname "")
		)
		(fill
			(thermal_gap 0.5)
			(thermal_bridge_width 0.5)
			(island_removal_mode 0)
		)
		(polygon
			(pts
				(arc
					(start 388.458964 -354.434902)
					(mid 384.458972 -350.43491)
					(end 380.458726 -354.434902)
				)
				(arc
					(start 380.458726 -354.434902)
					(mid 384.458972 -358.435148)
					(end 388.458964 -354.434902)
				)
			)
		)
	)
	(zone
		(layer "B.Cu")
		(hatch none 0.5)
		(connect_pads
			(clearance 0)
		)
		(min_thickness 0.25)
		(keepout
			(tracks not_allowed)
			(vias allowed)
			(pads allowed)
			(copperpour not_allowed)
			(footprints allowed)
		)
		(placement
			(enabled no)
			(sheetname "")
		)
		(fill
			(thermal_gap 0.5)
			(thermal_bridge_width 0.5)
			(island_removal_mode 0)
		)
		(polygon
			(pts
				(arc
					(start 456.460098 -347.699838)
					(mid 461.460088 -352.699828)
					(end 466.460078 -347.699838)
				)
				(arc
					(start 466.460078 -347.699838)
					(mid 461.460088 -342.699848)
					(end 456.460098 -347.699838)
				)
			)
		)
	)
	(zone
		(layer "B.Cu")
		(hatch none 0.5)
		(connect_pads
			(clearance 0)
		)
		(min_thickness 0.25)
		(keepout
			(tracks not_allowed)
			(vias allowed)
			(pads allowed)
			(copperpour not_allowed)
			(footprints allowed)
		)
		(placement
			(enabled no)
			(sheetname "")
		)
		(fill
			(thermal_gap 0.5)
			(thermal_bridge_width 0.5)
			(island_removal_mode 0)
		)
		(polygon
			(pts
				(arc
					(start 155.065984 -400.858228)
					(mid 154.362404 -400.858228)
					(end 155.065984 -400.858228)
				)
			)
		)
	)
	(zone
		(layer "B.Cu")
		(hatch none 0.5)
		(connect_pads
			(clearance 0)
		)
		(min_thickness 0.25)
		(keepout
			(tracks allowed)
			(vias allowed)
			(pads allowed)
			(copperpour allowed)
			(footprints allowed)
		)
		(placement
			(enabled no)
			(sheetname "")
		)
		(fill
			(thermal_gap 0.5)
			(thermal_bridge_width 0.5)
			(island_removal_mode 0)
		)
		(polygon
			(pts
				(xy 356.57536 -60.96) (xy 356.57536 -60.1345) (xy 357.70312 -60.1345) (xy 357.70312 -60.96)
			)
		)
	)
	(zone
		(layer "B.Cu")
		(hatch none 0.5)
		(connect_pads
			(clearance 0)
		)
		(min_thickness 0.25)
		(keepout
			(tracks allowed)
			(vias allowed)
			(pads allowed)
			(copperpour allowed)
			(footprints not_allowed)
		)
		(placement
			(enabled no)
			(sheetname "")
		)
		(fill
			(thermal_gap 0.5)
			(thermal_bridge_width 0.5)
			(island_removal_mode 0)
		)
		(polygon
			(pts
				(arc
					(start 380.458726 -354.434902)
					(mid 384.458972 -358.435148)
					(end 388.458964 -354.434902)
				)
				(arc
					(start 388.458964 -354.434902)
					(mid 384.458972 -350.43491)
					(end 380.458726 -354.434902)
				)
			)
		)
	)
	(zone
		(layer "B.Cu")
		(hatch none 0.5)
		(connect_pads
			(clearance 0)
		)
		(min_thickness 0.25)
		(keepout
			(tracks allowed)
			(vias allowed)
			(pads allowed)
			(copperpour allowed)
			(footprints not_allowed)
		)
		(placement
			(enabled no)
			(sheetname "")
		)
		(fill
			(thermal_gap 0.5)
			(thermal_bridge_width 0.5)
			(island_removal_mode 0)
		)
		(polygon
			(pts
				(arc
					(start 64.382904 -50.25009)
					(mid 65.784579 -49.92679)
					(end 66.903092 -49.022254)
				)
				(arc
					(start 66.903092 -49.022254)
					(mid 71.402756 -50.917617)
					(end 74.382884 -47.049944)
				)
				(arc
					(start 74.382884 -47.049944)
					(mid 71.402678 -43.182132)
					(end 66.903092 -45.077888)
				)
				(arc
					(start 66.903092 -45.077888)
					(mid 65.784607 -44.173293)
					(end 64.382904 -43.850052)
				)
				(arc
					(start 62.782958 -43.850052)
					(mid 59.582812 -47.050198)
					(end 62.782958 -50.25009)
				)
			)
		)
	)
	(zone
		(layer "B.Cu")
		(hatch none 0.5)
		(connect_pads
			(clearance 0)
		)
		(min_thickness 0.25)
		(keepout
			(tracks allowed)
			(vias allowed)
			(pads allowed)
			(copperpour allowed)
			(footprints not_allowed)
		)
		(placement
			(enabled no)
			(sheetname "")
		)
		(fill
			(thermal_gap 0.5)
			(thermal_bridge_width 0.5)
			(island_removal_mode 0)
		)
		(polygon
			(pts
				(arc
					(start 283.979874 -419.999922)
					(mid 287.98012 -424.000168)
					(end 291.980112 -419.999922)
				)
				(arc
					(start 291.980112 -419.999922)
					(mid 287.98012 -415.99993)
					(end 283.979874 -419.999922)
				)
			)
		)
	)
	(zone
		(layer "B.Cu")
		(hatch none 0.5)
		(connect_pads
			(clearance 0)
		)
		(min_thickness 0.25)
		(keepout
			(tracks not_allowed)
			(vias allowed)
			(pads allowed)
			(copperpour not_allowed)
			(footprints allowed)
		)
		(placement
			(enabled no)
			(sheetname "")
		)
		(fill
			(thermal_gap 0.5)
			(thermal_bridge_width 0.5)
			(island_removal_mode 0)
		)
		(polygon
			(pts
				(arc
					(start 462.000092 -22.29993)
					(mid 464.800188 -25.100026)
					(end 467.60003 -22.29993)
				)
				(arc
					(start 467.60003 -22.29993)
					(mid 464.800188 -19.500088)
					(end 462.000092 -22.29993)
				)
			)
		)
	)
	(zone
		(layer "B.Cu")
		(hatch none 0.5)
		(connect_pads
			(clearance 0)
		)
		(min_thickness 0.25)
		(keepout
			(tracks allowed)
			(vias allowed)
			(pads allowed)
			(copperpour allowed)
			(footprints not_allowed)
		)
		(placement
			(enabled no)
			(sheetname "")
		)
		(fill
			(thermal_gap 0.5)
			(thermal_bridge_width 0.5)
			(island_removal_mode 0)
		)
		(polygon
			(pts
				(arc
					(start 5.340096 -160.50006)
					(mid 10.340086 -165.50005)
					(end 15.340076 -160.50006)
				)
				(arc
					(start 15.340076 -160.50006)
					(mid 10.340086 -155.50007)
					(end 5.340096 -160.50006)
				)
			)
		)
	)
	(zone
		(layer "B.Cu")
		(hatch none 0.5)
		(connect_pads
			(clearance 0)
		)
		(min_thickness 0.25)
		(keepout
			(tracks allowed)
			(vias allowed)
			(pads allowed)
			(copperpour allowed)
			(footprints not_allowed)
		)
		(placement
			(enabled no)
			(sheetname "")
		)
		(fill
			(thermal_gap 0.5)
			(thermal_bridge_width 0.5)
			(island_removal_mode 0)
		)
		(polygon
			(pts
				(arc
					(start 288.550096 -435.600094)
					(mid 293.550086 -440.600084)
					(end 298.550076 -435.600094)
				)
				(arc
					(start 298.550076 -435.600094)
					(mid 293.550086 -430.600104)
					(end 288.550096 -435.600094)
				)
			)
		)
	)
	(zone
		(layer "B.Cu")
		(hatch none 0.5)
		(connect_pads
			(clearance 0)
		)
		(min_thickness 0.25)
		(keepout
			(tracks allowed)
			(vias allowed)
			(pads allowed)
			(copperpour allowed)
			(footprints not_allowed)
		)
		(placement
			(enabled no)
			(sheetname "")
		)
		(fill
			(thermal_gap 0.5)
			(thermal_bridge_width 0.5)
			(island_removal_mode 0)
		)
		(polygon
			(pts
				(xy 63.840106 -239.860074) (xy 63.840106 -202.360022) (xy 8.839962 -202.360022) (xy 8.839962 -239.860074)
			)
		)
	)
	(zone
		(layer "B.Cu")
		(hatch none 0.5)
		(connect_pads
			(clearance 0)
		)
		(min_thickness 0.25)
		(keepout
			(tracks not_allowed)
			(vias allowed)
			(pads allowed)
			(copperpour not_allowed)
			(footprints allowed)
		)
		(placement
			(enabled no)
			(sheetname "")
		)
		(fill
			(thermal_gap 0.5)
			(thermal_bridge_width 0.5)
			(island_removal_mode 0)
		)
		(polygon
			(pts
				(arc
					(start 27.187144 -400.432016)
					(mid 26.483564 -400.432016)
					(end 27.187144 -400.432016)
				)
			)
		)
	)
	(zone
		(layer "B.Cu")
		(hatch none 0.5)
		(connect_pads
			(clearance 0)
		)
		(min_thickness 0.25)
		(keepout
			(tracks not_allowed)
			(vias allowed)
			(pads allowed)
			(copperpour not_allowed)
			(footprints allowed)
		)
		(placement
			(enabled no)
			(sheetname "")
		)
		(fill
			(thermal_gap 0.5)
			(thermal_bridge_width 0.5)
			(island_removal_mode 0)
		)
		(polygon
			(pts
				(arc
					(start 123.244356 -224.389442)
					(mid 122.591576 -224.389442)
					(end 123.244356 -224.389442)
				)
			)
		)
	)
	(zone
		(layer "B.Cu")
		(hatch none 0.5)
		(connect_pads
			(clearance 0)
		)
		(min_thickness 0.25)
		(keepout
			(tracks allowed)
			(vias allowed)
			(pads allowed)
			(copperpour allowed)
			(footprints not_allowed)
		)
		(placement
			(enabled no)
			(sheetname "")
		)
		(fill
			(thermal_gap 0.5)
			(thermal_bridge_width 0.5)
			(island_removal_mode 0)
		)
		(polygon
			(pts
				(arc
					(start 320.099944 -160.50006)
					(mid 322.90004 -163.300156)
					(end 325.699882 -160.50006)
				)
				(arc
					(start 325.699882 -160.50006)
					(mid 322.90004 -157.700218)
					(end 320.099944 -160.50006)
				)
			)
		)
	)
	(zone
		(layer "B.Cu")
		(hatch none 0.5)
		(connect_pads
			(clearance 0)
		)
		(min_thickness 0.25)
		(keepout
			(tracks allowed)
			(vias allowed)
			(pads allowed)
			(copperpour allowed)
			(footprints allowed)
		)
		(placement
			(enabled no)
			(sheetname "")
		)
		(fill
			(thermal_gap 0.5)
			(thermal_bridge_width 0.5)
			(island_removal_mode 0)
		)
		(polygon
			(pts
				(xy 328.193908 -39.315136) (xy 328.193908 -42.11193) (xy 325.50862 -44.797218) (xy 325.50862 -46.23562)
				(xy 325.98487 -46.71187) (xy 327.685908 -48.412908) (xy 327.685908 -54.003956) (xy 327.685908 -56.734456)
				(xy 328.193908 -57.242456) (xy 329.740768 -58.789316) (xy 337.233768 -58.789316) (xy 337.848448 -59.403996)
				(xy 347.442028 -59.403996) (xy 348.841568 -58.004456) (xy 348.841568 -54.816756) (xy 348.841568 -39.899336)
				(xy 348.176088 -39.233856) (xy 346.042488 -39.233856) (xy 345.481148 -39.795196) (xy 344.361008 -39.795196)
				(xy 343.799668 -39.233856) (xy 337.381088 -39.233856) (xy 335.918048 -37.770816) (xy 331.460348 -37.770816)
				(xy 331.460348 -37.806376) (xy 330.832968 -38.433756) (xy 329.075288 -38.433756)
			)
		)
	)
	(zone
		(layer "B.Cu")
		(hatch none 0.5)
		(connect_pads
			(clearance 0)
		)
		(min_thickness 0.25)
		(keepout
			(tracks allowed)
			(vias allowed)
			(pads allowed)
			(copperpour allowed)
			(footprints allowed)
		)
		(placement
			(enabled no)
			(sheetname "")
		)
		(fill
			(thermal_gap 0.5)
			(thermal_bridge_width 0.5)
			(island_removal_mode 0)
		)
		(polygon
			(pts
				(xy 284.80766 -367.525808) (xy 284.80766 -364.614968) (xy 288.80816 -364.614968) (xy 288.80816 -367.525808)
			)
		)
	)
	(zone
		(layer "B.Cu")
		(hatch none 0.5)
		(connect_pads
			(clearance 0)
		)
		(min_thickness 0.25)
		(keepout
			(tracks allowed)
			(vias allowed)
			(pads allowed)
			(copperpour allowed)
			(footprints allowed)
		)
		(placement
			(enabled no)
			(sheetname "")
		)
		(fill
			(thermal_gap 0.5)
			(thermal_bridge_width 0.5)
			(island_removal_mode 0)
		)
		(polygon
			(pts
				(xy 131.3434 -25.182068) (xy 131.3434 -23.785068) (xy 132.50164 -23.785068) (xy 132.50164 -25.182068)
			)
		)
	)
	(zone
		(layer "B.Cu")
		(hatch none 0.5)
		(connect_pads
			(clearance 0)
		)
		(min_thickness 0.25)
		(keepout
			(tracks not_allowed)
			(vias allowed)
			(pads allowed)
			(copperpour not_allowed)
			(footprints allowed)
		)
		(placement
			(enabled no)
			(sheetname "")
		)
		(fill
			(thermal_gap 0.5)
			(thermal_bridge_width 0.5)
			(island_removal_mode 0)
		)
		(polygon
			(pts
				(arc
					(start 456.460098 -160.50006)
					(mid 461.460088 -165.50005)
					(end 466.460078 -160.50006)
				)
				(arc
					(start 466.460078 -160.50006)
					(mid 461.460088 -155.50007)
					(end 456.460098 -160.50006)
				)
			)
		)
	)
	(zone
		(layer "B.Cu")
		(hatch none 0.5)
		(connect_pads
			(clearance 0)
		)
		(min_thickness 0.25)
		(keepout
			(tracks allowed)
			(vias allowed)
			(pads allowed)
			(copperpour allowed)
			(footprints allowed)
		)
		(placement
			(enabled no)
			(sheetname "")
		)
		(fill
			(thermal_gap 0.5)
			(thermal_bridge_width 0.5)
			(island_removal_mode 0)
		)
		(polygon
			(pts
				(xy 112.8522 -355.742748) (xy 112.8522 -353.601528) (xy 107.15752 -353.601528) (xy 107.15752 -355.742748)
			)
		)
	)
	(zone
		(layer "B.Cu")
		(hatch none 0.5)
		(connect_pads
			(clearance 0)
		)
		(min_thickness 0.25)
		(keepout
			(tracks not_allowed)
			(vias allowed)
			(pads allowed)
			(copperpour not_allowed)
			(footprints allowed)
		)
		(placement
			(enabled no)
			(sheetname "")
		)
		(fill
			(thermal_gap 0.5)
			(thermal_bridge_width 0.5)
			(island_removal_mode 0)
		)
		(polygon
			(pts
				(arc
					(start 76.764388 -400.858228)
					(mid 76.060808 -400.858228)
					(end 76.764388 -400.858228)
				)
			)
		)
	)
	(zone
		(layer "B.Cu")
		(hatch none 0.5)
		(connect_pads
			(clearance 0)
		)
		(min_thickness 0.25)
		(keepout
			(tracks allowed)
			(vias allowed)
			(pads allowed)
			(copperpour allowed)
			(footprints allowed)
		)
		(placement
			(enabled no)
			(sheetname "")
		)
		(fill
			(thermal_gap 0.5)
			(thermal_bridge_width 0.5)
			(island_removal_mode 0)
		)
		(polygon
			(pts
				(xy 337.56346 -138.049508) (xy 337.56346 -136.197848) (xy 338.80552 -136.197848) (xy 338.80552 -138.049508)
			)
		)
	)
	(zone
		(layer "B.Cu")
		(hatch none 0.5)
		(connect_pads
			(clearance 0)
		)
		(min_thickness 0.25)
		(keepout
			(tracks allowed)
			(vias allowed)
			(pads allowed)
			(copperpour allowed)
			(footprints allowed)
		)
		(placement
			(enabled no)
			(sheetname "")
		)
		(fill
			(thermal_gap 0.5)
			(thermal_bridge_width 0.5)
			(island_removal_mode 0)
		)
		(polygon
			(pts
				(xy 137.28446 -25.5016) (xy 137.28446 -24.58974) (xy 139.03706 -24.58974) (xy 139.03706 -25.5016)
			)
		)
	)
	(zone
		(layer "B.Cu")
		(hatch none 0.5)
		(connect_pads
			(clearance 0)
		)
		(min_thickness 0.25)
		(keepout
			(tracks not_allowed)
			(vias allowed)
			(pads allowed)
			(copperpour not_allowed)
			(footprints allowed)
		)
		(placement
			(enabled no)
			(sheetname "")
		)
		(fill
			(thermal_gap 0.5)
			(thermal_bridge_width 0.5)
			(island_removal_mode 0)
		)
		(polygon
			(pts
				(arc
					(start 139.749784 -400.858228)
					(mid 139.046204 -400.858228)
					(end 139.749784 -400.858228)
				)
			)
		)
	)
	(zone
		(layer "B.Cu")
		(hatch none 0.5)
		(connect_pads
			(clearance 0)
		)
		(min_thickness 0.25)
		(keepout
			(tracks allowed)
			(vias allowed)
			(pads allowed)
			(copperpour allowed)
			(footprints allowed)
		)
		(placement
			(enabled no)
			(sheetname "")
		)
		(fill
			(thermal_gap 0.5)
			(thermal_bridge_width 0.5)
			(island_removal_mode 0)
		)
		(polygon
			(pts
				(xy 20.5613 -316.349888) (xy 20.5613 -315.727588) (xy 21.18868 -315.727588) (xy 21.18868 -316.349888)
			)
		)
	)
	(zone
		(layer "B.Cu")
		(hatch none 0.5)
		(connect_pads
			(clearance 0)
		)
		(min_thickness 0.25)
		(keepout
			(tracks allowed)
			(vias allowed)
			(pads allowed)
			(copperpour allowed)
			(footprints allowed)
		)
		(placement
			(enabled no)
			(sheetname "")
		)
		(fill
			(thermal_gap 0.5)
			(thermal_bridge_width 0.5)
			(island_removal_mode 0)
		)
		(polygon
			(pts
				(xy 53.8988 -170.169332) (xy 55.392066 -170.169332) (xy 55.828946 -169.732452) (xy 55.828946 -168.157652)
				(xy 55.069486 -167.398192) (xy 51.970686 -167.398192) (xy 51.884326 -167.484552) (xy 51.884326 -169.310812)
				(xy 51.724306 -169.470832) (xy 50.225706 -169.470832) (xy 49.885346 -169.811192) (xy 48.72228 -170.974258)
				(xy 48.72228 -174.978568) (xy 49.51476 -175.771048) (xy 51.3842 -175.771048) (xy 53.36794 -173.787308)
				(xy 53.36794 -170.700192)
			)
		)
	)
	(zone
		(layer "B.Cu")
		(hatch none 0.5)
		(connect_pads
			(clearance 0)
		)
		(min_thickness 0.25)
		(keepout
			(tracks not_allowed)
			(vias allowed)
			(pads allowed)
			(copperpour not_allowed)
			(footprints allowed)
		)
		(placement
			(enabled no)
			(sheetname "")
		)
		(fill
			(thermal_gap 0.5)
			(thermal_bridge_width 0.5)
			(island_removal_mode 0)
		)
		(polygon
			(pts
				(arc
					(start 125.593602 -225.203258)
					(mid 124.940822 -225.203258)
					(end 125.593602 -225.203258)
				)
			)
		)
	)
	(zone
		(layer "B.Cu")
		(hatch none 0.5)
		(connect_pads
			(clearance 0)
		)
		(min_thickness 0.25)
		(keepout
			(tracks allowed)
			(vias allowed)
			(pads allowed)
			(copperpour allowed)
			(footprints not_allowed)
		)
		(placement
			(enabled no)
			(sheetname "")
		)
		(fill
			(thermal_gap 0.5)
			(thermal_bridge_width 0.5)
			(island_removal_mode 0)
		)
		(polygon
			(pts
				(arc
					(start 195.568316 -12.557506)
					(mid 196.124305 -12.723848)
					(end 196.701918 -12.78001)
				)
				(arc
					(start 211.500466 -12.78001)
					(mid 203.225355 -34.798634)
					(end 195.568316 -12.557506)
				)
			)
		)
	)
	(zone
		(layer "B.Cu")
		(hatch none 0.5)
		(connect_pads
			(clearance 0)
		)
		(min_thickness 0.25)
		(keepout
			(tracks allowed)
			(vias allowed)
			(pads allowed)
			(copperpour allowed)
			(footprints not_allowed)
		)
		(placement
			(enabled no)
			(sheetname "")
		)
		(fill
			(thermal_gap 0.5)
			(thermal_bridge_width 0.5)
			(island_removal_mode 0)
		)
		(polygon
			(pts
				(xy 401.376896 -191.77) (xy 318.377062 -191.77) (xy 318.377062 -311.770014) (xy 401.376896 -311.770014)
			)
		)
	)
	(zone
		(layer "B.Cu")
		(hatch none 0.5)
		(connect_pads
			(clearance 0)
		)
		(min_thickness 0.25)
		(keepout
			(tracks not_allowed)
			(vias allowed)
			(pads allowed)
			(copperpour not_allowed)
			(footprints allowed)
		)
		(placement
			(enabled no)
			(sheetname "")
		)
		(fill
			(thermal_gap 0.5)
			(thermal_bridge_width 0.5)
			(island_removal_mode 0)
		)
		(polygon
			(pts
				(arc
					(start 231.650032 -272.50009)
					(mid 236.650022 -277.50008)
					(end 241.650012 -272.50009)
				)
				(arc
					(start 241.650012 -272.50009)
					(mid 236.650022 -267.5001)
					(end 231.650032 -272.50009)
				)
			)
		)
	)
	(zone
		(layer "B.Cu")
		(hatch none 0.5)
		(connect_pads
			(clearance 0)
		)
		(min_thickness 0.25)
		(keepout
			(tracks not_allowed)
			(vias allowed)
			(pads allowed)
			(copperpour not_allowed)
			(footprints allowed)
		)
		(placement
			(enabled no)
			(sheetname "")
		)
		(fill
			(thermal_gap 0.5)
			(thermal_bridge_width 0.5)
			(island_removal_mode 0)
		)
		(polygon
			(pts
				(arc
					(start 120.424956 -224.389442)
					(mid 119.772176 -224.389442)
					(end 120.424956 -224.389442)
				)
			)
		)
	)
	(zone
		(layer "B.Cu")
		(hatch none 0.5)
		(connect_pads
			(clearance 0)
		)
		(min_thickness 0.25)
		(keepout
			(tracks not_allowed)
			(vias allowed)
			(pads allowed)
			(copperpour not_allowed)
			(footprints allowed)
		)
		(placement
			(enabled no)
			(sheetname "")
		)
		(fill
			(thermal_gap 0.5)
			(thermal_bridge_width 0.5)
			(island_removal_mode 0)
		)
		(polygon
			(pts
				(arc
					(start 162.900106 -160.50006)
					(mid 167.900096 -165.50005)
					(end 172.900086 -160.50006)
				)
				(arc
					(start 172.900086 -160.50006)
					(mid 167.900096 -155.50007)
					(end 162.900106 -160.50006)
				)
			)
		)
	)
	(zone
		(layer "B.Cu")
		(hatch none 0.5)
		(connect_pads
			(clearance 0)
		)
		(min_thickness 0.25)
		(keepout
			(tracks allowed)
			(vias allowed)
			(pads allowed)
			(copperpour allowed)
			(footprints not_allowed)
		)
		(placement
			(enabled no)
			(sheetname "")
		)
		(fill
			(thermal_gap 0.5)
			(thermal_bridge_width 0.5)
			(island_removal_mode 0)
		)
		(polygon
			(pts
				(arc
					(start 104.024938 -431.360072)
					(mid 112.024922 -439.360056)
					(end 120.024906 -431.360072)
				)
				(arc
					(start 120.024906 -431.360072)
					(mid 112.024922 -423.360088)
					(end 104.024938 -431.360072)
				)
			)
		)
	)
	(zone
		(layer "B.Cu")
		(hatch none 0.5)
		(connect_pads
			(clearance 0)
		)
		(min_thickness 0.25)
		(keepout
			(tracks allowed)
			(vias allowed)
			(pads allowed)
			(copperpour allowed)
			(footprints allowed)
		)
		(placement
			(enabled no)
			(sheetname "")
		)
		(fill
			(thermal_gap 0.5)
			(thermal_bridge_width 0.5)
			(island_removal_mode 0)
		)
		(polygon
			(pts
				(xy 357.453946 -333.45755) (xy 358.792526 -333.45755) (xy 359.186226 -333.85125) (xy 359.186226 -336.06613)
				(xy 359.376726 -336.25663) (xy 362.922566 -336.25663) (xy 363.138466 -336.47253) (xy 363.138466 -338.63407)
				(xy 362.978446 -338.79409) (xy 357.542846 -338.79409) (xy 357.098346 -338.34959) (xy 357.098346 -333.81315)
			)
		)
	)
	(zone
		(layer "B.Cu")
		(hatch none 0.5)
		(connect_pads
			(clearance 0)
		)
		(min_thickness 0.25)
		(keepout
			(tracks not_allowed)
			(vias allowed)
			(pads allowed)
			(copperpour not_allowed)
			(footprints allowed)
		)
		(placement
			(enabled no)
			(sheetname "")
		)
		(fill
			(thermal_gap 0.5)
			(thermal_bridge_width 0.5)
			(island_removal_mode 0)
		)
		(polygon
			(pts
				(arc
					(start 121.834402 -225.203258)
					(mid 121.181622 -225.203258)
					(end 121.834402 -225.203258)
				)
			)
		)
	)
	(zone
		(layer "B.Cu")
		(hatch none 0.5)
		(connect_pads
			(clearance 0)
		)
		(min_thickness 0.25)
		(keepout
			(tracks not_allowed)
			(vias allowed)
			(pads allowed)
			(copperpour not_allowed)
			(footprints allowed)
		)
		(placement
			(enabled no)
			(sheetname "")
		)
		(fill
			(thermal_gap 0.5)
			(thermal_bridge_width 0.5)
			(island_removal_mode 0)
		)
		(polygon
			(pts
				(arc
					(start 132.172202 -223.575626)
					(mid 131.519422 -223.575626)
					(end 132.172202 -223.575626)
				)
			)
		)
	)
	(zone
		(layer "B.Cu")
		(hatch none 0.5)
		(connect_pads
			(clearance 0)
		)
		(min_thickness 0.25)
		(keepout
			(tracks not_allowed)
			(vias allowed)
			(pads allowed)
			(copperpour not_allowed)
			(footprints allowed)
		)
		(placement
			(enabled no)
			(sheetname "")
		)
		(fill
			(thermal_gap 0.5)
			(thermal_bridge_width 0.5)
			(island_removal_mode 0)
		)
		(polygon
			(pts
				(arc
					(start 226.650042 -44.500038)
					(mid 228.650038 -46.500034)
					(end 230.650034 -44.500038)
				)
				(arc
					(start 230.650034 -44.500038)
					(mid 228.650038 -42.500042)
					(end 226.650042 -44.500038)
				)
			)
		)
	)
	(zone
		(layer "B.Cu")
		(hatch none 0.5)
		(connect_pads
			(clearance 0)
		)
		(min_thickness 0.25)
		(keepout
			(tracks not_allowed)
			(vias allowed)
			(pads allowed)
			(copperpour not_allowed)
			(footprints allowed)
		)
		(placement
			(enabled no)
			(sheetname "")
		)
		(fill
			(thermal_gap 0.5)
			(thermal_bridge_width 0.5)
			(island_removal_mode 0)
		)
		(polygon
			(pts
				(arc
					(start 230.89997 -81.699862)
					(mid 235.89996 -86.699852)
					(end 240.89995 -81.699862)
				)
				(arc
					(start 240.89995 -81.699862)
					(mid 235.89996 -76.699872)
					(end 230.89997 -81.699862)
				)
			)
		)
	)
	(zone
		(layer "B.Cu")
		(hatch none 0.5)
		(connect_pads
			(clearance 0)
		)
		(min_thickness 0.25)
		(keepout
			(tracks allowed)
			(vias allowed)
			(pads allowed)
			(copperpour allowed)
			(footprints not_allowed)
		)
		(placement
			(enabled no)
			(sheetname "")
		)
		(fill
			(thermal_gap 0.5)
			(thermal_bridge_width 0.5)
			(island_removal_mode 0)
		)
		(polygon
			(pts
				(arc
					(start 226.650042 -44.500038)
					(mid 228.650038 -46.500034)
					(end 230.650034 -44.500038)
				)
				(arc
					(start 230.650034 -44.500038)
					(mid 228.650038 -42.500042)
					(end 226.650042 -44.500038)
				)
			)
		)
	)
	(zone
		(layer "B.Cu")
		(hatch none 0.5)
		(connect_pads
			(clearance 0)
		)
		(min_thickness 0.25)
		(keepout
			(tracks not_allowed)
			(vias allowed)
			(pads allowed)
			(copperpour not_allowed)
			(footprints allowed)
		)
		(placement
			(enabled no)
			(sheetname "")
		)
		(fill
			(thermal_gap 0.5)
			(thermal_bridge_width 0.5)
			(island_removal_mode 0)
		)
		(polygon
			(pts
				(arc
					(start 352.85807 -225.203258)
					(mid 352.20529 -225.203258)
					(end 352.85807 -225.203258)
				)
			)
		)
	)
	(zone
		(layer "B.Cu")
		(hatch none 0.5)
		(connect_pads
			(clearance 0)
		)
		(min_thickness 0.25)
		(keepout
			(tracks allowed)
			(vias allowed)
			(pads allowed)
			(copperpour allowed)
			(footprints allowed)
		)
		(placement
			(enabled no)
			(sheetname "")
		)
		(fill
			(thermal_gap 0.5)
			(thermal_bridge_width 0.5)
			(island_removal_mode 0)
		)
		(polygon
			(pts
				(xy 15.69466 -407.3017) (xy 15.69466 -405.94788) (xy 17.399 -405.94788) (xy 17.399 -407.3017)
			)
		)
	)
	(zone
		(layer "B.Cu")
		(hatch none 0.5)
		(connect_pads
			(clearance 0)
		)
		(min_thickness 0.25)
		(keepout
			(tracks not_allowed)
			(vias allowed)
			(pads allowed)
			(copperpour not_allowed)
			(footprints allowed)
		)
		(placement
			(enabled no)
			(sheetname "")
		)
		(fill
			(thermal_gap 0.5)
			(thermal_bridge_width 0.5)
			(island_removal_mode 0)
		)
		(polygon
			(pts
				(arc
					(start 339.373718 -407.00452)
					(mid 338.670138 -407.00452)
					(end 339.373718 -407.00452)
				)
			)
		)
	)
	(zone
		(layer "B.Cu")
		(hatch none 0.5)
		(connect_pads
			(clearance 0)
		)
		(min_thickness 0.25)
		(keepout
			(tracks allowed)
			(vias allowed)
			(pads allowed)
			(copperpour allowed)
			(footprints allowed)
		)
		(placement
			(enabled no)
			(sheetname "")
		)
		(fill
			(thermal_gap 0.5)
			(thermal_bridge_width 0.5)
			(island_removal_mode 0)
		)
		(polygon
			(pts
				(xy 129.0955 -13.07592) (xy 129.0955 -11.48588) (xy 133.74624 -11.48588) (xy 133.74624 -13.07592)
			)
		)
	)
	(zone
		(layer "B.Cu")
		(hatch none 0.5)
		(connect_pads
			(clearance 0)
		)
		(min_thickness 0.25)
		(keepout
			(tracks allowed)
			(vias allowed)
			(pads allowed)
			(copperpour allowed)
			(footprints not_allowed)
		)
		(placement
			(enabled no)
			(sheetname "")
		)
		(fill
			(thermal_gap 0.5)
			(thermal_bridge_width 0.5)
			(island_removal_mode 0)
		)
		(polygon
			(pts
				(arc
					(start 265.394948 -153.766012)
					(mid 277.89505 -166.266114)
					(end 290.394898 -153.766012)
				)
				(arc
					(start 290.394898 -153.766012)
					(mid 277.89505 -141.266164)
					(end 265.394948 -153.766012)
				)
			)
		)
	)
	(zone
		(layer "B.Cu")
		(hatch none 0.5)
		(connect_pads
			(clearance 0)
		)
		(min_thickness 0.25)
		(keepout
			(tracks allowed)
			(vias allowed)
			(pads allowed)
			(copperpour allowed)
			(footprints allowed)
		)
		(placement
			(enabled no)
			(sheetname "")
		)
		(fill
			(thermal_gap 0.5)
			(thermal_bridge_width 0.5)
			(island_removal_mode 0)
		)
		(polygon
			(pts
				(xy 329.15098 -347.411548) (xy 329.15098 -343.179908) (xy 323.82968 -343.179908) (xy 323.82968 -347.411548)
			)
		)
	)
	(zone
		(layer "B.Cu")
		(hatch none 0.5)
		(connect_pads
			(clearance 0)
		)
		(min_thickness 0.25)
		(keepout
			(tracks allowed)
			(vias allowed)
			(pads allowed)
			(copperpour allowed)
			(footprints not_allowed)
		)
		(placement
			(enabled no)
			(sheetname "")
		)
		(fill
			(thermal_gap 0.5)
			(thermal_bridge_width 0.5)
			(island_removal_mode 0)
		)
		(polygon
			(pts
				(arc
					(start 186.174126 -424.87723)
					(mid 171.33592 -426.355977)
					(end 168.47185 -440.989974)
				)
				(arc
					(start 111.778542 -440.989974)
					(mid 112.130455 -440.181337)
					(end 112.424464 -439.349896)
				)
				(arc
					(start 112.424464 -439.349896)
					(mid 117.821179 -436.873722)
					(end 120.024906 -431.360072)
				)
				(arc
					(start 120.024906 -431.360072)
					(mid 115.561124 -424.184069)
					(end 107.15117 -425.016168)
				)
				(arc
					(start 107.15117 -425.016168)
					(mid 92.185132 -426.266952)
					(end 89.222072 -440.989974)
				)
				(arc
					(start 24.278082 -440.989974)
					(mid 21.795428 -426.718286)
					(end 7.500112 -424.375072)
				)
				(arc
					(start 7.500112 -409.528518)
					(mid 7.271649 -408.380426)
					(end 6.621272 -407.40711)
				)
				(arc
					(start 3.292856 -404.078694)
					(mid 3.076074 -403.754257)
					(end 2.999994 -403.371558)
				)
				(arc
					(start 2.999994 -371.291104)
					(mid 18.287657 -369.884849)
					(end 20.682204 -354.720652)
				)
				(arc
					(start 20.682204 -354.720652)
					(mid 20.644086 -340.623199)
					(end 7.500112 -335.526888)
				)
				(arc
					(start 7.500112 -167.978836)
					(mid 18.339932 -160.500105)
					(end 7.500112 -153.02103)
				)
				(xy 7.500112 -96.19996) (xy 462.799938 -96.19996)
				(arc
					(start 462.799938 -148.072094)
					(mid 458.148582 -148.446709)
					(end 453.958706 -150.501096)
				)
				(arc
					(start 453.958706 -150.501096)
					(mid 430.07429 -149.711573)
					(end 449.396358 -163.773866)
				)
				(arc
					(start 449.396358 -163.773866)
					(mid 454.41024 -170.822416)
					(end 462.799938 -172.928026)
				)
				(arc
					(start 462.799938 -335.272126)
					(mid 450.739289 -341.272019)
					(end 451.128892 -354.736908)
				)
				(arc
					(start 451.128892 -354.736908)
					(mid 452.927318 -369.277727)
					(end 467.300056 -372.121938)
				)
				(arc
					(start 467.300056 -404.871682)
					(mid 467.223955 -405.254267)
					(end 467.007194 -405.578564)
				)
				(arc
					(start 465.178648 -407.40711)
					(mid 464.528386 -408.380435)
					(end 464.300062 -409.528518)
				)
				(arc
					(start 464.300062 -424.375072)
					(mid 459.075499 -423.103142)
					(end 453.799956 -424.143678)
				)
				(arc
					(start 453.799956 -424.143678)
					(mid 445.528601 -423.535773)
					(end 438.69737 -428.23892)
				)
				(arc
					(start 438.69737 -428.23892)
					(mid 439.277182 -424.688541)
					(end 438.82183 -421.120062)
				)
				(arc
					(start 438.82183 -421.120062)
					(mid 426.779216 -405.27014)
					(end 414.73628 -421.120062)
				)
				(arc
					(start 414.73628 -421.120062)
					(mid 421.336371 -435.722912)
					(end 436.881778 -431.830988)
				)
				(arc
					(start 436.881778 -431.830988)
					(mid 436.330488 -436.471367)
					(end 437.521858 -440.989974)
				)
				(arc
					(start 382.576832 -440.989974)
					(mid 379.614138 -426.267334)
					(end 364.648496 -425.015914)
				)
				(arc
					(start 364.648496 -425.015914)
					(mid 356.238648 -424.184171)
					(end 351.775014 -431.360072)
				)
				(arc
					(start 351.775014 -431.360072)
					(mid 353.978264 -436.873475)
					(end 359.37444 -439.349896)
				)
				(arc
					(start 359.37444 -439.349896)
					(mid 359.668453 -440.181336)
					(end 360.020362 -440.989974)
				)
				(arc
					(start 304.828194 -440.989974)
					(mid 304.566245 -429.693253)
					(end 295.301924 -423.223436)
				)
				(arc
					(start 295.301924 -423.223436)
					(mid 293.96167 -414.687586)
					(end 285.643828 -412.34868)
				)
				(xy 285.643828 -405.99995) (xy 186.174126 -405.99995)
			)
		)
	)
	(zone
		(layer "B.Cu")
		(hatch none 0.5)
		(connect_pads
			(clearance 0)
		)
		(min_thickness 0.25)
		(keepout
			(tracks not_allowed)
			(vias allowed)
			(pads allowed)
			(copperpour not_allowed)
			(footprints allowed)
		)
		(placement
			(enabled no)
			(sheetname "")
		)
		(fill
			(thermal_gap 0.5)
			(thermal_bridge_width 0.5)
			(island_removal_mode 0)
		)
		(polygon
			(pts
				(arc
					(start 321.857878 -407.00452)
					(mid 321.154298 -407.00452)
					(end 321.857878 -407.00452)
				)
			)
		)
	)
	(zone
		(layer "B.Cu")
		(hatch none 0.5)
		(connect_pads
			(clearance 0)
		)
		(min_thickness 0.25)
		(keepout
			(tracks not_allowed)
			(vias allowed)
			(pads allowed)
			(copperpour not_allowed)
			(footprints allowed)
		)
		(placement
			(enabled no)
			(sheetname "")
		)
		(fill
			(thermal_gap 0.5)
			(thermal_bridge_width 0.5)
			(island_removal_mode 0)
		)
		(polygon
			(pts
				(arc
					(start 179.36337 -55.481728)
					(mid 178.65979 -55.481728)
					(end 179.36337 -55.481728)
				)
			)
		)
	)
	(zone
		(layer "B.Cu")
		(hatch none 0.5)
		(connect_pads
			(clearance 0)
		)
		(min_thickness 0.25)
		(keepout
			(tracks allowed)
			(vias allowed)
			(pads allowed)
			(copperpour allowed)
			(footprints allowed)
		)
		(placement
			(enabled no)
			(sheetname "")
		)
		(fill
			(thermal_gap 0.5)
			(thermal_bridge_width 0.5)
			(island_removal_mode 0)
		)
		(polygon
			(pts
				(xy 333.07528 -341.419688) (xy 333.07528 -338.882228) (xy 337.07832 -338.882228) (xy 337.07832 -341.419688)
			)
		)
	)
	(zone
		(layer "B.Cu")
		(hatch none 0.5)
		(connect_pads
			(clearance 0)
		)
		(min_thickness 0.25)
		(keepout
			(tracks not_allowed)
			(vias allowed)
			(pads allowed)
			(copperpour not_allowed)
			(footprints allowed)
		)
		(placement
			(enabled no)
			(sheetname "")
		)
		(fill
			(thermal_gap 0.5)
			(thermal_bridge_width 0.5)
			(island_removal_mode 0)
		)
		(polygon
			(pts
				(arc
					(start 324.057518 -407.00452)
					(mid 323.353938 -407.00452)
					(end 324.057518 -407.00452)
				)
			)
		)
	)
	(zone
		(layer "B.Cu")
		(hatch none 0.5)
		(connect_pads
			(clearance 0)
		)
		(min_thickness 0.25)
		(keepout
			(tracks allowed)
			(vias allowed)
			(pads allowed)
			(copperpour allowed)
			(footprints not_allowed)
		)
		(placement
			(enabled no)
			(sheetname "")
		)
		(fill
			(thermal_gap 0.5)
			(thermal_bridge_width 0.5)
			(island_removal_mode 0)
		)
		(polygon
			(pts
				(arc
					(start 107.15117 -425.016168)
					(mid 92.185132 -426.266952)
					(end 89.222072 -440.989974)
				)
				(arc
					(start 111.778542 -440.989974)
					(mid 112.130455 -440.181337)
					(end 112.424464 -439.349896)
				)
				(arc
					(start 112.424464 -439.349896)
					(mid 106.511272 -437.156329)
					(end 104.024938 -431.360072)
				)
				(arc
					(start 104.024938 -431.360072)
					(mid 104.848991 -427.823919)
					(end 107.15117 -425.016168)
				)
			)
		)
	)
	(zone
		(layer "B.Cu")
		(hatch none 0.5)
		(connect_pads
			(clearance 0)
		)
		(min_thickness 0.25)
		(keepout
			(tracks allowed)
			(vias allowed)
			(pads allowed)
			(copperpour allowed)
			(footprints allowed)
		)
		(placement
			(enabled no)
			(sheetname "")
		)
		(fill
			(thermal_gap 0.5)
			(thermal_bridge_width 0.5)
			(island_removal_mode 0)
		)
		(polygon
			(pts
				(xy 153.28138 -39.51986) (xy 153.28138 -35.61334) (xy 152.09012 -35.61334) (xy 152.09012 -39.51986)
			)
		)
	)
	(zone
		(layer "B.Cu")
		(hatch none 0.5)
		(connect_pads
			(clearance 0)
		)
		(min_thickness 0.25)
		(keepout
			(tracks allowed)
			(vias allowed)
			(pads allowed)
			(copperpour allowed)
			(footprints not_allowed)
		)
		(placement
			(enabled no)
			(sheetname "")
		)
		(fill
			(thermal_gap 0.5)
			(thermal_bridge_width 0.5)
			(island_removal_mode 0)
		)
		(polygon
			(pts
				(arc
					(start 310.399938 -160.50006)
					(mid 322.90004 -173.000162)
					(end 335.399888 -160.50006)
				)
				(arc
					(start 335.399888 -160.50006)
					(mid 322.90004 -148.000212)
					(end 310.399938 -160.50006)
				)
			)
		)
	)
	(zone
		(layer "B.Cu")
		(hatch none 0.5)
		(connect_pads
			(clearance 0)
		)
		(min_thickness 0.25)
		(keepout
			(tracks not_allowed)
			(vias allowed)
			(pads allowed)
			(copperpour not_allowed)
			(footprints allowed)
		)
		(placement
			(enabled no)
			(sheetname "")
		)
		(fill
			(thermal_gap 0.5)
			(thermal_bridge_width 0.5)
			(island_removal_mode 0)
		)
		(polygon
			(pts
				(arc
					(start 464.25993 -347.700092)
					(mid 461.460088 -344.90025)
					(end 458.659992 -347.700092)
				)
				(arc
					(start 458.659992 -347.700092)
					(mid 461.460088 -350.500188)
					(end 464.25993 -347.700092)
				)
			)
		)
	)
	(zone
		(layer "B.Cu")
		(hatch none 0.5)
		(connect_pads
			(clearance 0)
		)
		(min_thickness 0.25)
		(keepout
			(tracks allowed)
			(vias allowed)
			(pads allowed)
			(copperpour allowed)
			(footprints allowed)
		)
		(placement
			(enabled no)
			(sheetname "")
		)
		(fill
			(thermal_gap 0.5)
			(thermal_bridge_width 0.5)
			(island_removal_mode 0)
		)
		(polygon
			(pts
				(xy 415.96056 -181.145688) (xy 415.96056 -183.518048) (xy 420.0271 -183.518048) (xy 420.0271 -178.948588)
				(xy 417.83 -181.145688)
			)
		)
	)
	(zone
		(layer "B.Cu")
		(hatch none 0.5)
		(connect_pads
			(clearance 0)
		)
		(min_thickness 0.25)
		(keepout
			(tracks allowed)
			(vias allowed)
			(pads allowed)
			(copperpour allowed)
			(footprints not_allowed)
		)
		(placement
			(enabled no)
			(sheetname "")
		)
		(fill
			(thermal_gap 0.5)
			(thermal_bridge_width 0.5)
			(island_removal_mode 0)
		)
		(polygon
			(pts
				(xy 214.739982 -310.522112) (xy 214.739982 -273.02206) (xy 159.740092 -273.02206) (xy 159.740092 -310.522112)
			)
		)
	)
	(zone
		(layer "B.Cu")
		(hatch none 0.5)
		(connect_pads
			(clearance 0)
		)
		(min_thickness 0.25)
		(keepout
			(tracks allowed)
			(vias allowed)
			(pads allowed)
			(copperpour allowed)
			(footprints allowed)
		)
		(placement
			(enabled no)
			(sheetname "")
		)
		(fill
			(thermal_gap 0.5)
			(thermal_bridge_width 0.5)
			(island_removal_mode 0)
		)
		(polygon
			(pts
				(xy 183.22036 -404.40864) (xy 183.22036 -401.01012) (xy 185.8772 -401.01012) (xy 185.8772 -404.40864)
			)
		)
	)
	(zone
		(layer "B.Cu")
		(hatch none 0.5)
		(connect_pads
			(clearance 0)
		)
		(min_thickness 0.25)
		(keepout
			(tracks not_allowed)
			(vias allowed)
			(pads allowed)
			(copperpour not_allowed)
			(footprints allowed)
		)
		(placement
			(enabled no)
			(sheetname "")
		)
		(fill
			(thermal_gap 0.5)
			(thermal_bridge_width 0.5)
			(island_removal_mode 0)
		)
		(polygon
			(pts
				(arc
					(start 233.849926 -192.499996)
					(mid 236.650022 -195.300092)
					(end 239.450118 -192.499996)
				)
				(arc
					(start 239.450118 -192.499996)
					(mid 236.650022 -189.6999)
					(end 233.849926 -192.499996)
				)
			)
		)
	)
	(zone
		(layer "B.Cu")
		(hatch none 0.5)
		(connect_pads
			(clearance 0)
		)
		(min_thickness 0.25)
		(keepout
			(tracks allowed)
			(vias allowed)
			(pads allowed)
			(copperpour allowed)
			(footprints allowed)
		)
		(placement
			(enabled no)
			(sheetname "")
		)
		(fill
			(thermal_gap 0.5)
			(thermal_bridge_width 0.5)
			(island_removal_mode 0)
		)
		(polygon
			(pts
				(xy 42.32148 -358.419908) (xy 42.32148 -354.345748) (xy 37.64534 -354.345748) (xy 37.64534 -358.419908)
			)
		)
	)
	(zone
		(layer "B.Cu")
		(hatch none 0.5)
		(connect_pads
			(clearance 0)
		)
		(min_thickness 0.25)
		(keepout
			(tracks not_allowed)
			(vias allowed)
			(pads allowed)
			(copperpour not_allowed)
			(footprints allowed)
		)
		(placement
			(enabled no)
			(sheetname "")
		)
		(fill
			(thermal_gap 0.5)
			(thermal_bridge_width 0.5)
			(island_removal_mode 0)
		)
		(polygon
			(pts
				(arc
					(start 201.895456 -51.999896)
					(mid 204.645514 -54.749954)
					(end 207.395318 -51.999896)
				)
				(arc
					(start 207.395318 -51.999896)
					(mid 204.645514 -49.250092)
					(end 201.895456 -51.999896)
				)
			)
		)
	)
	(zone
		(layer "B.Cu")
		(hatch none 0.5)
		(connect_pads
			(clearance 0)
		)
		(min_thickness 0.25)
		(keepout
			(tracks not_allowed)
			(vias allowed)
			(pads allowed)
			(copperpour not_allowed)
			(footprints allowed)
		)
		(placement
			(enabled no)
			(sheetname "")
		)
		(fill
			(thermal_gap 0.5)
			(thermal_bridge_width 0.5)
			(island_removal_mode 0)
		)
		(polygon
			(pts
				(arc
					(start 92.700602 -223.575626)
					(mid 92.047822 -223.575626)
					(end 92.700602 -223.575626)
				)
			)
		)
	)
	(zone
		(layer "B.Cu")
		(hatch none 0.5)
		(connect_pads
			(clearance 0)
		)
		(min_thickness 0.25)
		(keepout
			(tracks not_allowed)
			(vias allowed)
			(pads allowed)
			(copperpour not_allowed)
			(footprints allowed)
		)
		(placement
			(enabled no)
			(sheetname "")
		)
		(fill
			(thermal_gap 0.5)
			(thermal_bridge_width 0.5)
			(island_removal_mode 0)
		)
		(polygon
			(pts
				(arc
					(start 370.71427 -223.575626)
					(mid 370.06149 -223.575626)
					(end 370.71427 -223.575626)
				)
			)
		)
	)
	(zone
		(layer "B.Cu")
		(hatch none 0.5)
		(connect_pads
			(clearance 0)
		)
		(min_thickness 0.25)
		(keepout
			(tracks allowed)
			(vias allowed)
			(pads allowed)
			(copperpour allowed)
			(footprints allowed)
		)
		(placement
			(enabled no)
			(sheetname "")
		)
		(fill
			(thermal_gap 0.5)
			(thermal_bridge_width 0.5)
			(island_removal_mode 0)
		)
		(polygon
			(pts
				(xy 333.15148 -38.197028) (xy 333.15148 -33.419288) (xy 335.92516 -33.419288) (xy 335.92516 -38.197028)
			)
		)
	)
	(zone
		(layer "B.Cu")
		(hatch none 0.5)
		(connect_pads
			(clearance 0)
		)
		(min_thickness 0.25)
		(keepout
			(tracks allowed)
			(vias allowed)
			(pads allowed)
			(copperpour allowed)
			(footprints allowed)
		)
		(placement
			(enabled no)
			(sheetname "")
		)
		(fill
			(thermal_gap 0.5)
			(thermal_bridge_width 0.5)
			(island_removal_mode 0)
		)
		(polygon
			(pts
				(xy 341.48522 -333.45755) (xy 342.8238 -333.45755) (xy 343.2175 -333.85125) (xy 343.2175 -336.06613)
				(xy 343.408 -336.25663) (xy 346.95384 -336.25663) (xy 347.16974 -336.47253) (xy 347.16974 -338.63407)
				(xy 347.00972 -338.79409) (xy 341.57412 -338.79409) (xy 341.12962 -338.34959) (xy 341.12962 -333.81315)
			)
		)
	)
	(zone
		(layer "B.Cu")
		(hatch none 0.5)
		(connect_pads
			(clearance 0)
		)
		(min_thickness 0.25)
		(keepout
			(tracks not_allowed)
			(vias allowed)
			(pads allowed)
			(copperpour not_allowed)
			(footprints allowed)
		)
		(placement
			(enabled no)
			(sheetname "")
		)
		(fill
			(thermal_gap 0.5)
			(thermal_bridge_width 0.5)
			(island_removal_mode 0)
		)
		(polygon
			(pts
				(arc
					(start 391.01776 -400.858228)
					(mid 390.31418 -400.858228)
					(end 391.01776 -400.858228)
				)
			)
		)
	)
	(zone
		(layer "B.Cu")
		(hatch none 0.5)
		(connect_pads
			(clearance 0)
		)
		(min_thickness 0.25)
		(keepout
			(tracks allowed)
			(vias allowed)
			(pads allowed)
			(copperpour allowed)
			(footprints allowed)
		)
		(placement
			(enabled no)
			(sheetname "")
		)
		(fill
			(thermal_gap 0.5)
			(thermal_bridge_width 0.5)
			(island_removal_mode 0)
		)
		(polygon
			(pts
				(xy 164.70884 -34.56686) (xy 164.70884 -33.69056) (xy 165.96614 -33.69056) (xy 165.96614 -34.56686)
			)
		)
	)
	(zone
		(layer "B.Cu")
		(hatch none 0.5)
		(connect_pads
			(clearance 0)
		)
		(min_thickness 0.25)
		(keepout
			(tracks not_allowed)
			(vias allowed)
			(pads allowed)
			(copperpour not_allowed)
			(footprints allowed)
		)
		(placement
			(enabled no)
			(sheetname "")
		)
		(fill
			(thermal_gap 0.5)
			(thermal_bridge_width 0.5)
			(island_removal_mode 0)
		)
		(polygon
			(pts
				(arc
					(start 91.216988 -400.858228)
					(mid 90.513408 -400.858228)
					(end 91.216988 -400.858228)
				)
			)
		)
	)
	(zone
		(layer "B.Cu")
		(hatch none 0.5)
		(connect_pads
			(clearance 0)
		)
		(min_thickness 0.25)
		(keepout
			(tracks allowed)
			(vias allowed)
			(pads allowed)
			(copperpour allowed)
			(footprints allowed)
		)
		(placement
			(enabled no)
			(sheetname "")
		)
		(fill
			(thermal_gap 0.5)
			(thermal_bridge_width 0.5)
			(island_removal_mode 0)
		)
		(polygon
			(pts
				(xy 247.40362 -36.85794) (xy 247.40362 -35.9918) (xy 246.59082 -35.9918) (xy 246.59082 -36.85794)
			)
		)
	)
	(zone
		(layer "B.Cu")
		(hatch none 0.5)
		(connect_pads
			(clearance 0)
		)
		(min_thickness 0.25)
		(keepout
			(tracks not_allowed)
			(vias allowed)
			(pads allowed)
			(copperpour not_allowed)
			(footprints allowed)
		)
		(placement
			(enabled no)
			(sheetname "")
		)
		(fill
			(thermal_gap 0.5)
			(thermal_bridge_width 0.5)
			(island_removal_mode 0)
		)
		(polygon
			(pts
				(arc
					(start 378.23267 -223.575626)
					(mid 377.57989 -223.575626)
					(end 378.23267 -223.575626)
				)
			)
		)
	)
	(zone
		(layer "B.Cu")
		(hatch none 0.5)
		(connect_pads
			(clearance 0)
		)
		(min_thickness 0.25)
		(keepout
			(tracks not_allowed)
			(vias allowed)
			(pads allowed)
			(copperpour not_allowed)
			(footprints allowed)
		)
		(placement
			(enabled no)
			(sheetname "")
		)
		(fill
			(thermal_gap 0.5)
			(thermal_bridge_width 0.5)
			(island_removal_mode 0)
		)
		(polygon
			(pts
				(arc
					(start 352.490278 -407.00452)
					(mid 351.786698 -407.00452)
					(end 352.490278 -407.00452)
				)
			)
		)
	)
	(zone
		(layer "B.Cu")
		(hatch none 0.5)
		(connect_pads
			(clearance 0)
		)
		(min_thickness 0.25)
		(keepout
			(tracks allowed)
			(vias allowed)
			(pads allowed)
			(copperpour allowed)
			(footprints allowed)
		)
		(placement
			(enabled no)
			(sheetname "")
		)
		(fill
			(thermal_gap 0.5)
			(thermal_bridge_width 0.5)
			(island_removal_mode 0)
		)
		(polygon
			(pts
				(xy 358.76484 -40.52316) (xy 358.76484 -38.40988) (xy 356.97922 -38.40988) (xy 356.97922 -40.52316)
			)
		)
	)
	(zone
		(layer "B.Cu")
		(hatch none 0.5)
		(connect_pads
			(clearance 0)
		)
		(min_thickness 0.25)
		(keepout
			(tracks allowed)
			(vias allowed)
			(pads allowed)
			(copperpour allowed)
			(footprints not_allowed)
		)
		(placement
			(enabled no)
			(sheetname "")
		)
		(fill
			(thermal_gap 0.5)
			(thermal_bridge_width 0.5)
			(island_removal_mode 0)
		)
		(polygon
			(pts
				(arc
					(start 80.3148 -353.525074)
					(mid 81.915 -355.125274)
					(end 83.514946 -353.525074)
				)
				(arc
					(start 83.514946 -353.525074)
					(mid 81.915 -351.925128)
					(end 80.3148 -353.525074)
				)
			)
		)
	)
	(zone
		(layer "B.Cu")
		(hatch none 0.5)
		(connect_pads
			(clearance 0)
		)
		(min_thickness 0.25)
		(keepout
			(tracks not_allowed)
			(vias allowed)
			(pads allowed)
			(copperpour not_allowed)
			(footprints allowed)
		)
		(placement
			(enabled no)
			(sheetname "")
		)
		(fill
			(thermal_gap 0.5)
			(thermal_bridge_width 0.5)
			(island_removal_mode 0)
		)
		(polygon
			(pts
				(arc
					(start 97.869756 -224.389442)
					(mid 97.216976 -224.389442)
					(end 97.869756 -224.389442)
				)
			)
		)
	)
	(zone
		(layer "B.Cu")
		(hatch none 0.5)
		(connect_pads
			(clearance 0)
		)
		(min_thickness 0.25)
		(keepout
			(tracks allowed)
			(vias allowed)
			(pads allowed)
			(copperpour allowed)
			(footprints not_allowed)
		)
		(placement
			(enabled no)
			(sheetname "")
		)
		(fill
			(thermal_gap 0.5)
			(thermal_bridge_width 0.5)
			(island_removal_mode 0)
		)
		(polygon
			(pts
				(arc
					(start 335.399888 -160.50006)
					(mid 322.90004 -148.000212)
					(end 310.399938 -160.50006)
				)
				(arc
					(start 310.399938 -160.50006)
					(mid 322.90004 -173.000162)
					(end 335.399888 -160.50006)
				)
			)
		)
	)
	(zone
		(layer "B.Cu")
		(hatch none 0.5)
		(connect_pads
			(clearance 0)
		)
		(min_thickness 0.25)
		(keepout
			(tracks allowed)
			(vias allowed)
			(pads allowed)
			(copperpour allowed)
			(footprints allowed)
		)
		(placement
			(enabled no)
			(sheetname "")
		)
		(fill
			(thermal_gap 0.5)
			(thermal_bridge_width 0.5)
			(island_removal_mode 0)
		)
		(polygon
			(pts
				(xy 12.41806 -107.24134) (xy 12.41806 -104.55148) (xy 11.48588 -104.55148) (xy 11.48588 -107.24134)
			)
		)
	)
	(zone
		(layer "B.Cu")
		(hatch none 0.5)
		(connect_pads
			(clearance 0)
		)
		(min_thickness 0.25)
		(keepout
			(tracks allowed)
			(vias allowed)
			(pads allowed)
			(copperpour allowed)
			(footprints not_allowed)
		)
		(placement
			(enabled no)
			(sheetname "")
		)
		(fill
			(thermal_gap 0.5)
			(thermal_bridge_width 0.5)
			(island_removal_mode 0)
		)
		(polygon
			(pts
				(arc
					(start 231.650032 -272.50009)
					(mid 236.650022 -277.50008)
					(end 241.650012 -272.50009)
				)
				(arc
					(start 241.650012 -272.50009)
					(mid 236.650022 -267.5001)
					(end 231.650032 -272.50009)
				)
			)
		)
	)
	(zone
		(layer "B.Cu")
		(hatch none 0.5)
		(connect_pads
			(clearance 0)
		)
		(min_thickness 0.25)
		(keepout
			(tracks not_allowed)
			(vias allowed)
			(pads allowed)
			(copperpour not_allowed)
			(footprints allowed)
		)
		(placement
			(enabled no)
			(sheetname "")
		)
		(fill
			(thermal_gap 0.5)
			(thermal_bridge_width 0.5)
			(island_removal_mode 0)
		)
		(polygon
			(pts
				(arc
					(start 94.280228 -400.858228)
					(mid 93.576648 -400.858228)
					(end 94.280228 -400.858228)
				)
			)
		)
	)
	(zone
		(layer "B.Cu")
		(hatch none 0.5)
		(connect_pads
			(clearance 0)
		)
		(min_thickness 0.25)
		(keepout
			(tracks not_allowed)
			(vias allowed)
			(pads allowed)
			(copperpour not_allowed)
			(footprints allowed)
		)
		(placement
			(enabled no)
			(sheetname "")
		)
		(fill
			(thermal_gap 0.5)
			(thermal_bridge_width 0.5)
			(island_removal_mode 0)
		)
		(polygon
			(pts
				(arc
					(start 179.36337 -54.618128)
					(mid 178.65979 -54.618128)
					(end 179.36337 -54.618128)
				)
			)
		)
	)
	(zone
		(layer "B.Cu")
		(hatch none 0.5)
		(connect_pads
			(clearance 0)
		)
		(min_thickness 0.25)
		(keepout
			(tracks not_allowed)
			(vias allowed)
			(pads allowed)
			(copperpour not_allowed)
			(footprints allowed)
		)
		(placement
			(enabled no)
			(sheetname "")
		)
		(fill
			(thermal_gap 0.5)
			(thermal_bridge_width 0.5)
			(island_removal_mode 0)
		)
		(polygon
			(pts
				(arc
					(start 179.36337 -48.61814)
					(mid 178.65979 -48.61814)
					(end 179.36337 -48.61814)
				)
			)
		)
	)
	(zone
		(layer "B.Cu")
		(hatch none 0.5)
		(connect_pads
			(clearance 0)
		)
		(min_thickness 0.25)
		(keepout
			(tracks allowed)
			(vias allowed)
			(pads allowed)
			(copperpour allowed)
			(footprints not_allowed)
		)
		(placement
			(enabled no)
			(sheetname "")
		)
		(fill
			(thermal_gap 0.5)
			(thermal_bridge_width 0.5)
			(island_removal_mode 0)
		)
		(polygon
			(pts
				(arc
					(start 276.64537 -51.999896)
					(mid 268.645386 -43.999912)
					(end 260.645402 -51.999896)
				)
				(arc
					(start 260.645402 -51.999896)
					(mid 268.645386 -59.99988)
					(end 276.64537 -51.999896)
				)
			)
		)
	)
	(zone
		(layer "B.Cu")
		(hatch none 0.5)
		(connect_pads
			(clearance 0)
		)
		(min_thickness 0.25)
		(keepout
			(tracks allowed)
			(vias allowed)
			(pads allowed)
			(copperpour allowed)
			(footprints allowed)
		)
		(placement
			(enabled no)
			(sheetname "")
		)
		(fill
			(thermal_gap 0.5)
			(thermal_bridge_width 0.5)
			(island_removal_mode 0)
		)
		(polygon
			(pts
				(xy 153.82494 -31.33344) (xy 153.82494 -30.21584) (xy 155.26766 -30.21584) (xy 155.26766 -31.33344)
			)
		)
	)
	(zone
		(layer "B.Cu")
		(hatch none 0.5)
		(connect_pads
			(clearance 0)
		)
		(min_thickness 0.25)
		(keepout
			(tracks allowed)
			(vias allowed)
			(pads allowed)
			(copperpour allowed)
			(footprints allowed)
		)
		(placement
			(enabled no)
			(sheetname "")
		)
		(fill
			(thermal_gap 0.5)
			(thermal_bridge_width 0.5)
			(island_removal_mode 0)
		)
		(polygon
			(pts
				(xy 365.67872 -333.455518) (xy 367.0173 -333.455518) (xy 367.411 -333.849218) (xy 367.411 -336.064098)
				(xy 367.6015 -336.254598) (xy 371.14734 -336.254598) (xy 371.36324 -336.470498) (xy 371.36324 -338.632038)
				(xy 371.20322 -338.792058) (xy 365.76762 -338.792058) (xy 365.32312 -338.347558) (xy 365.32312 -333.811118)
			)
		)
	)
	(zone
		(layer "B.Cu")
		(hatch none 0.5)
		(connect_pads
			(clearance 0)
		)
		(min_thickness 0.25)
		(keepout
			(tracks not_allowed)
			(vias allowed)
			(pads allowed)
			(copperpour not_allowed)
			(footprints allowed)
		)
		(placement
			(enabled no)
			(sheetname "")
		)
		(fill
			(thermal_gap 0.5)
			(thermal_bridge_width 0.5)
			(island_removal_mode 0)
		)
		(polygon
			(pts
				(arc
					(start 78.964028 -400.858228)
					(mid 78.260448 -400.858228)
					(end 78.964028 -400.858228)
				)
			)
		)
	)
	(zone
		(layers "B.Cu" "In4.Cu" "In6.Cu" "In11.Cu" "In13.Cu" "In15.Cu")
		(hatch none 0.5)
		(connect_pads
			(clearance 0)
		)
		(min_thickness 0.25)
		(keepout
			(tracks not_allowed)
			(vias allowed)
			(pads allowed)
			(copperpour not_allowed)
			(footprints allowed)
		)
		(placement
			(enabled no)
			(sheetname "")
		)
		(fill yes
			(thermal_gap 0.5)
			(thermal_bridge_width 0.5)
			(island_removal_mode 0)
		)
		(polygon
			(pts
				(arc
					(start 158.009336 -301.01667)
					(mid 157.356556 -301.01667)
					(end 158.009336 -301.01667)
				)
			)
		)
	)
	(zone
		(layers "B.Cu" "In4.Cu" "In6.Cu" "In11.Cu" "In13.Cu" "In15.Cu")
		(hatch none 0.5)
		(connect_pads
			(clearance 0)
		)
		(min_thickness 0.25)
		(keepout
			(tracks not_allowed)
			(vias allowed)
			(pads allowed)
			(copperpour not_allowed)
			(footprints allowed)
		)
		(placement
			(enabled no)
			(sheetname "")
		)
		(fill yes
			(thermal_gap 0.5)
			(thermal_bridge_width 0.5)
			(island_removal_mode 0)
		)
		(polygon
			(pts
				(arc
					(start 338.871052 -266.128246)
					(mid 338.218272 -266.128246)
					(end 338.871052 -266.128246)
				)
			)
		)
	)
	(zone
		(layers "B.Cu" "In4.Cu" "In6.Cu" "In11.Cu" "In13.Cu" "In15.Cu")
		(hatch none 0.5)
		(connect_pads
			(clearance 0)
		)
		(min_thickness 0.25)
		(keepout
			(tracks not_allowed)
			(vias allowed)
			(pads allowed)
			(copperpour not_allowed)
			(footprints allowed)
		)
		(placement
			(enabled no)
			(sheetname "")
		)
		(fill yes
			(thermal_gap 0.5)
			(thermal_bridge_width 0.5)
			(island_removal_mode 0)
		)
		(polygon
			(pts
				(arc
					(start 331.901038 -400.858228)
					(mid 331.197458 -400.858228)
					(end 331.901038 -400.858228)
				)
			)
		)
	)
	(zone
		(layers "B.Cu" "In4.Cu" "In6.Cu" "In11.Cu" "In13.Cu" "In15.Cu")
		(hatch none 0.5)
		(connect_pads
			(clearance 0)
		)
		(min_thickness 0.25)
		(keepout
			(tracks not_allowed)
			(vias allowed)
			(pads allowed)
			(copperpour not_allowed)
			(footprints allowed)
		)
		(placement
			(enabled no)
			(sheetname "")
		)
		(fill yes
			(thermal_gap 0.5)
			(thermal_bridge_width 0.5)
			(island_removal_mode 0)
		)
		(polygon
			(pts
				(arc
					(start 135.101584 -267.755878)
					(mid 134.448804 -267.755878)
					(end 135.101584 -267.755878)
				)
			)
		)
	)
	(zone
		(layers "B.Cu" "In4.Cu" "In6.Cu" "In11.Cu" "In13.Cu" "In15.Cu")
		(hatch none 0.5)
		(connect_pads
			(clearance 0)
		)
		(min_thickness 0.25)
		(keepout
			(tracks not_allowed)
			(vias allowed)
			(pads allowed)
			(copperpour not_allowed)
			(footprints allowed)
		)
		(placement
			(enabled no)
			(sheetname "")
		)
		(fill yes
			(thermal_gap 0.5)
			(thermal_bridge_width 0.5)
			(island_removal_mode 0)
		)
		(polygon
			(pts
				(arc
					(start 383.511806 -268.569694)
					(mid 382.859026 -268.569694)
					(end 383.511806 -268.569694)
				)
			)
		)
	)
	(zone
		(layers "B.Cu" "In4.Cu" "In6.Cu" "In11.Cu" "In13.Cu" "In15.Cu")
		(hatch none 0.5)
		(connect_pads
			(clearance 0)
		)
		(min_thickness 0.25)
		(keepout
			(tracks not_allowed)
			(vias allowed)
			(pads allowed)
			(copperpour not_allowed)
			(footprints allowed)
		)
		(placement
			(enabled no)
			(sheetname "")
		)
		(fill yes
			(thermal_gap 0.5)
			(thermal_bridge_width 0.5)
			(island_removal_mode 0)
		)
		(polygon
			(pts
				(arc
					(start 380.222252 -256.361438)
					(mid 379.569472 -256.361438)
					(end 380.222252 -256.361438)
				)
			)
		)
	)
	(zone
		(layers "B.Cu" "In4.Cu" "In6.Cu" "In11.Cu" "In13.Cu" "In15.Cu")
		(hatch none 0.5)
		(connect_pads
			(clearance 0)
		)
		(min_thickness 0.25)
		(keepout
			(tracks not_allowed)
			(vias allowed)
			(pads allowed)
			(copperpour not_allowed)
			(footprints allowed)
		)
		(placement
			(enabled no)
			(sheetname "")
		)
		(fill yes
			(thermal_gap 0.5)
			(thermal_bridge_width 0.5)
			(island_removal_mode 0)
		)
		(polygon
			(pts
				(arc
					(start 425.162472 -313.766708)
					(mid 424.509692 -313.766708)
					(end 425.162472 -313.766708)
				)
			)
		)
	)
	(zone
		(layers "B.Cu" "In4.Cu" "In6.Cu" "In11.Cu" "In13.Cu" "In15.Cu")
		(hatch none 0.5)
		(connect_pads
			(clearance 0)
		)
		(min_thickness 0.25)
		(keepout
			(tracks not_allowed)
			(vias allowed)
			(pads allowed)
			(copperpour not_allowed)
			(footprints allowed)
		)
		(placement
			(enabled no)
			(sheetname "")
		)
		(fill yes
			(thermal_gap 0.5)
			(thermal_bridge_width 0.5)
			(island_removal_mode 0)
		)
		(polygon
			(pts
				(arc
					(start 89.051384 -275.8948)
					(mid 88.398604 -275.8948)
					(end 89.051384 -275.8948)
				)
			)
		)
	)
	(zone
		(layers "B.Cu" "In4.Cu" "In6.Cu" "In11.Cu" "In13.Cu" "In15.Cu")
		(hatch none 0.5)
		(connect_pads
			(clearance 0)
		)
		(min_thickness 0.25)
		(keepout
			(tracks not_allowed)
			(vias allowed)
			(pads allowed)
			(copperpour not_allowed)
			(footprints allowed)
		)
		(placement
			(enabled no)
			(sheetname "")
		)
		(fill yes
			(thermal_gap 0.5)
			(thermal_bridge_width 0.5)
			(island_removal_mode 0)
		)
		(polygon
			(pts
				(arc
					(start 177.146204 -263.616694)
					(mid 176.493424 -263.616694)
					(end 177.146204 -263.616694)
				)
			)
		)
	)
	(zone
		(layers "B.Cu" "In4.Cu" "In6.Cu" "In11.Cu" "In13.Cu" "In15.Cu")
		(hatch none 0.5)
		(connect_pads
			(clearance 0)
		)
		(min_thickness 0.25)
		(keepout
			(tracks not_allowed)
			(vias allowed)
			(pads allowed)
			(copperpour not_allowed)
			(footprints allowed)
		)
		(placement
			(enabled no)
			(sheetname "")
		)
		(fill yes
			(thermal_gap 0.5)
			(thermal_bridge_width 0.5)
			(island_removal_mode 0)
		)
		(polygon
			(pts
				(arc
					(start 287.687004 -245.76659)
					(mid 287.034224 -245.76659)
					(end 287.687004 -245.76659)
				)
			)
		)
	)
	(zone
		(layers "B.Cu" "In4.Cu" "In6.Cu" "In11.Cu" "In13.Cu" "In15.Cu")
		(hatch none 0.5)
		(connect_pads
			(clearance 0)
		)
		(min_thickness 0.25)
		(keepout
			(tracks not_allowed)
			(vias allowed)
			(pads allowed)
			(copperpour not_allowed)
			(footprints allowed)
		)
		(placement
			(enabled no)
			(sheetname "")
		)
		(fill yes
			(thermal_gap 0.5)
			(thermal_bridge_width 0.5)
			(island_removal_mode 0)
		)
		(polygon
			(pts
				(arc
					(start 134.991856 -233.34218)
					(mid 134.339076 -233.34218)
					(end 134.991856 -233.34218)
				)
			)
		)
	)
	(zone
		(layers "B.Cu" "In4.Cu" "In6.Cu" "In11.Cu" "In13.Cu" "In15.Cu")
		(hatch none 0.5)
		(connect_pads
			(clearance 0)
		)
		(min_thickness 0.25)
		(keepout
			(tracks not_allowed)
			(vias allowed)
			(pads allowed)
			(copperpour not_allowed)
			(footprints allowed)
		)
		(placement
			(enabled no)
			(sheetname "")
		)
		(fill yes
			(thermal_gap 0.5)
			(thermal_bridge_width 0.5)
			(island_removal_mode 0)
		)
		(polygon
			(pts
				(arc
					(start 177.222404 -296.766742)
					(mid 176.569624 -296.766742)
					(end 177.222404 -296.766742)
				)
			)
		)
	)
	(zone
		(layers "B.Cu" "In4.Cu" "In6.Cu" "In11.Cu" "In13.Cu" "In15.Cu")
		(hatch none 0.5)
		(connect_pads
			(clearance 0)
		)
		(min_thickness 0.25)
		(keepout
			(tracks not_allowed)
			(vias allowed)
			(pads allowed)
			(copperpour not_allowed)
			(footprints allowed)
		)
		(placement
			(enabled no)
			(sheetname "")
		)
		(fill yes
			(thermal_gap 0.5)
			(thermal_bridge_width 0.5)
			(island_removal_mode 0)
		)
		(polygon
			(pts
				(arc
					(start 383.871724 -244.73662)
					(mid 383.218944 -244.73662)
					(end 383.871724 -244.73662)
				)
			)
		)
	)
	(zone
		(layers "B.Cu" "In4.Cu" "In6.Cu" "In11.Cu" "In13.Cu" "In15.Cu")
		(hatch none 0.5)
		(connect_pads
			(clearance 0)
		)
		(min_thickness 0.25)
		(keepout
			(tracks not_allowed)
			(vias allowed)
			(pads allowed)
			(copperpour not_allowed)
			(footprints allowed)
		)
		(placement
			(enabled no)
			(sheetname "")
		)
		(fill yes
			(thermal_gap 0.5)
			(thermal_bridge_width 0.5)
			(island_removal_mode 0)
		)
		(polygon
			(pts
				(arc
					(start 291.787072 -260.21665)
					(mid 291.134292 -260.21665)
					(end 291.787072 -260.21665)
				)
			)
		)
	)
	(zone
		(layers "B.Cu" "In4.Cu" "In6.Cu" "In11.Cu" "In13.Cu" "In15.Cu")
		(hatch none 0.5)
		(connect_pads
			(clearance 0)
		)
		(min_thickness 0.25)
		(keepout
			(tracks not_allowed)
			(vias allowed)
			(pads allowed)
			(copperpour not_allowed)
			(footprints allowed)
		)
		(placement
			(enabled no)
			(sheetname "")
		)
		(fill yes
			(thermal_gap 0.5)
			(thermal_bridge_width 0.5)
			(island_removal_mode 0)
		)
		(polygon
			(pts
				(arc
					(start 405.949404 -230.466646)
					(mid 405.296624 -230.466646)
					(end 405.949404 -230.466646)
				)
			)
		)
	)
	(zone
		(layers "B.Cu" "In4.Cu" "In6.Cu" "In11.Cu" "In13.Cu" "In15.Cu")
		(hatch none 0.5)
		(connect_pads
			(clearance 0)
		)
		(min_thickness 0.25)
		(keepout
			(tracks not_allowed)
			(vias allowed)
			(pads allowed)
			(copperpour not_allowed)
			(footprints allowed)
		)
		(placement
			(enabled no)
			(sheetname "")
		)
		(fill yes
			(thermal_gap 0.5)
			(thermal_bridge_width 0.5)
			(island_removal_mode 0)
		)
		(polygon
			(pts
				(arc
					(start 173.122336 -271.266666)
					(mid 172.469556 -271.266666)
					(end 173.122336 -271.266666)
				)
			)
		)
	)
	(zone
		(layers "B.Cu" "In4.Cu" "In6.Cu" "In11.Cu" "In13.Cu" "In15.Cu")
		(hatch none 0.5)
		(connect_pads
			(clearance 0)
		)
		(min_thickness 0.25)
		(keepout
			(tracks not_allowed)
			(vias allowed)
			(pads allowed)
			(copperpour not_allowed)
			(footprints allowed)
		)
		(placement
			(enabled no)
			(sheetname "")
		)
		(fill yes
			(thermal_gap 0.5)
			(thermal_bridge_width 0.5)
			(island_removal_mode 0)
		)
		(polygon
			(pts
				(arc
					(start 335.827878 -400.858228)
					(mid 335.124298 -400.858228)
					(end 335.827878 -400.858228)
				)
			)
		)
	)
	(zone
		(layers "B.Cu" "In4.Cu" "In6.Cu" "In11.Cu" "In13.Cu" "In15.Cu")
		(hatch none 0.5)
		(connect_pads
			(clearance 0)
		)
		(min_thickness 0.25)
		(keepout
			(tracks not_allowed)
			(vias allowed)
			(pads allowed)
			(copperpour not_allowed)
			(footprints allowed)
		)
		(placement
			(enabled no)
			(sheetname "")
		)
		(fill yes
			(thermal_gap 0.5)
			(thermal_bridge_width 0.5)
			(island_removal_mode 0)
		)
		(polygon
			(pts
				(arc
					(start 342.52027 -249.620024)
					(mid 341.86749 -249.620024)
					(end 342.52027 -249.620024)
				)
			)
		)
	)
	(zone
		(layers "B.Cu" "In4.Cu" "In6.Cu" "In11.Cu" "In13.Cu" "In15.Cu")
		(hatch none 0.5)
		(connect_pads
			(clearance 0)
		)
		(min_thickness 0.25)
		(keepout
			(tracks not_allowed)
			(vias allowed)
			(pads allowed)
			(copperpour not_allowed)
			(footprints allowed)
		)
		(placement
			(enabled no)
			(sheetname "")
		)
		(fill yes
			(thermal_gap 0.5)
			(thermal_bridge_width 0.5)
			(island_removal_mode 0)
		)
		(polygon
			(pts
				(arc
					(start 113.376202 -223.575626)
					(mid 112.723422 -223.575626)
					(end 113.376202 -223.575626)
				)
			)
		)
	)
	(zone
		(layers "B.Cu" "In4.Cu" "In6.Cu" "In11.Cu" "In13.Cu" "In15.Cu")
		(hatch none 0.5)
		(connect_pads
			(clearance 0)
		)
		(min_thickness 0.25)
		(keepout
			(tracks not_allowed)
			(vias allowed)
			(pads allowed)
			(copperpour not_allowed)
			(footprints allowed)
		)
		(placement
			(enabled no)
			(sheetname "")
		)
		(fill yes
			(thermal_gap 0.5)
			(thermal_bridge_width 0.5)
			(island_removal_mode 0)
		)
		(polygon
			(pts
				(arc
					(start 410.049472 -304.416714)
					(mid 409.396692 -304.416714)
					(end 410.049472 -304.416714)
				)
			)
		)
	)
	(zone
		(layers "B.Cu" "In4.Cu" "In6.Cu" "In11.Cu" "In13.Cu" "In15.Cu")
		(hatch none 0.5)
		(connect_pads
			(clearance 0)
		)
		(min_thickness 0.25)
		(keepout
			(tracks not_allowed)
			(vias allowed)
			(pads allowed)
			(copperpour not_allowed)
			(footprints allowed)
		)
		(placement
			(enabled no)
			(sheetname "")
		)
		(fill yes
			(thermal_gap 0.5)
			(thermal_bridge_width 0.5)
			(island_removal_mode 0)
		)
		(polygon
			(pts
				(arc
					(start 386.691124 -223.575626)
					(mid 386.038344 -223.575626)
					(end 386.691124 -223.575626)
				)
			)
		)
	)
	(zone
		(layers "B.Cu" "In4.Cu" "In6.Cu" "In11.Cu" "In13.Cu" "In15.Cu")
		(hatch none 0.5)
		(connect_pads
			(clearance 0)
		)
		(min_thickness 0.25)
		(keepout
			(tracks not_allowed)
			(vias allowed)
			(pads allowed)
			(copperpour not_allowed)
			(footprints allowed)
		)
		(placement
			(enabled no)
			(sheetname "")
		)
		(fill yes
			(thermal_gap 0.5)
			(thermal_bridge_width 0.5)
			(island_removal_mode 0)
		)
		(polygon
			(pts
				(arc
					(start 337.351624 -227.64496)
					(mid 336.698844 -227.64496)
					(end 337.351624 -227.64496)
				)
			)
		)
	)
	(zone
		(layers "B.Cu" "In4.Cu" "In6.Cu" "In11.Cu" "In13.Cu" "In15.Cu")
		(hatch none 0.5)
		(connect_pads
			(clearance 0)
		)
		(min_thickness 0.25)
		(keepout
			(tracks not_allowed)
			(vias allowed)
			(pads allowed)
			(copperpour not_allowed)
			(footprints allowed)
		)
		(placement
			(enabled no)
			(sheetname "")
		)
		(fill yes
			(thermal_gap 0.5)
			(thermal_bridge_width 0.5)
			(island_removal_mode 0)
		)
		(polygon
			(pts
				(arc
					(start 90.821002 -238.225584)
					(mid 90.168222 -238.225584)
					(end 90.821002 -238.225584)
				)
			)
		)
	)
	(zone
		(layers "B.Cu" "In4.Cu" "In6.Cu" "In11.Cu" "In13.Cu" "In15.Cu")
		(hatch none 0.5)
		(connect_pads
			(clearance 0)
		)
		(min_thickness 0.25)
		(keepout
			(tracks not_allowed)
			(vias allowed)
			(pads allowed)
			(copperpour not_allowed)
			(footprints allowed)
		)
		(placement
			(enabled no)
			(sheetname "")
		)
		(fill yes
			(thermal_gap 0.5)
			(thermal_bridge_width 0.5)
			(island_removal_mode 0)
		)
		(polygon
			(pts
				(arc
					(start 47.290736 -245.76659)
					(mid 46.637956 -245.76659)
					(end 47.290736 -245.76659)
				)
			)
		)
	)
	(zone
		(layers "B.Cu" "In4.Cu" "In6.Cu" "In11.Cu" "In13.Cu" "In15.Cu")
		(hatch none 0.5)
		(connect_pads
			(clearance 0)
		)
		(min_thickness 0.25)
		(keepout
			(tracks not_allowed)
			(vias allowed)
			(pads allowed)
			(copperpour not_allowed)
			(footprints allowed)
		)
		(placement
			(enabled no)
			(sheetname "")
		)
		(fill yes
			(thermal_gap 0.5)
			(thermal_bridge_width 0.5)
			(island_removal_mode 0)
		)
		(polygon
			(pts
				(arc
					(start 337.461606 -262.058658)
					(mid 336.808826 -262.058658)
					(end 337.461606 -262.058658)
				)
			)
		)
	)
	(zone
		(layers "B.Cu" "In4.Cu" "In6.Cu" "In11.Cu" "In13.Cu" "In15.Cu")
		(hatch none 0.5)
		(connect_pads
			(clearance 0)
		)
		(min_thickness 0.25)
		(keepout
			(tracks not_allowed)
			(vias allowed)
			(pads allowed)
			(copperpour not_allowed)
			(footprints allowed)
		)
		(placement
			(enabled no)
			(sheetname "")
		)
		(fill yes
			(thermal_gap 0.5)
			(thermal_bridge_width 0.5)
			(island_removal_mode 0)
		)
		(polygon
			(pts
				(arc
					(start 47.290736 -252.566678)
					(mid 46.637956 -252.566678)
					(end 47.290736 -252.566678)
				)
			)
		)
	)
	(zone
		(layers "B.Cu" "In4.Cu" "In6.Cu" "In11.Cu" "In13.Cu" "In15.Cu")
		(hatch none 0.5)
		(connect_pads
			(clearance 0)
		)
		(min_thickness 0.25)
		(keepout
			(tracks not_allowed)
			(vias allowed)
			(pads allowed)
			(copperpour not_allowed)
			(footprints allowed)
		)
		(placement
			(enabled no)
			(sheetname "")
		)
		(fill yes
			(thermal_gap 0.5)
			(thermal_bridge_width 0.5)
			(island_removal_mode 0)
		)
		(polygon
			(pts
				(arc
					(start 51.416204 -290.816792)
					(mid 50.763424 -290.816792)
					(end 51.416204 -290.816792)
				)
			)
		)
	)
	(zone
		(layers "B.Cu" "In4.Cu" "In6.Cu" "In11.Cu" "In13.Cu" "In15.Cu")
		(hatch none 0.5)
		(connect_pads
			(clearance 0)
		)
		(min_thickness 0.25)
		(keepout
			(tracks not_allowed)
			(vias allowed)
			(pads allowed)
			(copperpour not_allowed)
			(footprints allowed)
		)
		(placement
			(enabled no)
			(sheetname "")
		)
		(fill yes
			(thermal_gap 0.5)
			(thermal_bridge_width 0.5)
			(island_removal_mode 0)
		)
		(polygon
			(pts
				(arc
					(start 299.356272 -274.666964)
					(mid 298.703492 -274.666964)
					(end 299.356272 -274.666964)
				)
			)
		)
	)
	(zone
		(layers "B.Cu" "In4.Cu" "In6.Cu" "In11.Cu" "In13.Cu" "In15.Cu")
		(hatch none 0.5)
		(connect_pads
			(clearance 0)
		)
		(min_thickness 0.25)
		(keepout
			(tracks not_allowed)
			(vias allowed)
			(pads allowed)
			(copperpour not_allowed)
			(footprints allowed)
		)
		(placement
			(enabled no)
			(sheetname "")
		)
		(fill yes
			(thermal_gap 0.5)
			(thermal_bridge_width 0.5)
			(island_removal_mode 0)
		)
		(polygon
			(pts
				(arc
					(start 421.062404 -272.966688)
					(mid 420.409624 -272.966688)
					(end 421.062404 -272.966688)
				)
			)
		)
	)
	(zone
		(layers "B.Cu" "In4.Cu" "In6.Cu" "In11.Cu" "In13.Cu" "In15.Cu")
		(hatch none 0.5)
		(connect_pads
			(clearance 0)
		)
		(min_thickness 0.25)
		(keepout
			(tracks not_allowed)
			(vias allowed)
			(pads allowed)
			(copperpour not_allowed)
			(footprints allowed)
		)
		(placement
			(enabled no)
			(sheetname "")
		)
		(fill yes
			(thermal_gap 0.5)
			(thermal_bridge_width 0.5)
			(island_removal_mode 0)
		)
		(polygon
			(pts
				(arc
					(start 135.931656 -239.853216)
					(mid 135.278876 -239.853216)
					(end 135.931656 -239.853216)
				)
			)
		)
	)
	(zone
		(layers "B.Cu" "In4.Cu" "In6.Cu" "In11.Cu" "In13.Cu" "In15.Cu")
		(hatch none 0.5)
		(connect_pads
			(clearance 0)
		)
		(min_thickness 0.25)
		(keepout
			(tracks not_allowed)
			(vias allowed)
			(pads allowed)
			(copperpour not_allowed)
			(footprints allowed)
		)
		(placement
			(enabled no)
			(sheetname "")
		)
		(fill yes
			(thermal_gap 0.5)
			(thermal_bridge_width 0.5)
			(island_removal_mode 0)
		)
		(polygon
			(pts
				(arc
					(start 361.786424 -224.389442)
					(mid 361.133644 -224.389442)
					(end 361.786424 -224.389442)
				)
			)
		)
	)
	(zone
		(layers "B.Cu" "In4.Cu" "In6.Cu" "In11.Cu" "In13.Cu" "In15.Cu")
		(hatch none 0.5)
		(connect_pads
			(clearance 0)
		)
		(min_thickness 0.25)
		(keepout
			(tracks not_allowed)
			(vias allowed)
			(pads allowed)
			(copperpour not_allowed)
			(footprints allowed)
		)
		(placement
			(enabled no)
			(sheetname "")
		)
		(fill yes
			(thermal_gap 0.5)
			(thermal_bridge_width 0.5)
			(island_removal_mode 0)
		)
		(polygon
			(pts
				(arc
					(start 158.009336 -302.716692)
					(mid 157.356556 -302.716692)
					(end 158.009336 -302.716692)
				)
			)
		)
	)
	(zone
		(layers "B.Cu" "In4.Cu" "In6.Cu" "In11.Cu" "In13.Cu" "In15.Cu")
		(hatch none 0.5)
		(connect_pads
			(clearance 0)
		)
		(min_thickness 0.25)
		(keepout
			(tracks not_allowed)
			(vias allowed)
			(pads allowed)
			(copperpour not_allowed)
			(footprints allowed)
		)
		(placement
			(enabled no)
			(sheetname "")
		)
		(fill yes
			(thermal_gap 0.5)
			(thermal_bridge_width 0.5)
			(island_removal_mode 0)
		)
		(polygon
			(pts
				(arc
					(start 295.230804 -289.966654)
					(mid 294.578024 -289.966654)
					(end 295.230804 -289.966654)
				)
			)
		)
	)
	(zone
		(layers "B.Cu" "In4.Cu" "In6.Cu" "In11.Cu" "In13.Cu" "In15.Cu")
		(hatch none 0.5)
		(connect_pads
			(clearance 0)
		)
		(min_thickness 0.25)
		(keepout
			(tracks not_allowed)
			(vias allowed)
			(pads allowed)
			(copperpour not_allowed)
			(footprints allowed)
		)
		(placement
			(enabled no)
			(sheetname "")
		)
		(fill yes
			(thermal_gap 0.5)
			(thermal_bridge_width 0.5)
			(island_removal_mode 0)
		)
		(polygon
			(pts
				(arc
					(start 386.221224 -224.389442)
					(mid 385.568444 -224.389442)
					(end 386.221224 -224.389442)
				)
			)
		)
	)
	(zone
		(layers "B.Cu" "In4.Cu" "In6.Cu" "In11.Cu" "In13.Cu" "In15.Cu")
		(hatch none 0.5)
		(connect_pads
			(clearance 0)
		)
		(min_thickness 0.25)
		(keepout
			(tracks not_allowed)
			(vias allowed)
			(pads allowed)
			(copperpour not_allowed)
			(footprints allowed)
		)
		(placement
			(enabled no)
			(sheetname "")
		)
		(fill yes
			(thermal_gap 0.5)
			(thermal_bridge_width 0.5)
			(island_removal_mode 0)
		)
		(polygon
			(pts
				(arc
					(start 425.162472 -267.016738)
					(mid 424.509692 -267.016738)
					(end 425.162472 -267.016738)
				)
			)
		)
	)
	(zone
		(layers "B.Cu" "In4.Cu" "In6.Cu" "In11.Cu" "In13.Cu" "In15.Cu")
		(hatch none 0.5)
		(connect_pads
			(clearance 0)
		)
		(min_thickness 0.25)
		(keepout
			(tracks not_allowed)
			(vias allowed)
			(pads allowed)
			(copperpour not_allowed)
			(footprints allowed)
		)
		(placement
			(enabled no)
			(sheetname "")
		)
		(fill yes
			(thermal_gap 0.5)
			(thermal_bridge_width 0.5)
			(island_removal_mode 0)
		)
		(polygon
			(pts
				(arc
					(start 299.330872 -246.616728)
					(mid 298.678092 -246.616728)
					(end 299.330872 -246.616728)
				)
			)
		)
	)
	(zone
		(layers "B.Cu" "In4.Cu" "In6.Cu" "In11.Cu" "In13.Cu" "In15.Cu")
		(hatch none 0.5)
		(connect_pads
			(clearance 0)
		)
		(min_thickness 0.25)
		(keepout
			(tracks not_allowed)
			(vias allowed)
			(pads allowed)
			(copperpour not_allowed)
			(footprints allowed)
		)
		(placement
			(enabled no)
			(sheetname "")
		)
		(fill yes
			(thermal_gap 0.5)
			(thermal_bridge_width 0.5)
			(island_removal_mode 0)
		)
		(polygon
			(pts
				(arc
					(start 291.787072 -244.916706)
					(mid 291.134292 -244.916706)
					(end 291.787072 -244.916706)
				)
			)
		)
	)
	(zone
		(layers "B.Cu" "In4.Cu" "In6.Cu" "In11.Cu" "In13.Cu" "In15.Cu")
		(hatch none 0.5)
		(connect_pads
			(clearance 0)
		)
		(min_thickness 0.25)
		(keepout
			(tracks not_allowed)
			(vias allowed)
			(pads allowed)
			(copperpour not_allowed)
			(footprints allowed)
		)
		(placement
			(enabled no)
			(sheetname "")
		)
		(fill yes
			(thermal_gap 0.5)
			(thermal_bridge_width 0.5)
			(island_removal_mode 0)
		)
		(polygon
			(pts
				(arc
					(start 376.94489 -0.048006)
					(mid 376.24131 -0.048006)
					(end 376.94489 -0.048006)
				)
			)
		)
	)
	(zone
		(layers "B.Cu" "In4.Cu" "In6.Cu" "In11.Cu" "In13.Cu" "In15.Cu")
		(hatch none 0.5)
		(connect_pads
			(clearance 0)
		)
		(min_thickness 0.25)
		(keepout
			(tracks not_allowed)
			(vias allowed)
			(pads allowed)
			(copperpour not_allowed)
			(footprints allowed)
		)
		(placement
			(enabled no)
			(sheetname "")
		)
		(fill yes
			(thermal_gap 0.5)
			(thermal_bridge_width 0.5)
			(island_removal_mode 0)
		)
		(polygon
			(pts
				(arc
					(start 337.351624 -237.411514)
					(mid 336.698844 -237.411514)
					(end 337.351624 -237.411514)
				)
			)
		)
	)
	(zone
		(layers "B.Cu" "In4.Cu" "In6.Cu" "In11.Cu" "In13.Cu" "In15.Cu")
		(hatch none 0.5)
		(connect_pads
			(clearance 0)
		)
		(min_thickness 0.25)
		(keepout
			(tracks not_allowed)
			(vias allowed)
			(pads allowed)
			(copperpour not_allowed)
			(footprints allowed)
		)
		(placement
			(enabled no)
			(sheetname "")
		)
		(fill yes
			(thermal_gap 0.5)
			(thermal_bridge_width 0.5)
			(island_removal_mode 0)
		)
		(polygon
			(pts
				(arc
					(start 336.521552 -260.430772)
					(mid 335.868772 -260.430772)
					(end 336.521552 -260.430772)
				)
			)
		)
	)
	(zone
		(layers "B.Cu" "In4.Cu" "In6.Cu" "In11.Cu" "In13.Cu" "In15.Cu")
		(hatch none 0.5)
		(connect_pads
			(clearance 0)
		)
		(min_thickness 0.25)
		(keepout
			(tracks not_allowed)
			(vias allowed)
			(pads allowed)
			(copperpour not_allowed)
			(footprints allowed)
		)
		(placement
			(enabled no)
			(sheetname "")
		)
		(fill yes
			(thermal_gap 0.5)
			(thermal_bridge_width 0.5)
			(island_removal_mode 0)
		)
		(polygon
			(pts
				(arc
					(start 262.589772 0.815594)
					(mid 261.886192 0.815594)
					(end 262.589772 0.815594)
				)
			)
		)
	)
	(zone
		(layers "B.Cu" "In4.Cu" "In6.Cu" "In11.Cu" "In13.Cu" "In15.Cu")
		(hatch none 0.5)
		(connect_pads
			(clearance 0)
		)
		(min_thickness 0.25)
		(keepout
			(tracks not_allowed)
			(vias allowed)
			(pads allowed)
			(copperpour not_allowed)
			(footprints allowed)
		)
		(placement
			(enabled no)
			(sheetname "")
		)
		(fill yes
			(thermal_gap 0.5)
			(thermal_bridge_width 0.5)
			(island_removal_mode 0)
		)
		(polygon
			(pts
				(arc
					(start 90.821002 -243.108988)
					(mid 90.168222 -243.108988)
					(end 90.821002 -243.108988)
				)
			)
		)
	)
	(zone
		(layers "B.Cu" "In4.Cu" "In6.Cu" "In11.Cu" "In13.Cu" "In15.Cu")
		(hatch none 0.5)
		(connect_pads
			(clearance 0)
		)
		(min_thickness 0.25)
		(keepout
			(tracks not_allowed)
			(vias allowed)
			(pads allowed)
			(copperpour not_allowed)
			(footprints allowed)
		)
		(placement
			(enabled no)
			(sheetname "")
		)
		(fill yes
			(thermal_gap 0.5)
			(thermal_bridge_width 0.5)
			(island_removal_mode 0)
		)
		(polygon
			(pts
				(arc
					(start 291.787072 -259.366766)
					(mid 291.134292 -259.366766)
					(end 291.787072 -259.366766)
				)
			)
		)
	)
	(zone
		(layers "B.Cu" "In4.Cu" "In6.Cu" "In11.Cu" "In13.Cu" "In15.Cu")
		(hatch none 0.5)
		(connect_pads
			(clearance 0)
		)
		(min_thickness 0.25)
		(keepout
			(tracks not_allowed)
			(vias allowed)
			(pads allowed)
			(copperpour not_allowed)
			(footprints allowed)
		)
		(placement
			(enabled no)
			(sheetname "")
		)
		(fill yes
			(thermal_gap 0.5)
			(thermal_bridge_width 0.5)
			(island_removal_mode 0)
		)
		(polygon
			(pts
				(arc
					(start 135.101584 -266.128246)
					(mid 134.448804 -266.128246)
					(end 135.101584 -266.128246)
				)
			)
		)
	)
	(zone
		(layers "B.Cu" "In4.Cu" "In6.Cu" "In11.Cu" "In13.Cu" "In15.Cu")
		(hatch none 0.5)
		(connect_pads
			(clearance 0)
		)
		(min_thickness 0.25)
		(keepout
			(tracks not_allowed)
			(vias allowed)
			(pads allowed)
			(copperpour not_allowed)
			(footprints allowed)
		)
		(placement
			(enabled no)
			(sheetname "")
		)
		(fill yes
			(thermal_gap 0.5)
			(thermal_bridge_width 0.5)
			(island_removal_mode 0)
		)
		(polygon
			(pts
				(arc
					(start 299.356272 -267.016738)
					(mid 298.703492 -267.016738)
					(end 299.356272 -267.016738)
				)
			)
		)
	)
	(zone
		(layers "B.Cu" "In4.Cu" "In6.Cu" "In11.Cu" "In13.Cu" "In15.Cu")
		(hatch none 0.5)
		(connect_pads
			(clearance 0)
		)
		(min_thickness 0.25)
		(keepout
			(tracks not_allowed)
			(vias allowed)
			(pads allowed)
			(copperpour not_allowed)
			(footprints allowed)
		)
		(placement
			(enabled no)
			(sheetname "")
		)
		(fill yes
			(thermal_gap 0.5)
			(thermal_bridge_width 0.5)
			(island_removal_mode 0)
		)
		(polygon
			(pts
				(arc
					(start 380.111 -407.00452)
					(mid 379.40742 -407.00452)
					(end 380.111 -407.00452)
				)
			)
		)
	)
	(zone
		(layers "B.Cu" "In4.Cu" "In6.Cu" "In11.Cu" "In13.Cu" "In15.Cu")
		(hatch none 0.5)
		(connect_pads
			(clearance 0)
		)
		(min_thickness 0.25)
		(keepout
			(tracks not_allowed)
			(vias allowed)
			(pads allowed)
			(copperpour not_allowed)
			(footprints allowed)
		)
		(placement
			(enabled no)
			(sheetname "")
		)
		(fill yes
			(thermal_gap 0.5)
			(thermal_bridge_width 0.5)
			(island_removal_mode 0)
		)
		(polygon
			(pts
				(arc
					(start 300.92523 -163.083748)
					(mid 300.22165 -163.083748)
					(end 300.92523 -163.083748)
				)
			)
		)
	)
	(zone
		(layers "B.Cu" "In4.Cu" "In6.Cu" "In11.Cu" "In13.Cu" "In15.Cu")
		(hatch none 0.5)
		(connect_pads
			(clearance 0)
		)
		(min_thickness 0.25)
		(keepout
			(tracks not_allowed)
			(vias allowed)
			(pads allowed)
			(copperpour not_allowed)
			(footprints allowed)
		)
		(placement
			(enabled no)
			(sheetname "")
		)
		(fill yes
			(thermal_gap 0.5)
			(thermal_bridge_width 0.5)
			(island_removal_mode 0)
		)
		(polygon
			(pts
				(arc
					(start 117.605556 -224.389442)
					(mid 116.952776 -224.389442)
					(end 117.605556 -224.389442)
				)
			)
		)
	)
	(zone
		(layers "B.Cu" "In4.Cu" "In6.Cu" "In11.Cu" "In13.Cu" "In15.Cu")
		(hatch none 0.5)
		(connect_pads
			(clearance 0)
		)
		(min_thickness 0.25)
		(keepout
			(tracks not_allowed)
			(vias allowed)
			(pads allowed)
			(copperpour not_allowed)
			(footprints allowed)
		)
		(placement
			(enabled no)
			(sheetname "")
		)
		(fill yes
			(thermal_gap 0.5)
			(thermal_bridge_width 0.5)
			(island_removal_mode 0)
		)
		(polygon
			(pts
				(arc
					(start 105.388156 -224.389442)
					(mid 104.735376 -224.389442)
					(end 105.388156 -224.389442)
				)
			)
		)
	)
	(zone
		(layers "B.Cu" "In4.Cu" "In6.Cu" "In11.Cu" "In13.Cu" "In15.Cu")
		(hatch none 0.5)
		(connect_pads
			(clearance 0)
		)
		(min_thickness 0.25)
		(keepout
			(tracks not_allowed)
			(vias allowed)
			(pads allowed)
			(copperpour not_allowed)
			(footprints allowed)
		)
		(placement
			(enabled no)
			(sheetname "")
		)
		(fill yes
			(thermal_gap 0.5)
			(thermal_bridge_width 0.5)
			(island_removal_mode 0)
		)
		(polygon
			(pts
				(arc
					(start 51.416204 -267.016738)
					(mid 50.763424 -267.016738)
					(end 51.416204 -267.016738)
				)
			)
		)
	)
	(zone
		(layers "B.Cu" "In4.Cu" "In6.Cu" "In11.Cu" "In13.Cu" "In15.Cu")
		(hatch none 0.5)
		(connect_pads
			(clearance 0)
		)
		(min_thickness 0.25)
		(keepout
			(tracks not_allowed)
			(vias allowed)
			(pads allowed)
			(copperpour not_allowed)
			(footprints allowed)
		)
		(placement
			(enabled no)
			(sheetname "")
		)
		(fill yes
			(thermal_gap 0.5)
			(thermal_bridge_width 0.5)
			(island_removal_mode 0)
		)
		(polygon
			(pts
				(arc
					(start 410.049472 -227.066602)
					(mid 409.396692 -227.066602)
					(end 410.049472 -227.066602)
				)
			)
		)
	)
	(zone
		(layers "B.Cu" "In4.Cu" "In6.Cu" "In11.Cu" "In13.Cu" "In15.Cu")
		(hatch none 0.5)
		(connect_pads
			(clearance 0)
		)
		(min_thickness 0.25)
		(keepout
			(tracks not_allowed)
			(vias allowed)
			(pads allowed)
			(copperpour not_allowed)
			(footprints allowed)
		)
		(placement
			(enabled no)
			(sheetname "")
		)
		(fill yes
			(thermal_gap 0.5)
			(thermal_bridge_width 0.5)
			(island_removal_mode 0)
		)
		(polygon
			(pts
				(arc
					(start 416.70859 -19.125438)
					(mid 416.00501 -19.125438)
					(end 416.70859 -19.125438)
				)
			)
		)
	)
	(zone
		(layers "B.Cu" "In4.Cu" "In6.Cu" "In11.Cu" "In13.Cu" "In15.Cu")
		(hatch none 0.5)
		(connect_pads
			(clearance 0)
		)
		(min_thickness 0.25)
		(keepout
			(tracks not_allowed)
			(vias allowed)
			(pads allowed)
			(copperpour not_allowed)
			(footprints allowed)
		)
		(placement
			(enabled no)
			(sheetname "")
		)
		(fill yes
			(thermal_gap 0.5)
			(thermal_bridge_width 0.5)
			(island_removal_mode 0)
		)
		(polygon
			(pts
				(arc
					(start 173.046136 -261.066788)
					(mid 172.393356 -261.066788)
					(end 173.046136 -261.066788)
				)
			)
		)
	)
	(zone
		(layers "B.Cu" "In4.Cu" "In6.Cu" "In11.Cu" "In13.Cu" "In15.Cu")
		(hatch none 0.5)
		(connect_pads
			(clearance 0)
		)
		(min_thickness 0.25)
		(keepout
			(tracks not_allowed)
			(vias allowed)
			(pads allowed)
			(copperpour not_allowed)
			(footprints allowed)
		)
		(placement
			(enabled no)
			(sheetname "")
		)
		(fill yes
			(thermal_gap 0.5)
			(thermal_bridge_width 0.5)
			(island_removal_mode 0)
		)
		(polygon
			(pts
				(arc
					(start 386.221224 -222.761556)
					(mid 385.568444 -222.761556)
					(end 386.221224 -222.761556)
				)
			)
		)
	)
	(zone
		(layers "B.Cu" "In4.Cu" "In6.Cu" "In11.Cu" "In13.Cu" "In15.Cu")
		(hatch none 0.5)
		(connect_pads
			(clearance 0)
		)
		(min_thickness 0.25)
		(keepout
			(tracks not_allowed)
			(vias allowed)
			(pads allowed)
			(copperpour not_allowed)
			(footprints allowed)
		)
		(placement
			(enabled no)
			(sheetname "")
		)
		(fill yes
			(thermal_gap 0.5)
			(thermal_bridge_width 0.5)
			(island_removal_mode 0)
		)
		(polygon
			(pts
				(arc
					(start 88.47201 -242.294918)
					(mid 87.81923 -242.294918)
					(end 88.47201 -242.294918)
				)
			)
		)
	)
	(zone
		(layers "B.Cu" "In4.Cu" "In6.Cu" "In11.Cu" "In13.Cu" "In15.Cu")
		(hatch none 0.5)
		(connect_pads
			(clearance 0)
		)
		(min_thickness 0.25)
		(keepout
			(tracks not_allowed)
			(vias allowed)
			(pads allowed)
			(copperpour not_allowed)
			(footprints allowed)
		)
		(placement
			(enabled no)
			(sheetname "")
		)
		(fill yes
			(thermal_gap 0.5)
			(thermal_bridge_width 0.5)
			(island_removal_mode 0)
		)
		(polygon
			(pts
				(arc
					(start 384.81127 -223.575626)
					(mid 384.15849 -223.575626)
					(end 384.81127 -223.575626)
				)
			)
		)
	)
	(zone
		(layers "B.Cu" "In4.Cu" "In6.Cu" "In11.Cu" "In13.Cu" "In15.Cu")
		(hatch none 0.5)
		(connect_pads
			(clearance 0)
		)
		(min_thickness 0.25)
		(keepout
			(tracks not_allowed)
			(vias allowed)
			(pads allowed)
			(copperpour not_allowed)
			(footprints allowed)
		)
		(placement
			(enabled no)
			(sheetname "")
		)
		(fill yes
			(thermal_gap 0.5)
			(thermal_bridge_width 0.5)
			(island_removal_mode 0)
		)
		(polygon
			(pts
				(arc
					(start 338.291424 -234.15625)
					(mid 337.638644 -234.15625)
					(end 338.291424 -234.15625)
				)
			)
		)
	)
	(zone
		(layers "B.Cu" "In4.Cu" "In6.Cu" "In11.Cu" "In13.Cu" "In15.Cu")
		(hatch none 0.5)
		(connect_pads
			(clearance 0)
		)
		(min_thickness 0.25)
		(keepout
			(tracks not_allowed)
			(vias allowed)
			(pads allowed)
			(copperpour not_allowed)
			(footprints allowed)
		)
		(placement
			(enabled no)
			(sheetname "")
		)
		(fill yes
			(thermal_gap 0.5)
			(thermal_bridge_width 0.5)
			(island_removal_mode 0)
		)
		(polygon
			(pts
				(arc
					(start 390.393174 -17.601438)
					(mid 389.689594 -17.601438)
					(end 390.393174 -17.601438)
				)
			)
		)
	)
	(zone
		(layers "B.Cu" "In4.Cu" "In6.Cu" "In11.Cu" "In13.Cu" "In15.Cu")
		(hatch none 0.5)
		(connect_pads
			(clearance 0)
		)
		(min_thickness 0.25)
		(keepout
			(tracks not_allowed)
			(vias allowed)
			(pads allowed)
			(copperpour not_allowed)
			(footprints allowed)
		)
		(placement
			(enabled no)
			(sheetname "")
		)
		(fill yes
			(thermal_gap 0.5)
			(thermal_bridge_width 0.5)
			(island_removal_mode 0)
		)
		(polygon
			(pts
				(arc
					(start 102.208584 -285.661354)
					(mid 101.555804 -285.661354)
					(end 102.208584 -285.661354)
				)
			)
		)
	)
	(zone
		(layers "B.Cu" "In4.Cu" "In6.Cu" "In11.Cu" "In13.Cu" "In15.Cu")
		(hatch none 0.5)
		(connect_pads
			(clearance 0)
		)
		(min_thickness 0.25)
		(keepout
			(tracks not_allowed)
			(vias allowed)
			(pads allowed)
			(copperpour not_allowed)
			(footprints allowed)
		)
		(placement
			(enabled no)
			(sheetname "")
		)
		(fill yes
			(thermal_gap 0.5)
			(thermal_bridge_width 0.5)
			(island_removal_mode 0)
		)
		(polygon
			(pts
				(arc
					(start 310.318404 -228.766624)
					(mid 309.665624 -228.766624)
					(end 310.318404 -228.766624)
				)
			)
		)
	)
	(zone
		(layers "B.Cu" "In4.Cu" "In6.Cu" "In11.Cu" "In13.Cu" "In15.Cu")
		(hatch none 0.5)
		(connect_pads
			(clearance 0)
		)
		(min_thickness 0.25)
		(keepout
			(tracks not_allowed)
			(vias allowed)
			(pads allowed)
			(copperpour not_allowed)
			(footprints allowed)
		)
		(placement
			(enabled no)
			(sheetname "")
		)
		(fill yes
			(thermal_gap 0.5)
			(thermal_bridge_width 0.5)
			(island_removal_mode 0)
		)
		(polygon
			(pts
				(arc
					(start 343.876884 -50.329592)
					(mid 343.224104 -50.329592)
					(end 343.876884 -50.329592)
				)
			)
		)
	)
	(zone
		(layers "B.Cu" "In4.Cu" "In6.Cu" "In11.Cu" "In13.Cu" "In15.Cu")
		(hatch none 0.5)
		(connect_pads
			(clearance 0)
		)
		(min_thickness 0.25)
		(keepout
			(tracks not_allowed)
			(vias allowed)
			(pads allowed)
			(copperpour not_allowed)
			(footprints allowed)
		)
		(placement
			(enabled no)
			(sheetname "")
		)
		(fill yes
			(thermal_gap 0.5)
			(thermal_bridge_width 0.5)
			(island_removal_mode 0)
		)
		(polygon
			(pts
				(arc
					(start 133.692138 -257.175254)
					(mid 133.039358 -257.175254)
					(end 133.692138 -257.175254)
				)
			)
		)
	)
	(zone
		(layers "B.Cu" "In4.Cu" "In6.Cu" "In11.Cu" "In13.Cu" "In15.Cu")
		(hatch none 0.5)
		(connect_pads
			(clearance 0)
		)
		(min_thickness 0.25)
		(keepout
			(tracks not_allowed)
			(vias allowed)
			(pads allowed)
			(copperpour not_allowed)
			(footprints allowed)
		)
		(placement
			(enabled no)
			(sheetname "")
		)
		(fill yes
			(thermal_gap 0.5)
			(thermal_bridge_width 0.5)
			(island_removal_mode 0)
		)
		(polygon
			(pts
				(arc
					(start 51.390804 -206.666592)
					(mid 50.738024 -206.666592)
					(end 51.390804 -206.666592)
				)
			)
		)
	)
	(zone
		(layers "B.Cu" "In4.Cu" "In6.Cu" "In11.Cu" "In13.Cu" "In15.Cu")
		(hatch none 0.5)
		(connect_pads
			(clearance 0)
		)
		(min_thickness 0.25)
		(keepout
			(tracks not_allowed)
			(vias allowed)
			(pads allowed)
			(copperpour not_allowed)
			(footprints allowed)
		)
		(placement
			(enabled no)
			(sheetname "")
		)
		(fill yes
			(thermal_gap 0.5)
			(thermal_bridge_width 0.5)
			(island_removal_mode 0)
		)
		(polygon
			(pts
				(arc
					(start 114.316002 -225.203258)
					(mid 113.663222 -225.203258)
					(end 114.316002 -225.203258)
				)
			)
		)
	)
	(zone
		(layers "B.Cu" "In4.Cu" "In6.Cu" "In11.Cu" "In13.Cu" "In15.Cu")
		(hatch none 0.5)
		(connect_pads
			(clearance 0)
		)
		(min_thickness 0.25)
		(keepout
			(tracks not_allowed)
			(vias allowed)
			(pads allowed)
			(copperpour not_allowed)
			(footprints allowed)
		)
		(placement
			(enabled no)
			(sheetname "")
		)
		(fill yes
			(thermal_gap 0.5)
			(thermal_bridge_width 0.5)
			(island_removal_mode 0)
		)
		(polygon
			(pts
				(arc
					(start 405.949404 -305.266598)
					(mid 405.296624 -305.266598)
					(end 405.949404 -305.266598)
				)
			)
		)
	)
	(zone
		(layers "B.Cu" "In4.Cu" "In6.Cu" "In11.Cu" "In13.Cu" "In15.Cu")
		(hatch none 0.5)
		(connect_pads
			(clearance 0)
		)
		(min_thickness 0.25)
		(keepout
			(tracks not_allowed)
			(vias allowed)
			(pads allowed)
			(copperpour not_allowed)
			(footprints allowed)
		)
		(placement
			(enabled no)
			(sheetname "")
		)
		(fill yes
			(thermal_gap 0.5)
			(thermal_bridge_width 0.5)
			(island_removal_mode 0)
		)
		(polygon
			(pts
				(arc
					(start 377.873006 -286.475424)
					(mid 377.220226 -286.475424)
					(end 377.873006 -286.475424)
				)
			)
		)
	)
	(zone
		(layers "B.Cu" "In4.Cu" "In6.Cu" "In11.Cu" "In13.Cu" "In15.Cu")
		(hatch none 0.5)
		(connect_pads
			(clearance 0)
		)
		(min_thickness 0.25)
		(keepout
			(tracks not_allowed)
			(vias allowed)
			(pads allowed)
			(copperpour not_allowed)
			(footprints allowed)
		)
		(placement
			(enabled no)
			(sheetname "")
		)
		(fill yes
			(thermal_gap 0.5)
			(thermal_bridge_width 0.5)
			(island_removal_mode 0)
		)
		(polygon
			(pts
				(arc
					(start 177.222404 -216.016586)
					(mid 176.569624 -216.016586)
					(end 177.222404 -216.016586)
				)
			)
		)
	)
	(zone
		(layers "B.Cu" "In4.Cu" "In6.Cu" "In11.Cu" "In13.Cu" "In15.Cu")
		(hatch none 0.5)
		(connect_pads
			(clearance 0)
		)
		(min_thickness 0.25)
		(keepout
			(tracks not_allowed)
			(vias allowed)
			(pads allowed)
			(copperpour not_allowed)
			(footprints allowed)
		)
		(placement
			(enabled no)
			(sheetname "")
		)
		(fill yes
			(thermal_gap 0.5)
			(thermal_bridge_width 0.5)
			(island_removal_mode 0)
		)
		(polygon
			(pts
				(arc
					(start 161.675064 -407.00452)
					(mid 160.971484 -407.00452)
					(end 161.675064 -407.00452)
				)
			)
		)
	)
	(zone
		(layers "B.Cu" "In4.Cu" "In6.Cu" "In11.Cu" "In13.Cu" "In15.Cu")
		(hatch none 0.5)
		(connect_pads
			(clearance 0)
		)
		(min_thickness 0.25)
		(keepout
			(tracks not_allowed)
			(vias allowed)
			(pads allowed)
			(copperpour not_allowed)
			(footprints allowed)
		)
		(placement
			(enabled no)
			(sheetname "")
		)
		(fill yes
			(thermal_gap 0.5)
			(thermal_bridge_width 0.5)
			(island_removal_mode 0)
		)
		(polygon
			(pts
				(arc
					(start 173.122336 -278.916638)
					(mid 172.469556 -278.916638)
					(end 173.122336 -278.916638)
				)
			)
		)
	)
	(zone
		(layers "B.Cu" "In4.Cu" "In6.Cu" "In11.Cu" "In13.Cu" "In15.Cu")
		(hatch none 0.5)
		(connect_pads
			(clearance 0)
		)
		(min_thickness 0.25)
		(keepout
			(tracks not_allowed)
			(vias allowed)
			(pads allowed)
			(copperpour not_allowed)
			(footprints allowed)
		)
		(placement
			(enabled no)
			(sheetname "")
		)
		(fill yes
			(thermal_gap 0.5)
			(thermal_bridge_width 0.5)
			(island_removal_mode 0)
		)
		(polygon
			(pts
				(arc
					(start 173.122336 -238.116618)
					(mid 172.469556 -238.116618)
					(end 173.122336 -238.116618)
				)
			)
		)
	)
	(zone
		(layers "B.Cu" "In4.Cu" "In6.Cu" "In11.Cu" "In13.Cu" "In15.Cu")
		(hatch none 0.5)
		(connect_pads
			(clearance 0)
		)
		(min_thickness 0.25)
		(keepout
			(tracks not_allowed)
			(vias allowed)
			(pads allowed)
			(copperpour not_allowed)
			(footprints allowed)
		)
		(placement
			(enabled no)
			(sheetname "")
		)
		(fill yes
			(thermal_gap 0.5)
			(thermal_bridge_width 0.5)
			(island_removal_mode 0)
		)
		(polygon
			(pts
				(arc
					(start 47.290736 -222.816674)
					(mid 46.637956 -222.816674)
					(end 47.290736 -222.816674)
				)
			)
		)
	)
	(zone
		(layers "B.Cu" "In4.Cu" "In6.Cu" "In11.Cu" "In13.Cu" "In15.Cu")
		(hatch none 0.5)
		(connect_pads
			(clearance 0)
		)
		(min_thickness 0.25)
		(keepout
			(tracks not_allowed)
			(vias allowed)
			(pads allowed)
			(copperpour not_allowed)
			(footprints allowed)
		)
		(placement
			(enabled no)
			(sheetname "")
		)
		(fill yes
			(thermal_gap 0.5)
			(thermal_bridge_width 0.5)
			(island_removal_mode 0)
		)
		(polygon
			(pts
				(arc
					(start 173.122336 -312.066686)
					(mid 172.469556 -312.066686)
					(end 173.122336 -312.066686)
				)
			)
		)
	)
	(zone
		(layers "B.Cu" "In4.Cu" "In6.Cu" "In11.Cu" "In13.Cu" "In15.Cu")
		(hatch none 0.5)
		(connect_pads
			(clearance 0)
		)
		(min_thickness 0.25)
		(keepout
			(tracks not_allowed)
			(vias allowed)
			(pads allowed)
			(copperpour not_allowed)
			(footprints allowed)
		)
		(placement
			(enabled no)
			(sheetname "")
		)
		(fill yes
			(thermal_gap 0.5)
			(thermal_bridge_width 0.5)
			(island_removal_mode 0)
		)
		(polygon
			(pts
				(arc
					(start 418.63899 -17.601438)
					(mid 417.93541 -17.601438)
					(end 418.63899 -17.601438)
				)
			)
		)
	)
	(zone
		(layers "B.Cu" "In4.Cu" "In6.Cu" "In11.Cu" "In13.Cu" "In15.Cu")
		(hatch none 0.5)
		(connect_pads
			(clearance 0)
		)
		(min_thickness 0.25)
		(keepout
			(tracks not_allowed)
			(vias allowed)
			(pads allowed)
			(copperpour not_allowed)
			(footprints allowed)
		)
		(placement
			(enabled no)
			(sheetname "")
		)
		(fill yes
			(thermal_gap 0.5)
			(thermal_bridge_width 0.5)
			(island_removal_mode 0)
		)
		(polygon
			(pts
				(arc
					(start 339.811106 -285.661354)
					(mid 339.158326 -285.661354)
					(end 339.811106 -285.661354)
				)
			)
		)
	)
	(zone
		(layers "B.Cu" "In4.Cu" "In6.Cu" "In11.Cu" "In13.Cu" "In15.Cu")
		(hatch none 0.5)
		(connect_pads
			(clearance 0)
		)
		(min_thickness 0.25)
		(keepout
			(tracks not_allowed)
			(vias allowed)
			(pads allowed)
			(copperpour not_allowed)
			(footprints allowed)
		)
		(placement
			(enabled no)
			(sheetname "")
		)
		(fill yes
			(thermal_gap 0.5)
			(thermal_bridge_width 0.5)
			(island_removal_mode 0)
		)
		(polygon
			(pts
				(arc
					(start 379.752606 -255.547622)
					(mid 379.099826 -255.547622)
					(end 379.752606 -255.547622)
				)
			)
		)
	)
	(zone
		(layers "B.Cu" "In4.Cu" "In6.Cu" "In11.Cu" "In13.Cu" "In15.Cu")
		(hatch none 0.5)
		(connect_pads
			(clearance 0)
		)
		(min_thickness 0.25)
		(keepout
			(tracks not_allowed)
			(vias allowed)
			(pads allowed)
			(copperpour not_allowed)
			(footprints allowed)
		)
		(placement
			(enabled no)
			(sheetname "")
		)
		(fill yes
			(thermal_gap 0.5)
			(thermal_bridge_width 0.5)
			(island_removal_mode 0)
		)
		(polygon
			(pts
				(arc
					(start 344.6907 -51.739546)
					(mid 344.03792 -51.739546)
					(end 344.6907 -51.739546)
				)
			)
		)
	)
	(zone
		(layers "B.Cu" "In4.Cu" "In6.Cu" "In11.Cu" "In13.Cu" "In15.Cu")
		(hatch none 0.5)
		(connect_pads
			(clearance 0)
		)
		(min_thickness 0.25)
		(keepout
			(tracks not_allowed)
			(vias allowed)
			(pads allowed)
			(copperpour not_allowed)
			(footprints allowed)
		)
		(placement
			(enabled no)
			(sheetname "")
		)
		(fill yes
			(thermal_gap 0.5)
			(thermal_bridge_width 0.5)
			(island_removal_mode 0)
		)
		(polygon
			(pts
				(arc
					(start 90.363548 -407.00452)
					(mid 89.659968 -407.00452)
					(end 90.363548 -407.00452)
				)
			)
		)
	)
	(zone
		(layers "B.Cu" "In4.Cu" "In6.Cu" "In11.Cu" "In13.Cu" "In15.Cu")
		(hatch none 0.5)
		(connect_pads
			(clearance 0)
		)
		(min_thickness 0.25)
		(keepout
			(tracks not_allowed)
			(vias allowed)
			(pads allowed)
			(copperpour not_allowed)
			(footprints allowed)
		)
		(placement
			(enabled no)
			(sheetname "")
		)
		(fill yes
			(thermal_gap 0.5)
			(thermal_bridge_width 0.5)
			(island_removal_mode 0)
		)
		(polygon
			(pts
				(arc
					(start 299.330872 -218.566746)
					(mid 298.678092 -218.566746)
					(end 299.330872 -218.566746)
				)
			)
		)
	)
	(zone
		(layers "B.Cu" "In4.Cu" "In6.Cu" "In11.Cu" "In13.Cu" "In15.Cu")
		(hatch none 0.5)
		(connect_pads
			(clearance 0)
		)
		(min_thickness 0.25)
		(keepout
			(tracks not_allowed)
			(vias allowed)
			(pads allowed)
			(copperpour not_allowed)
			(footprints allowed)
		)
		(placement
			(enabled no)
			(sheetname "")
		)
		(fill yes
			(thermal_gap 0.5)
			(thermal_bridge_width 0.5)
			(island_removal_mode 0)
		)
		(polygon
			(pts
				(arc
					(start 49.677828 -407.00452)
					(mid 48.974248 -407.00452)
					(end 49.677828 -407.00452)
				)
			)
		)
	)
	(zone
		(layers "B.Cu" "In4.Cu" "In6.Cu" "In11.Cu" "In13.Cu" "In15.Cu")
		(hatch none 0.5)
		(connect_pads
			(clearance 0)
		)
		(min_thickness 0.25)
		(keepout
			(tracks not_allowed)
			(vias allowed)
			(pads allowed)
			(copperpour not_allowed)
			(footprints allowed)
		)
		(placement
			(enabled no)
			(sheetname "")
		)
		(fill yes
			(thermal_gap 0.5)
			(thermal_bridge_width 0.5)
			(island_removal_mode 0)
		)
		(polygon
			(pts
				(arc
					(start 421.062404 -210.066636)
					(mid 420.409624 -210.066636)
					(end 421.062404 -210.066636)
				)
			)
		)
	)
	(zone
		(layers "B.Cu" "In4.Cu" "In6.Cu" "In11.Cu" "In13.Cu" "In15.Cu")
		(hatch none 0.5)
		(connect_pads
			(clearance 0)
		)
		(min_thickness 0.25)
		(keepout
			(tracks not_allowed)
			(vias allowed)
			(pads allowed)
			(copperpour not_allowed)
			(footprints allowed)
		)
		(placement
			(enabled no)
			(sheetname "")
		)
		(fill yes
			(thermal_gap 0.5)
			(thermal_bridge_width 0.5)
			(island_removal_mode 0)
		)
		(polygon
			(pts
				(arc
					(start 135.101584 -264.50036)
					(mid 134.448804 -264.50036)
					(end 135.101584 -264.50036)
				)
			)
		)
	)
	(zone
		(layers "B.Cu" "In4.Cu" "In6.Cu" "In11.Cu" "In13.Cu" "In15.Cu")
		(hatch none 0.5)
		(connect_pads
			(clearance 0)
		)
		(min_thickness 0.25)
		(keepout
			(tracks not_allowed)
			(vias allowed)
			(pads allowed)
			(copperpour not_allowed)
			(footprints allowed)
		)
		(placement
			(enabled no)
			(sheetname "")
		)
		(fill yes
			(thermal_gap 0.5)
			(thermal_bridge_width 0.5)
			(island_removal_mode 0)
		)
		(polygon
			(pts
				(arc
					(start 350.148652 -285.661354)
					(mid 349.495872 -285.661354)
					(end 350.148652 -285.661354)
				)
			)
		)
	)
	(zone
		(layers "B.Cu" "In4.Cu" "In6.Cu" "In11.Cu" "In13.Cu" "In15.Cu")
		(hatch none 0.5)
		(connect_pads
			(clearance 0)
		)
		(min_thickness 0.25)
		(keepout
			(tracks not_allowed)
			(vias allowed)
			(pads allowed)
			(copperpour not_allowed)
			(footprints allowed)
		)
		(placement
			(enabled no)
			(sheetname "")
		)
		(fill yes
			(thermal_gap 0.5)
			(thermal_bridge_width 0.5)
			(island_removal_mode 0)
		)
		(polygon
			(pts
				(arc
					(start 91.401138 -260.430772)
					(mid 90.748358 -260.430772)
					(end 91.401138 -260.430772)
				)
			)
		)
	)
	(zone
		(layers "B.Cu" "In4.Cu" "In6.Cu" "In11.Cu" "In13.Cu" "In15.Cu")
		(hatch none 0.5)
		(connect_pads
			(clearance 0)
		)
		(min_thickness 0.25)
		(keepout
			(tracks not_allowed)
			(vias allowed)
			(pads allowed)
			(copperpour not_allowed)
			(footprints allowed)
		)
		(placement
			(enabled no)
			(sheetname "")
		)
		(fill yes
			(thermal_gap 0.5)
			(thermal_bridge_width 0.5)
			(island_removal_mode 0)
		)
		(polygon
			(pts
				(arc
					(start 425.162472 -218.566746)
					(mid 424.509692 -218.566746)
					(end 425.162472 -218.566746)
				)
			)
		)
	)
	(zone
		(layers "B.Cu" "In4.Cu" "In6.Cu" "In11.Cu" "In13.Cu" "In15.Cu")
		(hatch none 0.5)
		(connect_pads
			(clearance 0)
		)
		(min_thickness 0.25)
		(keepout
			(tracks not_allowed)
			(vias allowed)
			(pads allowed)
			(copperpour not_allowed)
			(footprints allowed)
		)
		(placement
			(enabled no)
			(sheetname "")
		)
		(fill yes
			(thermal_gap 0.5)
			(thermal_bridge_width 0.5)
			(island_removal_mode 0)
		)
		(polygon
			(pts
				(arc
					(start 139.220702 -222.761556)
					(mid 138.567922 -222.761556)
					(end 139.220702 -222.761556)
				)
			)
		)
	)
	(zone
		(layers "B.Cu" "In4.Cu" "In6.Cu" "In11.Cu" "In13.Cu" "In15.Cu")
		(hatch none 0.5)
		(connect_pads
			(clearance 0)
		)
		(min_thickness 0.25)
		(keepout
			(tracks not_allowed)
			(vias allowed)
			(pads allowed)
			(copperpour not_allowed)
			(footprints allowed)
		)
		(placement
			(enabled no)
			(sheetname "")
		)
		(fill yes
			(thermal_gap 0.5)
			(thermal_bridge_width 0.5)
			(island_removal_mode 0)
		)
		(polygon
			(pts
				(arc
					(start 112.906556 -224.389442)
					(mid 112.253776 -224.389442)
					(end 112.906556 -224.389442)
				)
			)
		)
	)
	(zone
		(layers "B.Cu" "In4.Cu" "In6.Cu" "In11.Cu" "In13.Cu" "In15.Cu")
		(hatch none 0.5)
		(connect_pads
			(clearance 0)
		)
		(min_thickness 0.25)
		(keepout
			(tracks not_allowed)
			(vias allowed)
			(pads allowed)
			(copperpour not_allowed)
			(footprints allowed)
		)
		(placement
			(enabled no)
			(sheetname "")
		)
		(fill yes
			(thermal_gap 0.5)
			(thermal_bridge_width 0.5)
			(island_removal_mode 0)
		)
		(polygon
			(pts
				(arc
					(start 47.290736 -247.466612)
					(mid 46.637956 -247.466612)
					(end 47.290736 -247.466612)
				)
			)
		)
	)
	(zone
		(layers "B.Cu" "In4.Cu" "In6.Cu" "In11.Cu" "In13.Cu" "In15.Cu")
		(hatch none 0.5)
		(connect_pads
			(clearance 0)
		)
		(min_thickness 0.25)
		(keepout
			(tracks not_allowed)
			(vias allowed)
			(pads allowed)
			(copperpour not_allowed)
			(footprints allowed)
		)
		(placement
			(enabled no)
			(sheetname "")
		)
		(fill yes
			(thermal_gap 0.5)
			(thermal_bridge_width 0.5)
			(island_removal_mode 0)
		)
		(polygon
			(pts
				(arc
					(start 30.719268 -19.13636)
					(mid 30.015688 -19.13636)
					(end 30.719268 -19.13636)
				)
			)
		)
	)
	(zone
		(layers "B.Cu" "In4.Cu" "In6.Cu" "In11.Cu" "In13.Cu" "In15.Cu")
		(hatch none 0.5)
		(connect_pads
			(clearance 0)
		)
		(min_thickness 0.25)
		(keepout
			(tracks not_allowed)
			(vias allowed)
			(pads allowed)
			(copperpour not_allowed)
			(footprints allowed)
		)
		(placement
			(enabled no)
			(sheetname "")
		)
		(fill yes
			(thermal_gap 0.5)
			(thermal_bridge_width 0.5)
			(island_removal_mode 0)
		)
		(polygon
			(pts
				(arc
					(start 134.161784 -277.522432)
					(mid 133.509004 -277.522432)
					(end 134.161784 -277.522432)
				)
			)
		)
	)
	(zone
		(layers "B.Cu" "In4.Cu" "In6.Cu" "In11.Cu" "In13.Cu" "In15.Cu")
		(hatch none 0.5)
		(connect_pads
			(clearance 0)
		)
		(min_thickness 0.25)
		(keepout
			(tracks not_allowed)
			(vias allowed)
			(pads allowed)
			(copperpour not_allowed)
			(footprints allowed)
		)
		(placement
			(enabled no)
			(sheetname "")
		)
		(fill yes
			(thermal_gap 0.5)
			(thermal_bridge_width 0.5)
			(island_removal_mode 0)
		)
		(polygon
			(pts
				(arc
					(start 90.461084 -266.941808)
					(mid 89.808304 -266.941808)
					(end 90.461084 -266.941808)
				)
			)
		)
	)
	(zone
		(layers "B.Cu" "In4.Cu" "In6.Cu" "In11.Cu" "In13.Cu" "In15.Cu")
		(hatch none 0.5)
		(connect_pads
			(clearance 0)
		)
		(min_thickness 0.25)
		(keepout
			(tracks not_allowed)
			(vias allowed)
			(pads allowed)
			(copperpour not_allowed)
			(footprints allowed)
		)
		(placement
			(enabled no)
			(sheetname "")
		)
		(fill yes
			(thermal_gap 0.5)
			(thermal_bridge_width 0.5)
			(island_removal_mode 0)
		)
		(polygon
			(pts
				(arc
					(start 336.521552 -275.08073)
					(mid 335.868772 -275.08073)
					(end 336.521552 -275.08073)
				)
			)
		)
	)
	(zone
		(layers "B.Cu" "In4.Cu" "In6.Cu" "In11.Cu" "In13.Cu" "In15.Cu")
		(hatch none 0.5)
		(connect_pads
			(clearance 0)
		)
		(min_thickness 0.25)
		(keepout
			(tracks not_allowed)
			(vias allowed)
			(pads allowed)
			(copperpour not_allowed)
			(footprints allowed)
		)
		(placement
			(enabled no)
			(sheetname "")
		)
		(fill yes
			(thermal_gap 0.5)
			(thermal_bridge_width 0.5)
			(island_removal_mode 0)
		)
		(polygon
			(pts
				(arc
					(start 299.356272 -290.816792)
					(mid 298.703492 -290.816792)
					(end 299.356272 -290.816792)
				)
			)
		)
	)
	(zone
		(layers "B.Cu" "In4.Cu" "In6.Cu" "In11.Cu" "In13.Cu" "In15.Cu")
		(hatch none 0.5)
		(connect_pads
			(clearance 0)
		)
		(min_thickness 0.25)
		(keepout
			(tracks not_allowed)
			(vias allowed)
			(pads allowed)
			(copperpour not_allowed)
			(footprints allowed)
		)
		(placement
			(enabled no)
			(sheetname "")
		)
		(fill yes
			(thermal_gap 0.5)
			(thermal_bridge_width 0.5)
			(island_removal_mode 0)
		)
		(polygon
			(pts
				(arc
					(start 379.752606 -286.475424)
					(mid 379.099826 -286.475424)
					(end 379.752606 -286.475424)
				)
			)
		)
	)
	(zone
		(layers "B.Cu" "In4.Cu" "In6.Cu" "In11.Cu" "In13.Cu" "In15.Cu")
		(hatch none 0.5)
		(connect_pads
			(clearance 0)
		)
		(min_thickness 0.25)
		(keepout
			(tracks not_allowed)
			(vias allowed)
			(pads allowed)
			(copperpour not_allowed)
			(footprints allowed)
		)
		(placement
			(enabled no)
			(sheetname "")
		)
		(fill yes
			(thermal_gap 0.5)
			(thermal_bridge_width 0.5)
			(island_removal_mode 0)
		)
		(polygon
			(pts
				(arc
					(start 310.318404 -227.91674)
					(mid 309.665624 -227.91674)
					(end 310.318404 -227.91674)
				)
			)
		)
	)
	(zone
		(layers "B.Cu" "In4.Cu" "In6.Cu" "In11.Cu" "In13.Cu" "In15.Cu")
		(hatch none 0.5)
		(connect_pads
			(clearance 0)
		)
		(min_thickness 0.25)
		(keepout
			(tracks not_allowed)
			(vias allowed)
			(pads allowed)
			(copperpour not_allowed)
			(footprints allowed)
		)
		(placement
			(enabled no)
			(sheetname "")
		)
		(fill yes
			(thermal_gap 0.5)
			(thermal_bridge_width 0.5)
			(island_removal_mode 0)
		)
		(polygon
			(pts
				(arc
					(start 103.148384 -285.661354)
					(mid 102.495604 -285.661354)
					(end 103.148384 -285.661354)
				)
			)
		)
	)
	(zone
		(layers "B.Cu" "In4.Cu" "In6.Cu" "In11.Cu" "In13.Cu" "In15.Cu")
		(hatch none 0.5)
		(connect_pads
			(clearance 0)
		)
		(min_thickness 0.25)
		(keepout
			(tracks not_allowed)
			(vias allowed)
			(pads allowed)
			(copperpour not_allowed)
			(footprints allowed)
		)
		(placement
			(enabled no)
			(sheetname "")
		)
		(fill yes
			(thermal_gap 0.5)
			(thermal_bridge_width 0.5)
			(island_removal_mode 0)
		)
		(polygon
			(pts
				(arc
					(start 88.941402 -247.992138)
					(mid 88.288622 -247.992138)
					(end 88.941402 -247.992138)
				)
			)
		)
	)
	(zone
		(layers "B.Cu" "In4.Cu" "In6.Cu" "In11.Cu" "In13.Cu" "In15.Cu")
		(hatch none 0.5)
		(connect_pads
			(clearance 0)
		)
		(min_thickness 0.25)
		(keepout
			(tracks not_allowed)
			(vias allowed)
			(pads allowed)
			(copperpour not_allowed)
			(footprints allowed)
		)
		(placement
			(enabled no)
			(sheetname "")
		)
		(fill yes
			(thermal_gap 0.5)
			(thermal_bridge_width 0.5)
			(island_removal_mode 0)
		)
		(polygon
			(pts
				(arc
					(start 299.330872 -233.016806)
					(mid 298.678092 -233.016806)
					(end 299.330872 -233.016806)
				)
			)
		)
	)
	(zone
		(layers "B.Cu" "In4.Cu" "In6.Cu" "In11.Cu" "In13.Cu" "In15.Cu")
		(hatch none 0.5)
		(connect_pads
			(clearance 0)
		)
		(min_thickness 0.25)
		(keepout
			(tracks not_allowed)
			(vias allowed)
			(pads allowed)
			(copperpour not_allowed)
			(footprints allowed)
		)
		(placement
			(enabled no)
			(sheetname "")
		)
		(fill yes
			(thermal_gap 0.5)
			(thermal_bridge_width 0.5)
			(island_removal_mode 0)
		)
		(polygon
			(pts
				(arc
					(start 177.222404 -270.416782)
					(mid 176.569624 -270.416782)
					(end 177.222404 -270.416782)
				)
			)
		)
	)
	(zone
		(layers "B.Cu" "In4.Cu" "In6.Cu" "In11.Cu" "In13.Cu" "In15.Cu")
		(hatch none 0.5)
		(connect_pads
			(clearance 0)
		)
		(min_thickness 0.25)
		(keepout
			(tracks not_allowed)
			(vias allowed)
			(pads allowed)
			(copperpour not_allowed)
			(footprints allowed)
		)
		(placement
			(enabled no)
			(sheetname "")
		)
		(fill yes
			(thermal_gap 0.5)
			(thermal_bridge_width 0.5)
			(island_removal_mode 0)
		)
		(polygon
			(pts
				(arc
					(start 177.222404 -274.66671)
					(mid 176.569624 -274.66671)
					(end 177.222404 -274.66671)
				)
			)
		)
	)
	(zone
		(layers "B.Cu" "In4.Cu" "In6.Cu" "In11.Cu" "In13.Cu" "In15.Cu")
		(hatch none 0.5)
		(connect_pads
			(clearance 0)
		)
		(min_thickness 0.25)
		(keepout
			(tracks not_allowed)
			(vias allowed)
			(pads allowed)
			(copperpour not_allowed)
			(footprints allowed)
		)
		(placement
			(enabled no)
			(sheetname "")
		)
		(fill yes
			(thermal_gap 0.5)
			(thermal_bridge_width 0.5)
			(island_removal_mode 0)
		)
		(polygon
			(pts
				(arc
					(start 295.230804 -308.666642)
					(mid 294.578024 -308.666642)
					(end 295.230804 -308.666642)
				)
			)
		)
	)
	(zone
		(layers "B.Cu" "In4.Cu" "In6.Cu" "In11.Cu" "In13.Cu" "In15.Cu")
		(hatch none 0.5)
		(connect_pads
			(clearance 0)
		)
		(min_thickness 0.25)
		(keepout
			(tracks not_allowed)
			(vias allowed)
			(pads allowed)
			(copperpour not_allowed)
			(footprints allowed)
		)
		(placement
			(enabled no)
			(sheetname "")
		)
		(fill yes
			(thermal_gap 0.5)
			(thermal_bridge_width 0.5)
			(island_removal_mode 0)
		)
		(polygon
			(pts
				(arc
					(start 51.416204 -270.416782)
					(mid 50.763424 -270.416782)
					(end 51.416204 -270.416782)
				)
			)
		)
	)
	(zone
		(layers "B.Cu" "In4.Cu" "In6.Cu" "In11.Cu" "In13.Cu" "In15.Cu")
		(hatch none 0.5)
		(connect_pads
			(clearance 0)
		)
		(min_thickness 0.25)
		(keepout
			(tracks not_allowed)
			(vias allowed)
			(pads allowed)
			(copperpour not_allowed)
			(footprints allowed)
		)
		(placement
			(enabled no)
			(sheetname "")
		)
		(fill yes
			(thermal_gap 0.5)
			(thermal_bridge_width 0.5)
			(island_removal_mode 0)
		)
		(polygon
			(pts
				(arc
					(start 51.416204 -260.21665)
					(mid 50.763424 -260.21665)
					(end 51.416204 -260.21665)
				)
			)
		)
	)
	(zone
		(layers "B.Cu" "In4.Cu" "In6.Cu" "In11.Cu" "In13.Cu" "In15.Cu")
		(hatch none 0.5)
		(connect_pads
			(clearance 0)
		)
		(min_thickness 0.25)
		(keepout
			(tracks not_allowed)
			(vias allowed)
			(pads allowed)
			(copperpour not_allowed)
			(footprints allowed)
		)
		(placement
			(enabled no)
			(sheetname "")
		)
		(fill yes
			(thermal_gap 0.5)
			(thermal_bridge_width 0.5)
			(island_removal_mode 0)
		)
		(polygon
			(pts
				(arc
					(start 338.871052 -256.361438)
					(mid 338.218272 -256.361438)
					(end 338.871052 -256.361438)
				)
			)
		)
	)
	(zone
		(layers "B.Cu" "In4.Cu" "In6.Cu" "In11.Cu" "In13.Cu" "In15.Cu")
		(hatch none 0.5)
		(connect_pads
			(clearance 0)
		)
		(min_thickness 0.25)
		(keepout
			(tracks not_allowed)
			(vias allowed)
			(pads allowed)
			(copperpour not_allowed)
			(footprints allowed)
		)
		(placement
			(enabled no)
			(sheetname "")
		)
		(fill yes
			(thermal_gap 0.5)
			(thermal_bridge_width 0.5)
			(island_removal_mode 0)
		)
		(polygon
			(pts
				(arc
					(start 128.843024 -407.00452)
					(mid 128.139444 -407.00452)
					(end 128.843024 -407.00452)
				)
			)
		)
	)
	(zone
		(layers "B.Cu" "In4.Cu" "In6.Cu" "In11.Cu" "In13.Cu" "In15.Cu")
		(hatch none 0.5)
		(connect_pads
			(clearance 0)
		)
		(min_thickness 0.25)
		(keepout
			(tracks not_allowed)
			(vias allowed)
			(pads allowed)
			(copperpour not_allowed)
			(footprints allowed)
		)
		(placement
			(enabled no)
			(sheetname "")
		)
		(fill yes
			(thermal_gap 0.5)
			(thermal_bridge_width 0.5)
			(island_removal_mode 0)
		)
		(polygon
			(pts
				(arc
					(start 124.763784 -285.661354)
					(mid 124.111004 -285.661354)
					(end 124.763784 -285.661354)
				)
			)
		)
	)
	(zone
		(layers "B.Cu" "In4.Cu" "In6.Cu" "In11.Cu" "In13.Cu" "In15.Cu")
		(hatch none 0.5)
		(connect_pads
			(clearance 0)
		)
		(min_thickness 0.25)
		(keepout
			(tracks not_allowed)
			(vias allowed)
			(pads allowed)
			(copperpour not_allowed)
			(footprints allowed)
		)
		(placement
			(enabled no)
			(sheetname "")
		)
		(fill yes
			(thermal_gap 0.5)
			(thermal_bridge_width 0.5)
			(island_removal_mode 0)
		)
		(polygon
			(pts
				(arc
					(start 367.89487 -225.203258)
					(mid 367.24209 -225.203258)
					(end 367.89487 -225.203258)
				)
			)
		)
	)
	(zone
		(layers "B.Cu" "In4.Cu" "In6.Cu" "In11.Cu" "In13.Cu" "In15.Cu")
		(hatch none 0.5)
		(connect_pads
			(clearance 0)
		)
		(min_thickness 0.25)
		(keepout
			(tracks not_allowed)
			(vias allowed)
			(pads allowed)
			(copperpour not_allowed)
			(footprints allowed)
		)
		(placement
			(enabled no)
			(sheetname "")
		)
		(fill yes
			(thermal_gap 0.5)
			(thermal_bridge_width 0.5)
			(island_removal_mode 0)
		)
		(polygon
			(pts
				(arc
					(start 173.122336 -259.366766)
					(mid 172.469556 -259.366766)
					(end 173.122336 -259.366766)
				)
			)
		)
	)
	(zone
		(layers "B.Cu" "In4.Cu" "In6.Cu" "In11.Cu" "In13.Cu" "In15.Cu")
		(hatch none 0.5)
		(connect_pads
			(clearance 0)
		)
		(min_thickness 0.25)
		(keepout
			(tracks not_allowed)
			(vias allowed)
			(pads allowed)
			(copperpour not_allowed)
			(footprints allowed)
		)
		(placement
			(enabled no)
			(sheetname "")
		)
		(fill yes
			(thermal_gap 0.5)
			(thermal_bridge_width 0.5)
			(island_removal_mode 0)
		)
		(polygon
			(pts
				(arc
					(start 336.411824 -237.411514)
					(mid 335.759044 -237.411514)
					(end 336.411824 -237.411514)
				)
			)
		)
	)
	(zone
		(layers "B.Cu" "In4.Cu" "In6.Cu" "In11.Cu" "In13.Cu" "In15.Cu")
		(hatch none 0.5)
		(connect_pads
			(clearance 0)
		)
		(min_thickness 0.25)
		(keepout
			(tracks not_allowed)
			(vias allowed)
			(pads allowed)
			(copperpour not_allowed)
			(footprints allowed)
		)
		(placement
			(enabled no)
			(sheetname "")
		)
		(fill yes
			(thermal_gap 0.5)
			(thermal_bridge_width 0.5)
			(island_removal_mode 0)
		)
		(polygon
			(pts
				(arc
					(start 378.342652 -285.661354)
					(mid 377.689872 -285.661354)
					(end 378.342652 -285.661354)
				)
			)
		)
	)
	(zone
		(layers "B.Cu" "In4.Cu" "In6.Cu" "In11.Cu" "In13.Cu" "In15.Cu")
		(hatch none 0.5)
		(connect_pads
			(clearance 0)
		)
		(min_thickness 0.25)
		(keepout
			(tracks not_allowed)
			(vias allowed)
			(pads allowed)
			(copperpour not_allowed)
			(footprints allowed)
		)
		(placement
			(enabled no)
			(sheetname "")
		)
		(fill yes
			(thermal_gap 0.5)
			(thermal_bridge_width 0.5)
			(island_removal_mode 0)
		)
		(polygon
			(pts
				(arc
					(start 119.485156 -224.389442)
					(mid 118.832376 -224.389442)
					(end 119.485156 -224.389442)
				)
			)
		)
	)
	(zone
		(layers "B.Cu" "In4.Cu" "In6.Cu" "In11.Cu" "In13.Cu" "In15.Cu")
		(hatch none 0.5)
		(connect_pads
			(clearance 0)
		)
		(min_thickness 0.25)
		(keepout
			(tracks not_allowed)
			(vias allowed)
			(pads allowed)
			(copperpour not_allowed)
			(footprints allowed)
		)
		(placement
			(enabled no)
			(sheetname "")
		)
		(fill yes
			(thermal_gap 0.5)
			(thermal_bridge_width 0.5)
			(island_removal_mode 0)
		)
		(polygon
			(pts
				(arc
					(start 421.062404 -277.216616)
					(mid 420.409624 -277.216616)
					(end 421.062404 -277.216616)
				)
			)
		)
	)
	(zone
		(layers "B.Cu" "In4.Cu" "In6.Cu" "In11.Cu" "In13.Cu" "In15.Cu")
		(hatch none 0.5)
		(connect_pads
			(clearance 0)
		)
		(min_thickness 0.25)
		(keepout
			(tracks not_allowed)
			(vias allowed)
			(pads allowed)
			(copperpour not_allowed)
			(footprints allowed)
		)
		(placement
			(enabled no)
			(sheetname "")
		)
		(fill yes
			(thermal_gap 0.5)
			(thermal_bridge_width 0.5)
			(island_removal_mode 0)
		)
		(polygon
			(pts
				(arc
					(start 90.931238 -285.661354)
					(mid 90.278458 -285.661354)
					(end 90.931238 -285.661354)
				)
			)
		)
	)
	(zone
		(layers "B.Cu" "In4.Cu" "In6.Cu" "In11.Cu" "In13.Cu" "In15.Cu")
		(hatch none 0.5)
		(connect_pads
			(clearance 0)
		)
		(min_thickness 0.25)
		(keepout
			(tracks not_allowed)
			(vias allowed)
			(pads allowed)
			(copperpour not_allowed)
			(footprints allowed)
		)
		(placement
			(enabled no)
			(sheetname "")
		)
		(fill yes
			(thermal_gap 0.5)
			(thermal_bridge_width 0.5)
			(island_removal_mode 0)
		)
		(polygon
			(pts
				(arc
					(start 341.220806 -284.847538)
					(mid 340.568026 -284.847538)
					(end 341.220806 -284.847538)
				)
			)
		)
	)
	(zone
		(layers "B.Cu" "In4.Cu" "In6.Cu" "In11.Cu" "In13.Cu" "In15.Cu")
		(hatch none 0.5)
		(connect_pads
			(clearance 0)
		)
		(min_thickness 0.25)
		(keepout
			(tracks not_allowed)
			(vias allowed)
			(pads allowed)
			(copperpour not_allowed)
			(footprints allowed)
		)
		(placement
			(enabled no)
			(sheetname "")
		)
		(fill yes
			(thermal_gap 0.5)
			(thermal_bridge_width 0.5)
			(island_removal_mode 0)
		)
		(polygon
			(pts
				(arc
					(start 90.351356 -237.411514)
					(mid 89.698576 -237.411514)
					(end 90.351356 -237.411514)
				)
			)
		)
	)
	(zone
		(layers "B.Cu" "In4.Cu" "In6.Cu" "In11.Cu" "In13.Cu" "In15.Cu")
		(hatch none 0.5)
		(connect_pads
			(clearance 0)
		)
		(min_thickness 0.25)
		(keepout
			(tracks not_allowed)
			(vias allowed)
			(pads allowed)
			(copperpour not_allowed)
			(footprints allowed)
		)
		(placement
			(enabled no)
			(sheetname "")
		)
		(fill yes
			(thermal_gap 0.5)
			(thermal_bridge_width 0.5)
			(island_removal_mode 0)
		)
		(polygon
			(pts
				(arc
					(start 357.06558 -61.195966)
					(mid 356.362 -61.195966)
					(end 357.06558 -61.195966)
				)
			)
		)
	)
	(zone
		(layers "B.Cu" "In4.Cu" "In6.Cu" "In11.Cu" "In13.Cu" "In15.Cu")
		(hatch none 0.5)
		(connect_pads
			(clearance 0)
		)
		(min_thickness 0.25)
		(keepout
			(tracks not_allowed)
			(vias allowed)
			(pads allowed)
			(copperpour not_allowed)
			(footprints allowed)
		)
		(placement
			(enabled no)
			(sheetname "")
		)
		(fill yes
			(thermal_gap 0.5)
			(thermal_bridge_width 0.5)
			(island_removal_mode 0)
		)
		(polygon
			(pts
				(arc
					(start 382.931924 -230.086662)
					(mid 382.279144 -230.086662)
					(end 382.931924 -230.086662)
				)
			)
		)
	)
	(zone
		(layers "B.Cu" "In4.Cu" "In6.Cu" "In11.Cu" "In13.Cu" "In15.Cu")
		(hatch none 0.5)
		(connect_pads
			(clearance 0)
		)
		(min_thickness 0.25)
		(keepout
			(tracks not_allowed)
			(vias allowed)
			(pads allowed)
			(copperpour not_allowed)
			(footprints allowed)
		)
		(placement
			(enabled no)
			(sheetname "")
		)
		(fill yes
			(thermal_gap 0.5)
			(thermal_bridge_width 0.5)
			(island_removal_mode 0)
		)
		(polygon
			(pts
				(arc
					(start 173.122336 -233.86669)
					(mid 172.469556 -233.86669)
					(end 173.122336 -233.86669)
				)
			)
		)
	)
	(zone
		(layers "B.Cu" "In4.Cu" "In6.Cu" "In11.Cu" "In13.Cu" "In15.Cu")
		(hatch none 0.5)
		(connect_pads
			(clearance 0)
		)
		(min_thickness 0.25)
		(keepout
			(tracks not_allowed)
			(vias allowed)
			(pads allowed)
			(copperpour not_allowed)
			(footprints allowed)
		)
		(placement
			(enabled no)
			(sheetname "")
		)
		(fill yes
			(thermal_gap 0.5)
			(thermal_bridge_width 0.5)
			(island_removal_mode 0)
		)
		(polygon
			(pts
				(arc
					(start 47.290736 -275.516594)
					(mid 46.637956 -275.516594)
					(end 47.290736 -275.516594)
				)
			)
		)
	)
	(zone
		(layers "B.Cu" "In4.Cu" "In6.Cu" "In11.Cu" "In13.Cu" "In15.Cu")
		(hatch none 0.5)
		(connect_pads
			(clearance 0)
		)
		(min_thickness 0.25)
		(keepout
			(tracks not_allowed)
			(vias allowed)
			(pads allowed)
			(copperpour not_allowed)
			(footprints allowed)
		)
		(placement
			(enabled no)
			(sheetname "")
		)
		(fill yes
			(thermal_gap 0.5)
			(thermal_bridge_width 0.5)
			(island_removal_mode 0)
		)
		(polygon
			(pts
				(arc
					(start 299.356272 -295.06672)
					(mid 298.703492 -295.06672)
					(end 299.356272 -295.06672)
				)
			)
		)
	)
	(zone
		(layers "B.Cu" "In4.Cu" "In6.Cu" "In11.Cu" "In13.Cu" "In15.Cu")
		(hatch none 0.5)
		(connect_pads
			(clearance 0)
		)
		(min_thickness 0.25)
		(keepout
			(tracks not_allowed)
			(vias allowed)
			(pads allowed)
			(copperpour not_allowed)
			(footprints allowed)
		)
		(placement
			(enabled no)
			(sheetname "")
		)
		(fill yes
			(thermal_gap 0.5)
			(thermal_bridge_width 0.5)
			(island_removal_mode 0)
		)
		(polygon
			(pts
				(arc
					(start 299.356272 -307.816758)
					(mid 298.703492 -307.816758)
					(end 299.356272 -307.816758)
				)
			)
		)
	)
	(zone
		(layers "B.Cu" "In4.Cu" "In6.Cu" "In11.Cu" "In13.Cu" "In15.Cu")
		(hatch none 0.5)
		(connect_pads
			(clearance 0)
		)
		(min_thickness 0.25)
		(keepout
			(tracks not_allowed)
			(vias allowed)
			(pads allowed)
			(copperpour not_allowed)
			(footprints allowed)
		)
		(placement
			(enabled no)
			(sheetname "")
		)
		(fill yes
			(thermal_gap 0.5)
			(thermal_bridge_width 0.5)
			(island_removal_mode 0)
		)
		(polygon
			(pts
				(arc
					(start 368.475006 -286.475424)
					(mid 367.822226 -286.475424)
					(end 368.475006 -286.475424)
				)
			)
		)
	)
	(zone
		(layers "B.Cu" "In4.Cu" "In6.Cu" "In11.Cu" "In13.Cu" "In15.Cu")
		(hatch none 0.5)
		(connect_pads
			(clearance 0)
		)
		(min_thickness 0.25)
		(keepout
			(tracks not_allowed)
			(vias allowed)
			(pads allowed)
			(copperpour not_allowed)
			(footprints allowed)
		)
		(placement
			(enabled no)
			(sheetname "")
		)
		(fill yes
			(thermal_gap 0.5)
			(thermal_bridge_width 0.5)
			(island_removal_mode 0)
		)
		(polygon
			(pts
				(arc
					(start 135.101584 -275.8948)
					(mid 134.448804 -275.8948)
					(end 135.101584 -275.8948)
				)
			)
		)
	)
	(zone
		(layers "B.Cu" "In4.Cu" "In6.Cu" "In11.Cu" "In13.Cu" "In15.Cu")
		(hatch none 0.5)
		(connect_pads
			(clearance 0)
		)
		(min_thickness 0.25)
		(keepout
			(tracks not_allowed)
			(vias allowed)
			(pads allowed)
			(copperpour not_allowed)
			(footprints allowed)
		)
		(placement
			(enabled no)
			(sheetname "")
		)
		(fill yes
			(thermal_gap 0.5)
			(thermal_bridge_width 0.5)
			(island_removal_mode 0)
		)
		(polygon
			(pts
				(arc
					(start 98.919538 -284.847538)
					(mid 98.266758 -284.847538)
					(end 98.919538 -284.847538)
				)
			)
		)
	)
	(zone
		(layers "B.Cu" "In4.Cu" "In6.Cu" "In11.Cu" "In13.Cu" "In15.Cu")
		(hatch none 0.5)
		(connect_pads
			(clearance 0)
		)
		(min_thickness 0.25)
		(keepout
			(tracks not_allowed)
			(vias allowed)
			(pads allowed)
			(copperpour not_allowed)
			(footprints allowed)
		)
		(placement
			(enabled no)
			(sheetname "")
		)
		(fill yes
			(thermal_gap 0.5)
			(thermal_bridge_width 0.5)
			(island_removal_mode 0)
		)
		(polygon
			(pts
				(arc
					(start 382.101852 -285.661354)
					(mid 381.449072 -285.661354)
					(end 382.101852 -285.661354)
				)
			)
		)
	)
	(zone
		(layers "B.Cu" "In4.Cu" "In6.Cu" "In11.Cu" "In13.Cu" "In15.Cu")
		(hatch none 0.5)
		(connect_pads
			(clearance 0)
		)
		(min_thickness 0.25)
		(keepout
			(tracks not_allowed)
			(vias allowed)
			(pads allowed)
			(copperpour not_allowed)
			(footprints allowed)
		)
		(placement
			(enabled no)
			(sheetname "")
		)
		(fill yes
			(thermal_gap 0.5)
			(thermal_bridge_width 0.5)
			(island_removal_mode 0)
		)
		(polygon
			(pts
				(arc
					(start 116.665756 -224.389442)
					(mid 116.012976 -224.389442)
					(end 116.665756 -224.389442)
				)
			)
		)
	)
	(zone
		(layers "B.Cu" "In4.Cu" "In6.Cu" "In11.Cu" "In13.Cu" "In15.Cu")
		(hatch none 0.5)
		(connect_pads
			(clearance 0)
		)
		(min_thickness 0.25)
		(keepout
			(tracks not_allowed)
			(vias allowed)
			(pads allowed)
			(copperpour not_allowed)
			(footprints allowed)
		)
		(placement
			(enabled no)
			(sheetname "")
		)
		(fill yes
			(thermal_gap 0.5)
			(thermal_bridge_width 0.5)
			(island_removal_mode 0)
		)
		(polygon
			(pts
				(arc
					(start 89.051384 -254.733552)
					(mid 88.398604 -254.733552)
					(end 89.051384 -254.733552)
				)
			)
		)
	)
	(zone
		(layers "B.Cu" "In4.Cu" "In6.Cu" "In11.Cu" "In13.Cu" "In15.Cu")
		(hatch none 0.5)
		(connect_pads
			(clearance 0)
		)
		(min_thickness 0.25)
		(keepout
			(tracks not_allowed)
			(vias allowed)
			(pads allowed)
			(copperpour not_allowed)
			(footprints allowed)
		)
		(placement
			(enabled no)
			(sheetname "")
		)
		(fill yes
			(thermal_gap 0.5)
			(thermal_bridge_width 0.5)
			(island_removal_mode 0)
		)
		(polygon
			(pts
				(arc
					(start 344.6907 -50.799746)
					(mid 344.03792 -50.799746)
					(end 344.6907 -50.799746)
				)
			)
		)
	)
	(zone
		(layers "B.Cu" "In4.Cu" "In6.Cu" "In11.Cu" "In13.Cu" "In15.Cu")
		(hatch none 0.5)
		(connect_pads
			(clearance 0)
		)
		(min_thickness 0.25)
		(keepout
			(tracks not_allowed)
			(vias allowed)
			(pads allowed)
			(copperpour not_allowed)
			(footprints allowed)
		)
		(placement
			(enabled no)
			(sheetname "")
		)
		(fill yes
			(thermal_gap 0.5)
			(thermal_bridge_width 0.5)
			(island_removal_mode 0)
		)
		(polygon
			(pts
				(arc
					(start 344.980006 -284.847538)
					(mid 344.327226 -284.847538)
					(end 344.980006 -284.847538)
				)
			)
		)
	)
	(zone
		(layers "B.Cu" "In4.Cu" "In6.Cu" "In11.Cu" "In13.Cu" "In15.Cu")
		(hatch none 0.5)
		(connect_pads
			(clearance 0)
		)
		(min_thickness 0.25)
		(keepout
			(tracks not_allowed)
			(vias allowed)
			(pads allowed)
			(copperpour not_allowed)
			(footprints allowed)
		)
		(placement
			(enabled no)
			(sheetname "")
		)
		(fill yes
			(thermal_gap 0.5)
			(thermal_bridge_width 0.5)
			(island_removal_mode 0)
		)
		(polygon
			(pts
				(arc
					(start 173.122336 -221.116652)
					(mid 172.469556 -221.116652)
					(end 173.122336 -221.116652)
				)
			)
		)
	)
	(zone
		(layers "B.Cu" "In4.Cu" "In6.Cu" "In11.Cu" "In13.Cu" "In15.Cu")
		(hatch none 0.5)
		(connect_pads
			(clearance 0)
		)
		(min_thickness 0.25)
		(keepout
			(tracks not_allowed)
			(vias allowed)
			(pads allowed)
			(copperpour not_allowed)
			(footprints allowed)
		)
		(placement
			(enabled no)
			(sheetname "")
		)
		(fill yes
			(thermal_gap 0.5)
			(thermal_bridge_width 0.5)
			(island_removal_mode 0)
		)
		(polygon
			(pts
				(arc
					(start 421.062404 -245.76659)
					(mid 420.409624 -245.76659)
					(end 421.062404 -245.76659)
				)
			)
		)
	)
	(zone
		(layers "B.Cu" "In4.Cu" "In6.Cu" "In11.Cu" "In13.Cu" "In15.Cu")
		(hatch none 0.5)
		(connect_pads
			(clearance 0)
		)
		(min_thickness 0.25)
		(keepout
			(tracks not_allowed)
			(vias allowed)
			(pads allowed)
			(copperpour not_allowed)
			(footprints allowed)
		)
		(placement
			(enabled no)
			(sheetname "")
		)
		(fill yes
			(thermal_gap 0.5)
			(thermal_bridge_width 0.5)
			(island_removal_mode 0)
		)
		(polygon
			(pts
				(arc
					(start 135.101584 -274.266914)
					(mid 134.448804 -274.266914)
					(end 135.101584 -274.266914)
				)
			)
		)
	)
	(zone
		(layers "B.Cu" "In4.Cu" "In6.Cu" "In11.Cu" "In13.Cu" "In15.Cu")
		(hatch none 0.5)
		(connect_pads
			(clearance 0)
		)
		(min_thickness 0.25)
		(keepout
			(tracks not_allowed)
			(vias allowed)
			(pads allowed)
			(copperpour not_allowed)
			(footprints allowed)
		)
		(placement
			(enabled no)
			(sheetname "")
		)
		(fill yes
			(thermal_gap 0.5)
			(thermal_bridge_width 0.5)
			(island_removal_mode 0)
		)
		(polygon
			(pts
				(arc
					(start 368.944652 -285.661354)
					(mid 368.291872 -285.661354)
					(end 368.944652 -285.661354)
				)
			)
		)
	)
	(zone
		(layers "B.Cu" "In4.Cu" "In6.Cu" "In11.Cu" "In13.Cu" "In15.Cu")
		(hatch none 0.5)
		(connect_pads
			(clearance 0)
		)
		(min_thickness 0.25)
		(keepout
			(tracks not_allowed)
			(vias allowed)
			(pads allowed)
			(copperpour not_allowed)
			(footprints allowed)
		)
		(placement
			(enabled no)
			(sheetname "")
		)
		(fill yes
			(thermal_gap 0.5)
			(thermal_bridge_width 0.5)
			(island_removal_mode 0)
		)
		(polygon
			(pts
				(arc
					(start 336.991452 -259.616956)
					(mid 336.338672 -259.616956)
					(end 336.991452 -259.616956)
				)
			)
		)
	)
	(zone
		(layers "B.Cu" "In4.Cu" "In6.Cu" "In11.Cu" "In13.Cu" "In15.Cu")
		(hatch none 0.5)
		(connect_pads
			(clearance 0)
		)
		(min_thickness 0.25)
		(keepout
			(tracks not_allowed)
			(vias allowed)
			(pads allowed)
			(copperpour not_allowed)
			(footprints allowed)
		)
		(placement
			(enabled no)
			(sheetname "")
		)
		(fill yes
			(thermal_gap 0.5)
			(thermal_bridge_width 0.5)
			(island_removal_mode 0)
		)
		(polygon
			(pts
				(arc
					(start 121.944384 -285.661354)
					(mid 121.291604 -285.661354)
					(end 121.944384 -285.661354)
				)
			)
		)
	)
	(zone
		(layers "B.Cu" "In4.Cu" "In6.Cu" "In11.Cu" "In13.Cu" "In15.Cu")
		(hatch none 0.5)
		(connect_pads
			(clearance 0)
		)
		(min_thickness 0.25)
		(keepout
			(tracks not_allowed)
			(vias allowed)
			(pads allowed)
			(copperpour not_allowed)
			(footprints allowed)
		)
		(placement
			(enabled no)
			(sheetname "")
		)
		(fill yes
			(thermal_gap 0.5)
			(thermal_bridge_width 0.5)
			(island_removal_mode 0)
		)
		(polygon
			(pts
				(arc
					(start 427.055026 -19.125438)
					(mid 426.351446 -19.125438)
					(end 427.055026 -19.125438)
				)
			)
		)
	)
	(zone
		(layers "B.Cu" "In4.Cu" "In6.Cu" "In11.Cu" "In13.Cu" "In15.Cu")
		(hatch none 0.5)
		(connect_pads
			(clearance 0)
		)
		(min_thickness 0.25)
		(keepout
			(tracks not_allowed)
			(vias allowed)
			(pads allowed)
			(copperpour not_allowed)
			(footprints allowed)
		)
		(placement
			(enabled no)
			(sheetname "")
		)
		(fill yes
			(thermal_gap 0.5)
			(thermal_bridge_width 0.5)
			(island_removal_mode 0)
		)
		(polygon
			(pts
				(arc
					(start 134.161784 -271.011396)
					(mid 133.509004 -271.011396)
					(end 134.161784 -271.011396)
				)
			)
		)
	)
	(zone
		(layers "B.Cu" "In4.Cu" "In6.Cu" "In11.Cu" "In13.Cu" "In15.Cu")
		(hatch none 0.5)
		(connect_pads
			(clearance 0)
		)
		(min_thickness 0.25)
		(keepout
			(tracks not_allowed)
			(vias allowed)
			(pads allowed)
			(copperpour not_allowed)
			(footprints allowed)
		)
		(placement
			(enabled no)
			(sheetname "")
		)
		(fill yes
			(thermal_gap 0.5)
			(thermal_bridge_width 0.5)
			(island_removal_mode 0)
		)
		(polygon
			(pts
				(arc
					(start 158.009336 -227.91674)
					(mid 157.356556 -227.91674)
					(end 158.009336 -227.91674)
				)
			)
		)
	)
	(zone
		(layers "B.Cu" "In4.Cu" "In6.Cu" "In11.Cu" "In13.Cu" "In15.Cu")
		(hatch none 0.5)
		(connect_pads
			(clearance 0)
		)
		(min_thickness 0.25)
		(keepout
			(tracks not_allowed)
			(vias allowed)
			(pads allowed)
			(copperpour not_allowed)
			(footprints allowed)
		)
		(placement
			(enabled no)
			(sheetname "")
		)
		(fill yes
			(thermal_gap 0.5)
			(thermal_bridge_width 0.5)
			(island_removal_mode 0)
		)
		(polygon
			(pts
				(arc
					(start 338.291424 -243.922804)
					(mid 337.638644 -243.922804)
					(end 338.291424 -243.922804)
				)
			)
		)
	)
	(zone
		(layers "B.Cu" "In4.Cu" "In6.Cu" "In11.Cu" "In13.Cu" "In15.Cu")
		(hatch none 0.5)
		(connect_pads
			(clearance 0)
		)
		(min_thickness 0.25)
		(keepout
			(tracks not_allowed)
			(vias allowed)
			(pads allowed)
			(copperpour not_allowed)
			(footprints allowed)
		)
		(placement
			(enabled no)
			(sheetname "")
		)
		(fill yes
			(thermal_gap 0.5)
			(thermal_bridge_width 0.5)
			(island_removal_mode 0)
		)
		(polygon
			(pts
				(arc
					(start 83.373468 -407.00452)
					(mid 82.669888 -407.00452)
					(end 83.373468 -407.00452)
				)
			)
		)
	)
	(zone
		(layers "B.Cu" "In4.Cu" "In6.Cu" "In11.Cu" "In13.Cu" "In15.Cu")
		(hatch none 0.5)
		(connect_pads
			(clearance 0)
		)
		(min_thickness 0.25)
		(keepout
			(tracks not_allowed)
			(vias allowed)
			(pads allowed)
			(copperpour not_allowed)
			(footprints allowed)
		)
		(placement
			(enabled no)
			(sheetname "")
		)
		(fill yes
			(thermal_gap 0.5)
			(thermal_bridge_width 0.5)
			(island_removal_mode 0)
		)
		(polygon
			(pts
				(arc
					(start 24.267668 -19.13636)
					(mid 23.564088 -19.13636)
					(end 24.267668 -19.13636)
				)
			)
		)
	)
	(zone
		(layers "B.Cu" "In4.Cu" "In6.Cu" "In11.Cu" "In13.Cu" "In15.Cu")
		(hatch none 0.5)
		(connect_pads
			(clearance 0)
		)
		(min_thickness 0.25)
		(keepout
			(tracks not_allowed)
			(vias allowed)
			(pads allowed)
			(copperpour not_allowed)
			(footprints allowed)
		)
		(placement
			(enabled no)
			(sheetname "")
		)
		(fill yes
			(thermal_gap 0.5)
			(thermal_bridge_width 0.5)
			(island_removal_mode 0)
		)
		(polygon
			(pts
				(arc
					(start 90.461084 -270.19758)
					(mid 89.808304 -270.19758)
					(end 90.461084 -270.19758)
				)
			)
		)
	)
	(zone
		(layers "B.Cu" "In4.Cu" "In6.Cu" "In11.Cu" "In13.Cu" "In15.Cu")
		(hatch none 0.5)
		(connect_pads
			(clearance 0)
		)
		(min_thickness 0.25)
		(keepout
			(tracks not_allowed)
			(vias allowed)
			(pads allowed)
			(copperpour not_allowed)
			(footprints allowed)
		)
		(placement
			(enabled no)
			(sheetname "")
		)
		(fill yes
			(thermal_gap 0.5)
			(thermal_bridge_width 0.5)
			(island_removal_mode 0)
		)
		(polygon
			(pts
				(arc
					(start 380.692406 -255.547622)
					(mid 380.039626 -255.547622)
					(end 380.692406 -255.547622)
				)
			)
		)
	)
	(zone
		(layers "B.Cu" "In4.Cu" "In6.Cu" "In11.Cu" "In13.Cu" "In15.Cu")
		(hatch none 0.5)
		(connect_pads
			(clearance 0)
		)
		(min_thickness 0.25)
		(keepout
			(tracks not_allowed)
			(vias allowed)
			(pads allowed)
			(copperpour not_allowed)
			(footprints allowed)
		)
		(placement
			(enabled no)
			(sheetname "")
		)
		(fill yes
			(thermal_gap 0.5)
			(thermal_bridge_width 0.5)
			(island_removal_mode 0)
		)
		(polygon
			(pts
				(arc
					(start 134.052056 -230.086662)
					(mid 133.399276 -230.086662)
					(end 134.052056 -230.086662)
				)
			)
		)
	)
	(zone
		(layers "B.Cu" "In4.Cu" "In6.Cu" "In11.Cu" "In13.Cu" "In15.Cu")
		(hatch none 0.5)
		(connect_pads
			(clearance 0)
		)
		(min_thickness 0.25)
		(keepout
			(tracks not_allowed)
			(vias allowed)
			(pads allowed)
			(copperpour not_allowed)
			(footprints allowed)
		)
		(placement
			(enabled no)
			(sheetname "")
		)
		(fill yes
			(thermal_gap 0.5)
			(thermal_bridge_width 0.5)
			(island_removal_mode 0)
		)
		(polygon
			(pts
				(arc
					(start 177.222404 -248.31675)
					(mid 176.569624 -248.31675)
					(end 177.222404 -248.31675)
				)
			)
		)
	)
	(zone
		(layers "B.Cu" "In4.Cu" "In6.Cu" "In11.Cu" "In13.Cu" "In15.Cu")
		(hatch none 0.5)
		(connect_pads
			(clearance 0)
		)
		(min_thickness 0.25)
		(keepout
			(tracks not_allowed)
			(vias allowed)
			(pads allowed)
			(copperpour not_allowed)
			(footprints allowed)
		)
		(placement
			(enabled no)
			(sheetname "")
		)
		(fill yes
			(thermal_gap 0.5)
			(thermal_bridge_width 0.5)
			(island_removal_mode 0)
		)
		(polygon
			(pts
				(arc
					(start 92.230956 -248.806208)
					(mid 91.578176 -248.806208)
					(end 92.230956 -248.806208)
				)
			)
		)
	)
	(zone
		(layers "B.Cu" "In4.Cu" "In6.Cu" "In11.Cu" "In13.Cu" "In15.Cu")
		(hatch none 0.5)
		(connect_pads
			(clearance 0)
		)
		(min_thickness 0.25)
		(keepout
			(tracks not_allowed)
			(vias allowed)
			(pads allowed)
			(copperpour not_allowed)
			(footprints allowed)
		)
		(placement
			(enabled no)
			(sheetname "")
		)
		(fill yes
			(thermal_gap 0.5)
			(thermal_bridge_width 0.5)
			(island_removal_mode 0)
		)
		(polygon
			(pts
				(arc
					(start 134.052056 -233.34218)
					(mid 133.399276 -233.34218)
					(end 134.052056 -233.34218)
				)
			)
		)
	)
	(zone
		(layers "B.Cu" "In4.Cu" "In6.Cu" "In11.Cu" "In13.Cu" "In15.Cu")
		(hatch none 0.5)
		(connect_pads
			(clearance 0)
		)
		(min_thickness 0.25)
		(keepout
			(tracks not_allowed)
			(vias allowed)
			(pads allowed)
			(copperpour not_allowed)
			(footprints allowed)
		)
		(placement
			(enabled no)
			(sheetname "")
		)
		(fill yes
			(thermal_gap 0.5)
			(thermal_bridge_width 0.5)
			(island_removal_mode 0)
		)
		(polygon
			(pts
				(arc
					(start 93.426788 -407.00452)
					(mid 92.723208 -407.00452)
					(end 93.426788 -407.00452)
				)
			)
		)
	)
	(zone
		(layers "B.Cu" "In4.Cu" "In6.Cu" "In11.Cu" "In13.Cu" "In15.Cu")
		(hatch none 0.5)
		(connect_pads
			(clearance 0)
		)
		(min_thickness 0.25)
		(keepout
			(tracks not_allowed)
			(vias allowed)
			(pads allowed)
			(copperpour not_allowed)
			(footprints allowed)
		)
		(placement
			(enabled no)
			(sheetname "")
		)
		(fill yes
			(thermal_gap 0.5)
			(thermal_bridge_width 0.5)
			(island_removal_mode 0)
		)
		(polygon
			(pts
				(arc
					(start 421.062404 -259.366766)
					(mid 420.409624 -259.366766)
					(end 421.062404 -259.366766)
				)
			)
		)
	)
	(zone
		(layers "B.Cu" "In4.Cu" "In6.Cu" "In11.Cu" "In13.Cu" "In15.Cu")
		(hatch none 0.5)
		(connect_pads
			(clearance 0)
		)
		(min_thickness 0.25)
		(keepout
			(tracks not_allowed)
			(vias allowed)
			(pads allowed)
			(copperpour not_allowed)
			(footprints allowed)
		)
		(placement
			(enabled no)
			(sheetname "")
		)
		(fill yes
			(thermal_gap 0.5)
			(thermal_bridge_width 0.5)
			(island_removal_mode 0)
		)
		(polygon
			(pts
				(arc
					(start 50.541428 -407.00452)
					(mid 49.837848 -407.00452)
					(end 50.541428 -407.00452)
				)
			)
		)
	)
	(zone
		(layers "B.Cu" "In4.Cu" "In6.Cu" "In11.Cu" "In13.Cu" "In15.Cu")
		(hatch none 0.5)
		(connect_pads
			(clearance 0)
		)
		(min_thickness 0.25)
		(keepout
			(tracks not_allowed)
			(vias allowed)
			(pads allowed)
			(copperpour not_allowed)
			(footprints allowed)
		)
		(placement
			(enabled no)
			(sheetname "")
		)
		(fill yes
			(thermal_gap 0.5)
			(thermal_bridge_width 0.5)
			(island_removal_mode 0)
		)
		(polygon
			(pts
				(arc
					(start 51.390804 -218.566746)
					(mid 50.738024 -218.566746)
					(end 51.390804 -218.566746)
				)
			)
		)
	)
	(zone
		(layers "B.Cu" "In4.Cu" "In6.Cu" "In11.Cu" "In13.Cu" "In15.Cu")
		(hatch none 0.5)
		(connect_pads
			(clearance 0)
		)
		(min_thickness 0.25)
		(keepout
			(tracks not_allowed)
			(vias allowed)
			(pads allowed)
			(copperpour not_allowed)
			(footprints allowed)
		)
		(placement
			(enabled no)
			(sheetname "")
		)
		(fill yes
			(thermal_gap 0.5)
			(thermal_bridge_width 0.5)
			(island_removal_mode 0)
		)
		(polygon
			(pts
				(arc
					(start 173.122336 -241.516662)
					(mid 172.469556 -241.516662)
					(end 173.122336 -241.516662)
				)
			)
		)
	)
	(zone
		(layers "B.Cu" "In4.Cu" "In6.Cu" "In11.Cu" "In13.Cu" "In15.Cu")
		(hatch none 0.5)
		(connect_pads
			(clearance 0)
		)
		(min_thickness 0.25)
		(keepout
			(tracks not_allowed)
			(vias allowed)
			(pads allowed)
			(copperpour not_allowed)
			(footprints allowed)
		)
		(placement
			(enabled no)
			(sheetname "")
		)
		(fill yes
			(thermal_gap 0.5)
			(thermal_bridge_width 0.5)
			(island_removal_mode 0)
		)
		(polygon
			(pts
				(arc
					(start 115.256056 -223.575626)
					(mid 114.603276 -223.575626)
					(end 115.256056 -223.575626)
				)
			)
		)
	)
	(zone
		(layers "B.Cu" "In4.Cu" "In6.Cu" "In11.Cu" "In13.Cu" "In15.Cu")
		(hatch none 0.5)
		(connect_pads
			(clearance 0)
		)
		(min_thickness 0.25)
		(keepout
			(tracks not_allowed)
			(vias allowed)
			(pads allowed)
			(copperpour not_allowed)
			(footprints allowed)
		)
		(placement
			(enabled no)
			(sheetname "")
		)
		(fill yes
			(thermal_gap 0.5)
			(thermal_bridge_width 0.5)
			(island_removal_mode 0)
		)
		(polygon
			(pts
				(arc
					(start 384.81127 -221.94774)
					(mid 384.15849 -221.94774)
					(end 384.81127 -221.94774)
				)
			)
		)
	)
	(zone
		(layers "B.Cu" "In4.Cu" "In6.Cu" "In11.Cu" "In13.Cu" "In15.Cu")
		(hatch none 0.5)
		(connect_pads
			(clearance 0)
		)
		(min_thickness 0.25)
		(keepout
			(tracks not_allowed)
			(vias allowed)
			(pads allowed)
			(copperpour not_allowed)
			(footprints allowed)
		)
		(placement
			(enabled no)
			(sheetname "")
		)
		(fill yes
			(thermal_gap 0.5)
			(thermal_bridge_width 0.5)
			(island_removal_mode 0)
		)
		(polygon
			(pts
				(arc
					(start 405.949404 -299.316648)
					(mid 405.296624 -299.316648)
					(end 405.949404 -299.316648)
				)
			)
		)
	)
	(zone
		(layers "B.Cu" "In4.Cu" "In6.Cu" "In11.Cu" "In13.Cu" "In15.Cu")
		(hatch none 0.5)
		(connect_pads
			(clearance 0)
		)
		(min_thickness 0.25)
		(keepout
			(tracks not_allowed)
			(vias allowed)
			(pads allowed)
			(copperpour not_allowed)
			(footprints allowed)
		)
		(placement
			(enabled no)
			(sheetname "")
		)
		(fill yes
			(thermal_gap 0.5)
			(thermal_bridge_width 0.5)
			(island_removal_mode 0)
		)
		(polygon
			(pts
				(arc
					(start 425.162472 -204.96657)
					(mid 424.509692 -204.96657)
					(end 425.162472 -204.96657)
				)
			)
		)
	)
	(zone
		(layers "B.Cu" "In4.Cu" "In6.Cu" "In11.Cu" "In13.Cu" "In15.Cu")
		(hatch none 0.5)
		(connect_pads
			(clearance 0)
		)
		(min_thickness 0.25)
		(keepout
			(tracks not_allowed)
			(vias allowed)
			(pads allowed)
			(copperpour not_allowed)
			(footprints allowed)
		)
		(placement
			(enabled no)
			(sheetname "")
		)
		(fill yes
			(thermal_gap 0.5)
			(thermal_bridge_width 0.5)
			(island_removal_mode 0)
		)
		(polygon
			(pts
				(arc
					(start 381.632206 -262.058658)
					(mid 380.979426 -262.058658)
					(end 381.632206 -262.058658)
				)
			)
		)
	)
	(zone
		(layers "B.Cu" "In4.Cu" "In6.Cu" "In11.Cu" "In13.Cu" "In15.Cu")
		(hatch none 0.5)
		(connect_pads
			(clearance 0)
		)
		(min_thickness 0.25)
		(keepout
			(tracks not_allowed)
			(vias allowed)
			(pads allowed)
			(copperpour not_allowed)
			(footprints allowed)
		)
		(placement
			(enabled no)
			(sheetname "")
		)
		(fill yes
			(thermal_gap 0.5)
			(thermal_bridge_width 0.5)
			(island_removal_mode 0)
		)
		(polygon
			(pts
				(arc
					(start 299.356272 -276.366986)
					(mid 298.703492 -276.366986)
					(end 299.356272 -276.366986)
				)
			)
		)
	)
	(zone
		(layers "B.Cu" "In4.Cu" "In6.Cu" "In11.Cu" "In13.Cu" "In15.Cu")
		(hatch none 0.5)
		(connect_pads
			(clearance 0)
		)
		(min_thickness 0.25)
		(keepout
			(tracks not_allowed)
			(vias allowed)
			(pads allowed)
			(copperpour not_allowed)
			(footprints allowed)
		)
		(placement
			(enabled no)
			(sheetname "")
		)
		(fill yes
			(thermal_gap 0.5)
			(thermal_bridge_width 0.5)
			(island_removal_mode 0)
		)
		(polygon
			(pts
				(arc
					(start 337.351624 -235.783882)
					(mid 336.698844 -235.783882)
					(end 337.351624 -235.783882)
				)
			)
		)
	)
	(zone
		(layers "B.Cu" "In4.Cu" "In6.Cu" "In11.Cu" "In13.Cu" "In15.Cu")
		(hatch none 0.5)
		(connect_pads
			(clearance 0)
		)
		(min_thickness 0.25)
		(keepout
			(tracks not_allowed)
			(vias allowed)
			(pads allowed)
			(copperpour not_allowed)
			(footprints allowed)
		)
		(placement
			(enabled no)
			(sheetname "")
		)
		(fill yes
			(thermal_gap 0.5)
			(thermal_bridge_width 0.5)
			(island_removal_mode 0)
		)
		(polygon
			(pts
				(arc
					(start 118.075202 -225.203258)
					(mid 117.422422 -225.203258)
					(end 118.075202 -225.203258)
				)
			)
		)
	)
	(zone
		(layers "B.Cu" "In4.Cu" "In6.Cu" "In11.Cu" "In13.Cu" "In15.Cu")
		(hatch none 0.5)
		(connect_pads
			(clearance 0)
		)
		(min_thickness 0.25)
		(keepout
			(tracks not_allowed)
			(vias allowed)
			(pads allowed)
			(copperpour not_allowed)
			(footprints allowed)
		)
		(placement
			(enabled no)
			(sheetname "")
		)
		(fill yes
			(thermal_gap 0.5)
			(thermal_bridge_width 0.5)
			(island_removal_mode 0)
		)
		(polygon
			(pts
				(arc
					(start 425.162472 -274.66671)
					(mid 424.509692 -274.66671)
					(end 425.162472 -274.66671)
				)
			)
		)
	)
	(zone
		(layers "B.Cu" "In4.Cu" "In6.Cu" "In11.Cu" "In13.Cu" "In15.Cu")
		(hatch none 0.5)
		(connect_pads
			(clearance 0)
		)
		(min_thickness 0.25)
		(keepout
			(tracks not_allowed)
			(vias allowed)
			(pads allowed)
			(copperpour not_allowed)
			(footprints allowed)
		)
		(placement
			(enabled no)
			(sheetname "")
		)
		(fill yes
			(thermal_gap 0.5)
			(thermal_bridge_width 0.5)
			(island_removal_mode 0)
		)
		(polygon
			(pts
				(arc
					(start 328.085704 -0.048006)
					(mid 327.382124 -0.048006)
					(end 328.085704 -0.048006)
				)
			)
		)
	)
	(zone
		(layers "B.Cu" "In4.Cu" "In6.Cu" "In11.Cu" "In13.Cu" "In15.Cu")
		(hatch none 0.5)
		(connect_pads
			(clearance 0)
		)
		(min_thickness 0.25)
		(keepout
			(tracks not_allowed)
			(vias allowed)
			(pads allowed)
			(copperpour not_allowed)
			(footprints allowed)
		)
		(placement
			(enabled no)
			(sheetname "")
		)
		(fill yes
			(thermal_gap 0.5)
			(thermal_bridge_width 0.5)
			(island_removal_mode 0)
		)
		(polygon
			(pts
				(arc
					(start 338.76107 -231.714548)
					(mid 338.10829 -231.714548)
					(end 338.76107 -231.714548)
				)
			)
		)
	)
	(zone
		(layers "B.Cu" "In4.Cu" "In6.Cu" "In11.Cu" "In13.Cu" "In15.Cu")
		(hatch none 0.5)
		(connect_pads
			(clearance 0)
		)
		(min_thickness 0.25)
		(keepout
			(tracks not_allowed)
			(vias allowed)
			(pads allowed)
			(copperpour not_allowed)
			(footprints allowed)
		)
		(placement
			(enabled no)
			(sheetname "")
		)
		(fill yes
			(thermal_gap 0.5)
			(thermal_bridge_width 0.5)
			(island_removal_mode 0)
		)
		(polygon
			(pts
				(arc
					(start 383.511806 -276.708616)
					(mid 382.859026 -276.708616)
					(end 383.511806 -276.708616)
				)
			)
		)
	)
	(zone
		(layers "B.Cu" "In4.Cu" "In6.Cu" "In11.Cu" "In13.Cu" "In15.Cu")
		(hatch none 0.5)
		(connect_pads
			(clearance 0)
		)
		(min_thickness 0.25)
		(keepout
			(tracks not_allowed)
			(vias allowed)
			(pads allowed)
			(copperpour not_allowed)
			(footprints allowed)
		)
		(placement
			(enabled no)
			(sheetname "")
		)
		(fill yes
			(thermal_gap 0.5)
			(thermal_bridge_width 0.5)
			(island_removal_mode 0)
		)
		(polygon
			(pts
				(arc
					(start 338.871306 -285.661354)
					(mid 338.218526 -285.661354)
					(end 338.871306 -285.661354)
				)
			)
		)
	)
	(zone
		(layers "B.Cu" "In4.Cu" "In6.Cu" "In11.Cu" "In13.Cu" "In15.Cu")
		(hatch none 0.5)
		(connect_pads
			(clearance 0)
		)
		(min_thickness 0.25)
		(keepout
			(tracks not_allowed)
			(vias allowed)
			(pads allowed)
			(copperpour not_allowed)
			(footprints allowed)
		)
		(placement
			(enabled no)
			(sheetname "")
		)
		(fill yes
			(thermal_gap 0.5)
			(thermal_bridge_width 0.5)
			(island_removal_mode 0)
		)
		(polygon
			(pts
				(arc
					(start 51.416204 -265.316716)
					(mid 50.763424 -265.316716)
					(end 51.416204 -265.316716)
				)
			)
		)
	)
	(zone
		(layers "B.Cu" "In4.Cu" "In6.Cu" "In11.Cu" "In13.Cu" "In15.Cu")
		(hatch none 0.5)
		(connect_pads
			(clearance 0)
		)
		(min_thickness 0.25)
		(keepout
			(tracks not_allowed)
			(vias allowed)
			(pads allowed)
			(copperpour not_allowed)
			(footprints allowed)
		)
		(placement
			(enabled no)
			(sheetname "")
		)
		(fill yes
			(thermal_gap 0.5)
			(thermal_bridge_width 0.5)
			(island_removal_mode 0)
		)
		(polygon
			(pts
				(arc
					(start 425.162472 -244.916706)
					(mid 424.509692 -244.916706)
					(end 425.162472 -244.916706)
				)
			)
		)
	)
	(zone
		(layers "B.Cu" "In4.Cu" "In6.Cu" "In11.Cu" "In13.Cu" "In15.Cu")
		(hatch none 0.5)
		(connect_pads
			(clearance 0)
		)
		(min_thickness 0.25)
		(keepout
			(tracks not_allowed)
			(vias allowed)
			(pads allowed)
			(copperpour not_allowed)
			(footprints allowed)
		)
		(placement
			(enabled no)
			(sheetname "")
		)
		(fill yes
			(thermal_gap 0.5)
			(thermal_bridge_width 0.5)
			(island_removal_mode 0)
		)
		(polygon
			(pts
				(arc
					(start 381.632206 -271.825212)
					(mid 380.979426 -271.825212)
					(end 381.632206 -271.825212)
				)
			)
		)
	)
	(zone
		(layers "B.Cu" "In4.Cu" "In6.Cu" "In11.Cu" "In13.Cu" "In15.Cu")
		(hatch none 0.5)
		(connect_pads
			(clearance 0)
		)
		(min_thickness 0.25)
		(keepout
			(tracks not_allowed)
			(vias allowed)
			(pads allowed)
			(copperpour not_allowed)
			(footprints allowed)
		)
		(placement
			(enabled no)
			(sheetname "")
		)
		(fill yes
			(thermal_gap 0.5)
			(thermal_bridge_width 0.5)
			(island_removal_mode 0)
		)
		(polygon
			(pts
				(arc
					(start 295.230804 -216.866724)
					(mid 294.578024 -216.866724)
					(end 295.230804 -216.866724)
				)
			)
		)
	)
	(zone
		(layers "B.Cu" "In4.Cu" "In6.Cu" "In11.Cu" "In13.Cu" "In15.Cu")
		(hatch none 0.5)
		(connect_pads
			(clearance 0)
		)
		(min_thickness 0.25)
		(keepout
			(tracks not_allowed)
			(vias allowed)
			(pads allowed)
			(copperpour not_allowed)
			(footprints allowed)
		)
		(placement
			(enabled no)
			(sheetname "")
		)
		(fill yes
			(thermal_gap 0.5)
			(thermal_bridge_width 0.5)
			(island_removal_mode 0)
		)
		(polygon
			(pts
				(arc
					(start 365.545624 -224.389442)
					(mid 364.892844 -224.389442)
					(end 365.545624 -224.389442)
				)
			)
		)
	)
	(zone
		(layers "B.Cu" "In4.Cu" "In6.Cu" "In11.Cu" "In13.Cu" "In15.Cu")
		(hatch none 0.5)
		(connect_pads
			(clearance 0)
		)
		(min_thickness 0.25)
		(keepout
			(tracks not_allowed)
			(vias allowed)
			(pads allowed)
			(copperpour not_allowed)
			(footprints allowed)
		)
		(placement
			(enabled no)
			(sheetname "")
		)
		(fill yes
			(thermal_gap 0.5)
			(thermal_bridge_width 0.5)
			(island_removal_mode 0)
		)
		(polygon
			(pts
				(arc
					(start 173.122336 -275.516594)
					(mid 172.469556 -275.516594)
					(end 173.122336 -275.516594)
				)
			)
		)
	)
	(zone
		(layers "B.Cu" "In4.Cu" "In6.Cu" "In11.Cu" "In13.Cu" "In15.Cu")
		(hatch none 0.5)
		(connect_pads
			(clearance 0)
		)
		(min_thickness 0.25)
		(keepout
			(tracks not_allowed)
			(vias allowed)
			(pads allowed)
			(copperpour not_allowed)
			(footprints allowed)
		)
		(placement
			(enabled no)
			(sheetname "")
		)
		(fill yes
			(thermal_gap 0.5)
			(thermal_bridge_width 0.5)
			(island_removal_mode 0)
		)
		(polygon
			(pts
				(arc
					(start 134.161784 -275.8948)
					(mid 133.509004 -275.8948)
					(end 134.161784 -275.8948)
				)
			)
		)
	)
	(zone
		(layers "B.Cu" "In4.Cu" "In6.Cu" "In11.Cu" "In13.Cu" "In15.Cu")
		(hatch none 0.5)
		(connect_pads
			(clearance 0)
		)
		(min_thickness 0.25)
		(keepout
			(tracks not_allowed)
			(vias allowed)
			(pads allowed)
			(copperpour not_allowed)
			(footprints allowed)
		)
		(placement
			(enabled no)
			(sheetname "")
		)
		(fill yes
			(thermal_gap 0.5)
			(thermal_bridge_width 0.5)
			(island_removal_mode 0)
		)
		(polygon
			(pts
				(arc
					(start 47.290736 -314.616592)
					(mid 46.637956 -314.616592)
					(end 47.290736 -314.616592)
				)
			)
		)
	)
	(zone
		(layers "B.Cu" "In4.Cu" "In6.Cu" "In11.Cu" "In13.Cu" "In15.Cu")
		(hatch none 0.5)
		(connect_pads
			(clearance 0)
		)
		(min_thickness 0.25)
		(keepout
			(tracks not_allowed)
			(vias allowed)
			(pads allowed)
			(copperpour not_allowed)
			(footprints allowed)
		)
		(placement
			(enabled no)
			(sheetname "")
		)
		(fill yes
			(thermal_gap 0.5)
			(thermal_bridge_width 0.5)
			(island_removal_mode 0)
		)
		(polygon
			(pts
				(arc
					(start 410.049472 -306.116736)
					(mid 409.396692 -306.116736)
					(end 410.049472 -306.116736)
				)
			)
		)
	)
	(zone
		(layers "B.Cu" "In4.Cu" "In6.Cu" "In11.Cu" "In13.Cu" "In15.Cu")
		(hatch none 0.5)
		(connect_pads
			(clearance 0)
		)
		(min_thickness 0.25)
		(keepout
			(tracks not_allowed)
			(vias allowed)
			(pads allowed)
			(copperpour not_allowed)
			(footprints allowed)
		)
		(placement
			(enabled no)
			(sheetname "")
		)
		(fill yes
			(thermal_gap 0.5)
			(thermal_bridge_width 0.5)
			(island_removal_mode 0)
		)
		(polygon
			(pts
				(arc
					(start 53.604668 -407.00452)
					(mid 52.901088 -407.00452)
					(end 53.604668 -407.00452)
				)
			)
		)
	)
	(zone
		(layers "B.Cu" "In4.Cu" "In6.Cu" "In11.Cu" "In13.Cu" "In15.Cu")
		(hatch none 0.5)
		(connect_pads
			(clearance 0)
		)
		(min_thickness 0.25)
		(keepout
			(tracks not_allowed)
			(vias allowed)
			(pads allowed)
			(copperpour not_allowed)
			(footprints allowed)
		)
		(placement
			(enabled no)
			(sheetname "")
		)
		(fill yes
			(thermal_gap 0.5)
			(thermal_bridge_width 0.5)
			(island_removal_mode 0)
		)
		(polygon
			(pts
				(arc
					(start 381.992124 -236.597952)
					(mid 381.339344 -236.597952)
					(end 381.992124 -236.597952)
				)
			)
		)
	)
	(zone
		(layers "B.Cu" "In4.Cu" "In6.Cu" "In11.Cu" "In13.Cu" "In15.Cu")
		(hatch none 0.5)
		(connect_pads
			(clearance 0)
		)
		(min_thickness 0.25)
		(keepout
			(tracks not_allowed)
			(vias allowed)
			(pads allowed)
			(copperpour not_allowed)
			(footprints allowed)
		)
		(placement
			(enabled no)
			(sheetname "")
		)
		(fill yes
			(thermal_gap 0.5)
			(thermal_bridge_width 0.5)
			(island_removal_mode 0)
		)
		(polygon
			(pts
				(arc
					(start 91.760802 -249.620024)
					(mid 91.108022 -249.620024)
					(end 91.760802 -249.620024)
				)
			)
		)
	)
	(zone
		(layers "B.Cu" "In4.Cu" "In6.Cu" "In11.Cu" "In13.Cu" "In15.Cu")
		(hatch none 0.5)
		(connect_pads
			(clearance 0)
		)
		(min_thickness 0.25)
		(keepout
			(tracks not_allowed)
			(vias allowed)
			(pads allowed)
			(copperpour not_allowed)
			(footprints allowed)
		)
		(placement
			(enabled no)
			(sheetname "")
		)
		(fill yes
			(thermal_gap 0.5)
			(thermal_bridge_width 0.5)
			(island_removal_mode 0)
		)
		(polygon
			(pts
				(arc
					(start 91.401138 -255.547622)
					(mid 90.748358 -255.547622)
					(end 91.401138 -255.547622)
				)
			)
		)
	)
	(zone
		(layers "B.Cu" "In4.Cu" "In6.Cu" "In11.Cu" "In13.Cu" "In15.Cu")
		(hatch none 0.5)
		(connect_pads
			(clearance 0)
		)
		(min_thickness 0.25)
		(keepout
			(tracks not_allowed)
			(vias allowed)
			(pads allowed)
			(copperpour not_allowed)
			(footprints allowed)
		)
		(placement
			(enabled no)
			(sheetname "")
		)
		(fill yes
			(thermal_gap 0.5)
			(thermal_bridge_width 0.5)
			(island_removal_mode 0)
		)
		(polygon
			(pts
				(arc
					(start 295.230804 -274.66671)
					(mid 294.578024 -274.66671)
					(end 295.230804 -274.66671)
				)
			)
		)
	)
	(zone
		(layers "B.Cu" "In4.Cu" "In6.Cu" "In11.Cu" "In13.Cu" "In15.Cu")
		(hatch none 0.5)
		(connect_pads
			(clearance 0)
		)
		(min_thickness 0.25)
		(keepout
			(tracks not_allowed)
			(vias allowed)
			(pads allowed)
			(copperpour not_allowed)
			(footprints allowed)
		)
		(placement
			(enabled no)
			(sheetname "")
		)
		(fill yes
			(thermal_gap 0.5)
			(thermal_bridge_width 0.5)
			(island_removal_mode 0)
		)
		(polygon
			(pts
				(arc
					(start 337.351624 -240.667286)
					(mid 336.698844 -240.667286)
					(end 337.351624 -240.667286)
				)
			)
		)
	)
	(zone
		(layers "B.Cu" "In4.Cu" "In6.Cu" "In11.Cu" "In13.Cu" "In15.Cu")
		(hatch none 0.5)
		(connect_pads
			(clearance 0)
		)
		(min_thickness 0.25)
		(keepout
			(tracks not_allowed)
			(vias allowed)
			(pads allowed)
			(copperpour not_allowed)
			(footprints allowed)
		)
		(placement
			(enabled no)
			(sheetname "")
		)
		(fill yes
			(thermal_gap 0.5)
			(thermal_bridge_width 0.5)
			(island_removal_mode 0)
		)
		(polygon
			(pts
				(arc
					(start 299.356272 -270.416782)
					(mid 298.703492 -270.416782)
					(end 299.356272 -270.416782)
				)
			)
		)
	)
	(zone
		(layers "B.Cu" "In4.Cu" "In6.Cu" "In11.Cu" "In13.Cu" "In15.Cu")
		(hatch none 0.5)
		(connect_pads
			(clearance 0)
		)
		(min_thickness 0.25)
		(keepout
			(tracks not_allowed)
			(vias allowed)
			(pads allowed)
			(copperpour not_allowed)
			(footprints allowed)
		)
		(placement
			(enabled no)
			(sheetname "")
		)
		(fill yes
			(thermal_gap 0.5)
			(thermal_bridge_width 0.5)
			(island_removal_mode 0)
		)
		(polygon
			(pts
				(arc
					(start 134.161784 -269.38351)
					(mid 133.509004 -269.38351)
					(end 134.161784 -269.38351)
				)
			)
		)
	)
	(zone
		(layers "B.Cu" "In4.Cu" "In6.Cu" "In11.Cu" "In13.Cu" "In15.Cu")
		(hatch none 0.5)
		(connect_pads
			(clearance 0)
		)
		(min_thickness 0.25)
		(keepout
			(tracks not_allowed)
			(vias allowed)
			(pads allowed)
			(copperpour not_allowed)
			(footprints allowed)
		)
		(placement
			(enabled no)
			(sheetname "")
		)
		(fill yes
			(thermal_gap 0.5)
			(thermal_bridge_width 0.5)
			(island_removal_mode 0)
		)
		(polygon
			(pts
				(arc
					(start 373.643652 -285.661354)
					(mid 372.990872 -285.661354)
					(end 373.643652 -285.661354)
				)
			)
		)
	)
	(zone
		(layers "B.Cu" "In4.Cu" "In6.Cu" "In11.Cu" "In13.Cu" "In15.Cu")
		(hatch none 0.5)
		(connect_pads
			(clearance 0)
		)
		(min_thickness 0.25)
		(keepout
			(tracks not_allowed)
			(vias allowed)
			(pads allowed)
			(copperpour not_allowed)
			(footprints allowed)
		)
		(placement
			(enabled no)
			(sheetname "")
		)
		(fill yes
			(thermal_gap 0.5)
			(thermal_bridge_width 0.5)
			(island_removal_mode 0)
		)
		(polygon
			(pts
				(arc
					(start 90.351356 -239.0394)
					(mid 89.698576 -239.0394)
					(end 90.351356 -239.0394)
				)
			)
		)
	)
	(zone
		(layers "B.Cu" "In4.Cu" "In6.Cu" "In11.Cu" "In13.Cu" "In15.Cu")
		(hatch none 0.5)
		(connect_pads
			(clearance 0)
		)
		(min_thickness 0.25)
		(keepout
			(tracks not_allowed)
			(vias allowed)
			(pads allowed)
			(copperpour not_allowed)
			(footprints allowed)
		)
		(placement
			(enabled no)
			(sheetname "")
		)
		(fill yes
			(thermal_gap 0.5)
			(thermal_bridge_width 0.5)
			(island_removal_mode 0)
		)
		(polygon
			(pts
				(arc
					(start 299.330872 -221.96679)
					(mid 298.678092 -221.96679)
					(end 299.330872 -221.96679)
				)
			)
		)
	)
	(zone
		(layers "B.Cu" "In4.Cu" "In6.Cu" "In11.Cu" "In13.Cu" "In15.Cu")
		(hatch none 0.5)
		(connect_pads
			(clearance 0)
		)
		(min_thickness 0.25)
		(keepout
			(tracks not_allowed)
			(vias allowed)
			(pads allowed)
			(copperpour not_allowed)
			(footprints allowed)
		)
		(placement
			(enabled no)
			(sheetname "")
		)
		(fill yes
			(thermal_gap 0.5)
			(thermal_bridge_width 0.5)
			(island_removal_mode 0)
		)
		(polygon
			(pts
				(arc
					(start 299.356272 -313.766708)
					(mid 298.703492 -313.766708)
					(end 299.356272 -313.766708)
				)
			)
		)
	)
	(zone
		(layers "B.Cu" "In4.Cu" "In6.Cu" "In11.Cu" "In13.Cu" "In15.Cu")
		(hatch none 0.5)
		(connect_pads
			(clearance 0)
		)
		(min_thickness 0.25)
		(keepout
			(tracks not_allowed)
			(vias allowed)
			(pads allowed)
			(copperpour not_allowed)
			(footprints allowed)
		)
		(placement
			(enabled no)
			(sheetname "")
		)
		(fill yes
			(thermal_gap 0.5)
			(thermal_bridge_width 0.5)
			(island_removal_mode 0)
		)
		(polygon
			(pts
				(arc
					(start 177.222404 -217.716608)
					(mid 176.569624 -217.716608)
					(end 177.222404 -217.716608)
				)
			)
		)
	)
	(zone
		(layers "B.Cu" "In4.Cu" "In6.Cu" "In11.Cu" "In13.Cu" "In15.Cu")
		(hatch none 0.5)
		(connect_pads
			(clearance 0)
		)
		(min_thickness 0.25)
		(keepout
			(tracks not_allowed)
			(vias allowed)
			(pads allowed)
			(copperpour not_allowed)
			(footprints allowed)
		)
		(placement
			(enabled no)
			(sheetname "")
		)
		(fill yes
			(thermal_gap 0.5)
			(thermal_bridge_width 0.5)
			(island_removal_mode 0)
		)
		(polygon
			(pts
				(arc
					(start 410.049472 -225.36658)
					(mid 409.396692 -225.36658)
					(end 410.049472 -225.36658)
				)
			)
		)
	)
	(zone
		(layers "B.Cu" "In4.Cu" "In6.Cu" "In11.Cu" "In13.Cu" "In15.Cu")
		(hatch none 0.5)
		(connect_pads
			(clearance 0)
		)
		(min_thickness 0.25)
		(keepout
			(tracks not_allowed)
			(vias allowed)
			(pads allowed)
			(copperpour not_allowed)
			(footprints allowed)
		)
		(placement
			(enabled no)
			(sheetname "")
		)
		(fill yes
			(thermal_gap 0.5)
			(thermal_bridge_width 0.5)
			(island_removal_mode 0)
		)
		(polygon
			(pts
				(arc
					(start 341.690452 -285.661354)
					(mid 341.037672 -285.661354)
					(end 341.690452 -285.661354)
				)
			)
		)
	)
	(zone
		(layers "B.Cu" "In4.Cu" "In6.Cu" "In11.Cu" "In13.Cu" "In15.Cu")
		(hatch none 0.5)
		(connect_pads
			(clearance 0)
		)
		(min_thickness 0.25)
		(keepout
			(tracks not_allowed)
			(vias allowed)
			(pads allowed)
			(copperpour not_allowed)
			(footprints allowed)
		)
		(placement
			(enabled no)
			(sheetname "")
		)
		(fill yes
			(thermal_gap 0.5)
			(thermal_bridge_width 0.5)
			(island_removal_mode 0)
		)
		(polygon
			(pts
				(arc
					(start 89.051384 -269.38351)
					(mid 88.398604 -269.38351)
					(end 89.051384 -269.38351)
				)
			)
		)
	)
	(zone
		(layers "B.Cu" "In4.Cu" "In6.Cu" "In11.Cu" "In13.Cu" "In15.Cu")
		(hatch none 0.5)
		(connect_pads
			(clearance 0)
		)
		(min_thickness 0.25)
		(keepout
			(tracks not_allowed)
			(vias allowed)
			(pads allowed)
			(copperpour not_allowed)
			(footprints allowed)
		)
		(placement
			(enabled no)
			(sheetname "")
		)
		(fill yes
			(thermal_gap 0.5)
			(thermal_bridge_width 0.5)
			(island_removal_mode 0)
		)
		(polygon
			(pts
				(arc
					(start 177.222404 -267.016738)
					(mid 176.569624 -267.016738)
					(end 177.222404 -267.016738)
				)
			)
		)
	)
	(zone
		(layers "B.Cu" "In4.Cu" "In6.Cu" "In11.Cu" "In13.Cu" "In15.Cu")
		(hatch none 0.5)
		(connect_pads
			(clearance 0)
		)
		(min_thickness 0.25)
		(keepout
			(tracks not_allowed)
			(vias allowed)
			(pads allowed)
			(copperpour not_allowed)
			(footprints allowed)
		)
		(placement
			(enabled no)
			(sheetname "")
		)
		(fill yes
			(thermal_gap 0.5)
			(thermal_bridge_width 0.5)
			(island_removal_mode 0)
		)
		(polygon
			(pts
				(arc
					(start 405.949404 -227.91674)
					(mid 405.296624 -227.91674)
					(end 405.949404 -227.91674)
				)
			)
		)
	)
	(zone
		(layers "B.Cu" "In4.Cu" "In6.Cu" "In11.Cu" "In13.Cu" "In15.Cu")
		(hatch none 0.5)
		(connect_pads
			(clearance 0)
		)
		(min_thickness 0.25)
		(keepout
			(tracks not_allowed)
			(vias allowed)
			(pads allowed)
			(copperpour not_allowed)
			(footprints allowed)
		)
		(placement
			(enabled no)
			(sheetname "")
		)
		(fill yes
			(thermal_gap 0.5)
			(thermal_bridge_width 0.5)
			(island_removal_mode 0)
		)
		(polygon
			(pts
				(arc
					(start 173.122336 -250.866656)
					(mid 172.469556 -250.866656)
					(end 173.122336 -250.866656)
				)
			)
		)
	)
	(zone
		(layers "B.Cu" "In4.Cu" "In6.Cu" "In11.Cu" "In13.Cu" "In15.Cu")
		(hatch none 0.5)
		(connect_pads
			(clearance 0)
		)
		(min_thickness 0.25)
		(keepout
			(tracks not_allowed)
			(vias allowed)
			(pads allowed)
			(copperpour not_allowed)
			(footprints allowed)
		)
		(placement
			(enabled no)
			(sheetname "")
		)
		(fill yes
			(thermal_gap 0.5)
			(thermal_bridge_width 0.5)
			(island_removal_mode 0)
		)
		(polygon
			(pts
				(arc
					(start 108.207556 -224.389442)
					(mid 107.554776 -224.389442)
					(end 108.207556 -224.389442)
				)
			)
		)
	)
	(zone
		(layers "B.Cu" "In4.Cu" "In6.Cu" "In11.Cu" "In13.Cu" "In15.Cu")
		(hatch none 0.5)
		(connect_pads
			(clearance 0)
		)
		(min_thickness 0.25)
		(keepout
			(tracks not_allowed)
			(vias allowed)
			(pads allowed)
			(copperpour not_allowed)
			(footprints allowed)
		)
		(placement
			(enabled no)
			(sheetname "")
		)
		(fill yes
			(thermal_gap 0.5)
			(thermal_bridge_width 0.5)
			(island_removal_mode 0)
		)
		(polygon
			(pts
				(arc
					(start 337.461352 -266.941808)
					(mid 336.808572 -266.941808)
					(end 337.461352 -266.941808)
				)
			)
		)
	)
	(zone
		(layers "B.Cu" "In4.Cu" "In6.Cu" "In11.Cu" "In13.Cu" "In15.Cu")
		(hatch none 0.5)
		(connect_pads
			(clearance 0)
		)
		(min_thickness 0.25)
		(keepout
			(tracks not_allowed)
			(vias allowed)
			(pads allowed)
			(copperpour not_allowed)
			(footprints allowed)
		)
		(placement
			(enabled no)
			(sheetname "")
		)
		(fill yes
			(thermal_gap 0.5)
			(thermal_bridge_width 0.5)
			(island_removal_mode 0)
		)
		(polygon
			(pts
				(arc
					(start 381.632206 -273.453098)
					(mid 380.979426 -273.453098)
					(end 381.632206 -273.453098)
				)
			)
		)
	)
	(zone
		(layers "B.Cu" "In4.Cu" "In6.Cu" "In11.Cu" "In13.Cu" "In15.Cu")
		(hatch none 0.5)
		(connect_pads
			(clearance 0)
		)
		(min_thickness 0.25)
		(keepout
			(tracks not_allowed)
			(vias allowed)
			(pads allowed)
			(copperpour not_allowed)
			(footprints allowed)
		)
		(placement
			(enabled no)
			(sheetname "")
		)
		(fill yes
			(thermal_gap 0.5)
			(thermal_bridge_width 0.5)
			(island_removal_mode 0)
		)
		(polygon
			(pts
				(arc
					(start 420.986204 -262.766556)
					(mid 420.333424 -262.766556)
					(end 420.986204 -262.766556)
				)
			)
		)
	)
	(zone
		(layers "B.Cu" "In4.Cu" "In6.Cu" "In11.Cu" "In13.Cu" "In15.Cu")
		(hatch none 0.5)
		(connect_pads
			(clearance 0)
		)
		(min_thickness 0.25)
		(keepout
			(tracks not_allowed)
			(vias allowed)
			(pads allowed)
			(copperpour not_allowed)
			(footprints allowed)
		)
		(placement
			(enabled no)
			(sheetname "")
		)
		(fill yes
			(thermal_gap 0.5)
			(thermal_bridge_width 0.5)
			(island_removal_mode 0)
		)
		(polygon
			(pts
				(arc
					(start 131.812538 -257.175254)
					(mid 131.159758 -257.175254)
					(end 131.812538 -257.175254)
				)
			)
		)
	)
	(zone
		(layers "B.Cu" "In4.Cu" "In6.Cu" "In11.Cu" "In13.Cu" "In15.Cu")
		(hatch none 0.5)
		(connect_pads
			(clearance 0)
		)
		(min_thickness 0.25)
		(keepout
			(tracks not_allowed)
			(vias allowed)
			(pads allowed)
			(copperpour not_allowed)
			(footprints allowed)
		)
		(placement
			(enabled no)
			(sheetname "")
		)
		(fill yes
			(thermal_gap 0.5)
			(thermal_bridge_width 0.5)
			(island_removal_mode 0)
		)
		(polygon
			(pts
				(arc
					(start 126.643384 -285.661354)
					(mid 125.990604 -285.661354)
					(end 126.643384 -285.661354)
				)
			)
		)
	)
	(zone
		(layers "B.Cu" "In4.Cu" "In6.Cu" "In11.Cu" "In13.Cu" "In15.Cu")
		(hatch none 0.5)
		(connect_pads
			(clearance 0)
		)
		(min_thickness 0.25)
		(keepout
			(tracks not_allowed)
			(vias allowed)
			(pads allowed)
			(copperpour not_allowed)
			(footprints allowed)
		)
		(placement
			(enabled no)
			(sheetname "")
		)
		(fill yes
			(thermal_gap 0.5)
			(thermal_bridge_width 0.5)
			(island_removal_mode 0)
		)
		(polygon
			(pts
				(arc
					(start 177.222404 -246.616728)
					(mid 176.569624 -246.616728)
					(end 177.222404 -246.616728)
				)
			)
		)
	)
	(zone
		(layers "B.Cu" "In4.Cu" "In6.Cu" "In11.Cu" "In13.Cu" "In15.Cu")
		(hatch none 0.5)
		(connect_pads
			(clearance 0)
		)
		(min_thickness 0.25)
		(keepout
			(tracks not_allowed)
			(vias allowed)
			(pads allowed)
			(copperpour not_allowed)
			(footprints allowed)
		)
		(placement
			(enabled no)
			(sheetname "")
		)
		(fill yes
			(thermal_gap 0.5)
			(thermal_bridge_width 0.5)
			(island_removal_mode 0)
		)
		(polygon
			(pts
				(arc
					(start 314.418472 -223.666558)
					(mid 313.765692 -223.666558)
					(end 314.418472 -223.666558)
				)
			)
		)
	)
	(zone
		(layers "B.Cu" "In4.Cu" "In6.Cu" "In11.Cu" "In13.Cu" "In15.Cu")
		(hatch none 0.5)
		(connect_pads
			(clearance 0)
		)
		(min_thickness 0.25)
		(keepout
			(tracks not_allowed)
			(vias allowed)
			(pads allowed)
			(copperpour not_allowed)
			(footprints allowed)
		)
		(placement
			(enabled no)
			(sheetname "")
		)
		(fill yes
			(thermal_gap 0.5)
			(thermal_bridge_width 0.5)
			(island_removal_mode 0)
		)
		(polygon
			(pts
				(arc
					(start 421.062404 -275.516594)
					(mid 420.409624 -275.516594)
					(end 421.062404 -275.516594)
				)
			)
		)
	)
	(zone
		(layers "B.Cu" "In4.Cu" "In6.Cu" "In11.Cu" "In13.Cu" "In15.Cu")
		(hatch none 0.5)
		(connect_pads
			(clearance 0)
		)
		(min_thickness 0.25)
		(keepout
			(tracks not_allowed)
			(vias allowed)
			(pads allowed)
			(copperpour not_allowed)
			(footprints allowed)
		)
		(placement
			(enabled no)
			(sheetname "")
		)
		(fill yes
			(thermal_gap 0.5)
			(thermal_bridge_width 0.5)
			(island_removal_mode 0)
		)
		(polygon
			(pts
				(arc
					(start 407.157174 -17.601438)
					(mid 406.453594 -17.601438)
					(end 407.157174 -17.601438)
				)
			)
		)
	)
	(zone
		(layers "B.Cu" "In4.Cu" "In6.Cu" "In11.Cu" "In13.Cu" "In15.Cu")
		(hatch none 0.5)
		(connect_pads
			(clearance 0)
		)
		(min_thickness 0.25)
		(keepout
			(tracks not_allowed)
			(vias allowed)
			(pads allowed)
			(copperpour not_allowed)
			(footprints allowed)
		)
		(placement
			(enabled no)
			(sheetname "")
		)
		(fill yes
			(thermal_gap 0.5)
			(thermal_bridge_width 0.5)
			(island_removal_mode 0)
		)
		(polygon
			(pts
				(arc
					(start 382.101852 -272.639282)
					(mid 381.449072 -272.639282)
					(end 382.101852 -272.639282)
				)
			)
		)
	)
	(zone
		(layers "B.Cu" "In4.Cu" "In6.Cu" "In11.Cu" "In13.Cu" "In15.Cu")
		(hatch none 0.5)
		(connect_pads
			(clearance 0)
		)
		(min_thickness 0.25)
		(keepout
			(tracks not_allowed)
			(vias allowed)
			(pads allowed)
			(copperpour not_allowed)
			(footprints allowed)
		)
		(placement
			(enabled no)
			(sheetname "")
		)
		(fill yes
			(thermal_gap 0.5)
			(thermal_bridge_width 0.5)
			(island_removal_mode 0)
		)
		(polygon
			(pts
				(arc
					(start 25.131268 -19.13636)
					(mid 24.427688 -19.13636)
					(end 25.131268 -19.13636)
				)
			)
		)
	)
	(zone
		(layers "B.Cu" "In4.Cu" "In6.Cu" "In11.Cu" "In13.Cu" "In15.Cu")
		(hatch none 0.5)
		(connect_pads
			(clearance 0)
		)
		(min_thickness 0.25)
		(keepout
			(tracks not_allowed)
			(vias allowed)
			(pads allowed)
			(copperpour not_allowed)
			(footprints allowed)
		)
		(placement
			(enabled no)
			(sheetname "")
		)
		(fill yes
			(thermal_gap 0.5)
			(thermal_bridge_width 0.5)
			(island_removal_mode 0)
		)
		(polygon
			(pts
				(arc
					(start 338.76107 -246.364506)
					(mid 338.10829 -246.364506)
					(end 338.76107 -246.364506)
				)
			)
		)
	)
	(zone
		(layers "B.Cu" "In4.Cu" "In6.Cu" "In11.Cu" "In13.Cu" "In15.Cu")
		(hatch none 0.5)
		(connect_pads
			(clearance 0)
		)
		(min_thickness 0.25)
		(keepout
			(tracks not_allowed)
			(vias allowed)
			(pads allowed)
			(copperpour not_allowed)
			(footprints allowed)
		)
		(placement
			(enabled no)
			(sheetname "")
		)
		(fill yes
			(thermal_gap 0.5)
			(thermal_bridge_width 0.5)
			(island_removal_mode 0)
		)
		(polygon
			(pts
				(arc
					(start 78.110588 -407.00452)
					(mid 77.407008 -407.00452)
					(end 78.110588 -407.00452)
				)
			)
		)
	)
	(zone
		(layers "B.Cu" "In4.Cu" "In6.Cu" "In11.Cu" "In13.Cu" "In15.Cu")
		(hatch none 0.5)
		(connect_pads
			(clearance 0)
		)
		(min_thickness 0.25)
		(keepout
			(tracks not_allowed)
			(vias allowed)
			(pads allowed)
			(copperpour not_allowed)
			(footprints allowed)
		)
		(placement
			(enabled no)
			(sheetname "")
		)
		(fill yes
			(thermal_gap 0.5)
			(thermal_bridge_width 0.5)
			(island_removal_mode 0)
		)
		(polygon
			(pts
				(arc
					(start 173.122336 -207.51673)
					(mid 172.469556 -207.51673)
					(end 173.122336 -207.51673)
				)
			)
		)
	)
	(zone
		(layers "B.Cu" "In4.Cu" "In6.Cu" "In11.Cu" "In13.Cu" "In15.Cu")
		(hatch none 0.5)
		(connect_pads
			(clearance 0)
		)
		(min_thickness 0.25)
		(keepout
			(tracks not_allowed)
			(vias allowed)
			(pads allowed)
			(copperpour not_allowed)
			(footprints allowed)
		)
		(placement
			(enabled no)
			(sheetname "")
		)
		(fill yes
			(thermal_gap 0.5)
			(thermal_bridge_width 0.5)
			(island_removal_mode 0)
		)
		(polygon
			(pts
				(arc
					(start 421.43299 -19.125438)
					(mid 420.72941 -19.125438)
					(end 421.43299 -19.125438)
				)
			)
		)
	)
	(zone
		(layers "B.Cu" "In4.Cu" "In6.Cu" "In11.Cu" "In13.Cu" "In15.Cu")
		(hatch none 0.5)
		(connect_pads
			(clearance 0)
		)
		(min_thickness 0.25)
		(keepout
			(tracks not_allowed)
			(vias allowed)
			(pads allowed)
			(copperpour not_allowed)
			(footprints allowed)
		)
		(placement
			(enabled no)
			(sheetname "")
		)
		(fill yes
			(thermal_gap 0.5)
			(thermal_bridge_width 0.5)
			(island_removal_mode 0)
		)
		(polygon
			(pts
				(arc
					(start 383.041652 -256.361438)
					(mid 382.388872 -256.361438)
					(end 383.041652 -256.361438)
				)
			)
		)
	)
	(zone
		(layers "B.Cu" "In4.Cu" "In6.Cu" "In11.Cu" "In13.Cu" "In15.Cu")
		(hatch none 0.5)
		(connect_pads
			(clearance 0)
		)
		(min_thickness 0.25)
		(keepout
			(tracks not_allowed)
			(vias allowed)
			(pads allowed)
			(copperpour not_allowed)
			(footprints allowed)
		)
		(placement
			(enabled no)
			(sheetname "")
		)
		(fill yes
			(thermal_gap 0.5)
			(thermal_bridge_width 0.5)
			(island_removal_mode 0)
		)
		(polygon
			(pts
				(arc
					(start 177.222404 -236.416596)
					(mid 176.569624 -236.416596)
					(end 177.222404 -236.416596)
				)
			)
		)
	)
	(zone
		(layers "B.Cu" "In4.Cu" "In6.Cu" "In11.Cu" "In13.Cu" "In15.Cu")
		(hatch none 0.5)
		(connect_pads
			(clearance 0)
		)
		(min_thickness 0.25)
		(keepout
			(tracks not_allowed)
			(vias allowed)
			(pads allowed)
			(copperpour not_allowed)
			(footprints allowed)
		)
		(placement
			(enabled no)
			(sheetname "")
		)
		(fill yes
			(thermal_gap 0.5)
			(thermal_bridge_width 0.5)
			(island_removal_mode 0)
		)
		(polygon
			(pts
				(arc
					(start 383.401824 -230.900478)
					(mid 382.749044 -230.900478)
					(end 383.401824 -230.900478)
				)
			)
		)
	)
	(zone
		(layers "B.Cu" "In4.Cu" "In6.Cu" "In11.Cu" "In13.Cu" "In15.Cu")
		(hatch none 0.5)
		(connect_pads
			(clearance 0)
		)
		(min_thickness 0.25)
		(keepout
			(tracks not_allowed)
			(vias allowed)
			(pads allowed)
			(copperpour not_allowed)
			(footprints allowed)
		)
		(placement
			(enabled no)
			(sheetname "")
		)
		(fill yes
			(thermal_gap 0.5)
			(thermal_bridge_width 0.5)
			(island_removal_mode 0)
		)
		(polygon
			(pts
				(arc
					(start 173.122336 -247.466612)
					(mid 172.469556 -247.466612)
					(end 173.122336 -247.466612)
				)
			)
		)
	)
	(zone
		(layers "B.Cu" "In4.Cu" "In6.Cu" "In11.Cu" "In13.Cu" "In15.Cu")
		(hatch none 0.5)
		(connect_pads
			(clearance 0)
		)
		(min_thickness 0.25)
		(keepout
			(tracks not_allowed)
			(vias allowed)
			(pads allowed)
			(copperpour not_allowed)
			(footprints allowed)
		)
		(placement
			(enabled no)
			(sheetname "")
		)
		(fill yes
			(thermal_gap 0.5)
			(thermal_bridge_width 0.5)
			(island_removal_mode 0)
		)
		(polygon
			(pts
				(arc
					(start 51.416204 -274.666964)
					(mid 50.763424 -274.666964)
					(end 51.416204 -274.666964)
				)
			)
		)
	)
	(zone
		(layers "B.Cu" "In4.Cu" "In6.Cu" "In11.Cu" "In13.Cu" "In15.Cu")
		(hatch none 0.5)
		(connect_pads
			(clearance 0)
		)
		(min_thickness 0.25)
		(keepout
			(tracks not_allowed)
			(vias allowed)
			(pads allowed)
			(copperpour not_allowed)
			(footprints allowed)
		)
		(placement
			(enabled no)
			(sheetname "")
		)
		(fill yes
			(thermal_gap 0.5)
			(thermal_bridge_width 0.5)
			(island_removal_mode 0)
		)
		(polygon
			(pts
				(arc
					(start 36.307268 -19.13636)
					(mid 35.603688 -19.13636)
					(end 36.307268 -19.13636)
				)
			)
		)
	)
	(zone
		(layers "B.Cu" "In4.Cu" "In6.Cu" "In11.Cu" "In13.Cu" "In15.Cu")
		(hatch none 0.5)
		(connect_pads
			(clearance 0)
		)
		(min_thickness 0.25)
		(keepout
			(tracks not_allowed)
			(vias allowed)
			(pads allowed)
			(copperpour not_allowed)
			(footprints allowed)
		)
		(placement
			(enabled no)
			(sheetname "")
		)
		(fill yes
			(thermal_gap 0.5)
			(thermal_bridge_width 0.5)
			(island_removal_mode 0)
		)
		(polygon
			(pts
				(arc
					(start 51.390804 -240.666778)
					(mid 50.738024 -240.666778)
					(end 51.390804 -240.666778)
				)
			)
		)
	)
	(zone
		(layers "B.Cu" "In4.Cu" "In6.Cu" "In11.Cu" "In13.Cu" "In15.Cu")
		(hatch none 0.5)
		(connect_pads
			(clearance 0)
		)
		(min_thickness 0.25)
		(keepout
			(tracks not_allowed)
			(vias allowed)
			(pads allowed)
			(copperpour not_allowed)
			(footprints allowed)
		)
		(placement
			(enabled no)
			(sheetname "")
		)
		(fill yes
			(thermal_gap 0.5)
			(thermal_bridge_width 0.5)
			(island_removal_mode 0)
		)
		(polygon
			(pts
				(arc
					(start 299.330872 -240.666778)
					(mid 298.678092 -240.666778)
					(end 299.330872 -240.666778)
				)
			)
		)
	)
	(zone
		(layers "B.Cu" "In4.Cu" "In6.Cu" "In11.Cu" "In13.Cu" "In15.Cu")
		(hatch none 0.5)
		(connect_pads
			(clearance 0)
		)
		(min_thickness 0.25)
		(keepout
			(tracks not_allowed)
			(vias allowed)
			(pads allowed)
			(copperpour not_allowed)
			(footprints allowed)
		)
		(placement
			(enabled no)
			(sheetname "")
		)
		(fill yes
			(thermal_gap 0.5)
			(thermal_bridge_width 0.5)
			(island_removal_mode 0)
		)
		(polygon
			(pts
				(arc
					(start 92.563188 -407.00452)
					(mid 91.859608 -407.00452)
					(end 92.563188 -407.00452)
				)
			)
		)
	)
	(zone
		(layers "B.Cu" "In4.Cu" "In6.Cu" "In11.Cu" "In13.Cu" "In15.Cu")
		(hatch none 0.5)
		(connect_pads
			(clearance 0)
		)
		(min_thickness 0.25)
		(keepout
			(tracks not_allowed)
			(vias allowed)
			(pads allowed)
			(copperpour not_allowed)
			(footprints allowed)
		)
		(placement
			(enabled no)
			(sheetname "")
		)
		(fill yes
			(thermal_gap 0.5)
			(thermal_bridge_width 0.5)
			(island_removal_mode 0)
		)
		(polygon
			(pts
				(arc
					(start 135.101584 -279.150318)
					(mid 134.448804 -279.150318)
					(end 135.101584 -279.150318)
				)
			)
		)
	)
	(zone
		(layers "B.Cu" "In4.Cu" "In6.Cu" "In11.Cu" "In13.Cu" "In15.Cu")
		(hatch none 0.5)
		(connect_pads
			(clearance 0)
		)
		(min_thickness 0.25)
		(keepout
			(tracks not_allowed)
			(vias allowed)
			(pads allowed)
			(copperpour not_allowed)
			(footprints allowed)
		)
		(placement
			(enabled no)
			(sheetname "")
		)
		(fill yes
			(thermal_gap 0.5)
			(thermal_bridge_width 0.5)
			(island_removal_mode 0)
		)
		(polygon
			(pts
				(arc
					(start 425.162472 -270.416782)
					(mid 424.509692 -270.416782)
					(end 425.162472 -270.416782)
				)
			)
		)
	)
	(zone
		(layers "B.Cu" "In4.Cu" "In6.Cu" "In11.Cu" "In13.Cu" "In15.Cu")
		(hatch none 0.5)
		(connect_pads
			(clearance 0)
		)
		(min_thickness 0.25)
		(keepout
			(tracks not_allowed)
			(vias allowed)
			(pads allowed)
			(copperpour not_allowed)
			(footprints allowed)
		)
		(placement
			(enabled no)
			(sheetname "")
		)
		(fill yes
			(thermal_gap 0.5)
			(thermal_bridge_width 0.5)
			(island_removal_mode 0)
		)
		(polygon
			(pts
				(arc
					(start 340.64067 -249.620024)
					(mid 339.98789 -249.620024)
					(end 340.64067 -249.620024)
				)
			)
		)
	)
	(zone
		(layers "B.Cu" "In4.Cu" "In6.Cu" "In11.Cu" "In13.Cu" "In15.Cu")
		(hatch none 0.5)
		(connect_pads
			(clearance 0)
		)
		(min_thickness 0.25)
		(keepout
			(tracks not_allowed)
			(vias allowed)
			(pads allowed)
			(copperpour not_allowed)
			(footprints allowed)
		)
		(placement
			(enabled no)
			(sheetname "")
		)
		(fill yes
			(thermal_gap 0.5)
			(thermal_bridge_width 0.5)
			(island_removal_mode 0)
		)
		(polygon
			(pts
				(arc
					(start 337.461352 -270.19758)
					(mid 336.808572 -270.19758)
					(end 337.461352 -270.19758)
				)
			)
		)
	)
	(zone
		(layers "B.Cu" "In4.Cu" "In6.Cu" "In11.Cu" "In13.Cu" "In15.Cu")
		(hatch none 0.5)
		(connect_pads
			(clearance 0)
		)
		(min_thickness 0.25)
		(keepout
			(tracks not_allowed)
			(vias allowed)
			(pads allowed)
			(copperpour not_allowed)
			(footprints allowed)
		)
		(placement
			(enabled no)
			(sheetname "")
		)
		(fill yes
			(thermal_gap 0.5)
			(thermal_bridge_width 0.5)
			(island_removal_mode 0)
		)
		(polygon
			(pts
				(arc
					(start 405.949404 -224.516696)
					(mid 405.296624 -224.516696)
					(end 405.949404 -224.516696)
				)
			)
		)
	)
	(zone
		(layers "B.Cu" "In4.Cu" "In6.Cu" "In11.Cu" "In13.Cu" "In15.Cu")
		(hatch none 0.5)
		(connect_pads
			(clearance 0)
		)
		(min_thickness 0.25)
		(keepout
			(tracks not_allowed)
			(vias allowed)
			(pads allowed)
			(copperpour not_allowed)
			(footprints allowed)
		)
		(placement
			(enabled no)
			(sheetname "")
		)
		(fill yes
			(thermal_gap 0.5)
			(thermal_bridge_width 0.5)
			(island_removal_mode 0)
		)
		(polygon
			(pts
				(arc
					(start 177.222404 -250.016772)
					(mid 176.569624 -250.016772)
					(end 177.222404 -250.016772)
				)
			)
		)
	)
	(zone
		(layers "B.Cu" "In4.Cu" "In6.Cu" "In11.Cu" "In13.Cu" "In15.Cu")
		(hatch none 0.5)
		(connect_pads
			(clearance 0)
		)
		(min_thickness 0.25)
		(keepout
			(tracks not_allowed)
			(vias allowed)
			(pads allowed)
			(copperpour not_allowed)
			(footprints allowed)
		)
		(placement
			(enabled no)
			(sheetname "")
		)
		(fill yes
			(thermal_gap 0.5)
			(thermal_bridge_width 0.5)
			(island_removal_mode 0)
		)
		(polygon
			(pts
				(arc
					(start 337.461352 -275.08073)
					(mid 336.808572 -275.08073)
					(end 337.461352 -275.08073)
				)
			)
		)
	)
	(zone
		(layers "B.Cu" "In4.Cu" "In6.Cu" "In11.Cu" "In13.Cu" "In15.Cu")
		(hatch none 0.5)
		(connect_pads
			(clearance 0)
		)
		(min_thickness 0.25)
		(keepout
			(tracks not_allowed)
			(vias allowed)
			(pads allowed)
			(copperpour not_allowed)
			(footprints allowed)
		)
		(placement
			(enabled no)
			(sheetname "")
		)
		(fill yes
			(thermal_gap 0.5)
			(thermal_bridge_width 0.5)
			(island_removal_mode 0)
		)
		(polygon
			(pts
				(arc
					(start 338.401152 -263.686544)
					(mid 337.748372 -263.686544)
					(end 338.401152 -263.686544)
				)
			)
		)
	)
	(zone
		(layers "B.Cu" "In4.Cu" "In6.Cu" "In11.Cu" "In13.Cu" "In15.Cu")
		(hatch none 0.5)
		(connect_pads
			(clearance 0)
		)
		(min_thickness 0.25)
		(keepout
			(tracks not_allowed)
			(vias allowed)
			(pads allowed)
			(copperpour not_allowed)
			(footprints allowed)
		)
		(placement
			(enabled no)
			(sheetname "")
		)
		(fill yes
			(thermal_gap 0.5)
			(thermal_bridge_width 0.5)
			(island_removal_mode 0)
		)
		(polygon
			(pts
				(arc
					(start 405.949404 -303.566576)
					(mid 405.296624 -303.566576)
					(end 405.949404 -303.566576)
				)
			)
		)
	)
	(zone
		(layers "B.Cu" "In4.Cu" "In6.Cu" "In11.Cu" "In13.Cu" "In15.Cu")
		(hatch none 0.5)
		(connect_pads
			(clearance 0)
		)
		(min_thickness 0.25)
		(keepout
			(tracks not_allowed)
			(vias allowed)
			(pads allowed)
			(copperpour not_allowed)
			(footprints allowed)
		)
		(placement
			(enabled no)
			(sheetname "")
		)
		(fill yes
			(thermal_gap 0.5)
			(thermal_bridge_width 0.5)
			(island_removal_mode 0)
		)
		(polygon
			(pts
				(arc
					(start 381.992124 -231.714548)
					(mid 381.339344 -231.714548)
					(end 381.992124 -231.714548)
				)
			)
		)
	)
	(zone
		(layers "B.Cu" "In4.Cu" "In6.Cu" "In11.Cu" "In13.Cu" "In15.Cu")
		(hatch none 0.5)
		(connect_pads
			(clearance 0)
		)
		(min_thickness 0.25)
		(keepout
			(tracks not_allowed)
			(vias allowed)
			(pads allowed)
			(copperpour not_allowed)
			(footprints allowed)
		)
		(placement
			(enabled no)
			(sheetname "")
		)
		(fill yes
			(thermal_gap 0.5)
			(thermal_bridge_width 0.5)
			(island_removal_mode 0)
		)
		(polygon
			(pts
				(arc
					(start 110.087156 -224.389442)
					(mid 109.434376 -224.389442)
					(end 110.087156 -224.389442)
				)
			)
		)
	)
	(zone
		(layers "B.Cu" "In4.Cu" "In6.Cu" "In11.Cu" "In13.Cu" "In15.Cu")
		(hatch none 0.5)
		(connect_pads
			(clearance 0)
		)
		(min_thickness 0.25)
		(keepout
			(tracks not_allowed)
			(vias allowed)
			(pads allowed)
			(copperpour not_allowed)
			(footprints allowed)
		)
		(placement
			(enabled no)
			(sheetname "")
		)
		(fill yes
			(thermal_gap 0.5)
			(thermal_bridge_width 0.5)
			(island_removal_mode 0)
		)
		(polygon
			(pts
				(arc
					(start 367.425224 -224.389442)
					(mid 366.772444 -224.389442)
					(end 367.425224 -224.389442)
				)
			)
		)
	)
	(zone
		(layers "B.Cu" "In4.Cu" "In6.Cu" "In11.Cu" "In13.Cu" "In15.Cu")
		(hatch none 0.5)
		(connect_pads
			(clearance 0)
		)
		(min_thickness 0.25)
		(keepout
			(tracks not_allowed)
			(vias allowed)
			(pads allowed)
			(copperpour not_allowed)
			(footprints allowed)
		)
		(placement
			(enabled no)
			(sheetname "")
		)
		(fill yes
			(thermal_gap 0.5)
			(thermal_bridge_width 0.5)
			(island_removal_mode 0)
		)
		(polygon
			(pts
				(arc
					(start 410.049472 -231.316784)
					(mid 409.396692 -231.316784)
					(end 410.049472 -231.316784)
				)
			)
		)
	)
	(zone
		(layers "B.Cu" "In4.Cu" "In6.Cu" "In11.Cu" "In13.Cu" "In15.Cu")
		(hatch none 0.5)
		(connect_pads
			(clearance 0)
		)
		(min_thickness 0.25)
		(keepout
			(tracks not_allowed)
			(vias allowed)
			(pads allowed)
			(copperpour not_allowed)
			(footprints allowed)
		)
		(placement
			(enabled no)
			(sheetname "")
		)
		(fill yes
			(thermal_gap 0.5)
			(thermal_bridge_width 0.5)
			(island_removal_mode 0)
		)
		(polygon
			(pts
				(arc
					(start 39.746936 -267.866622)
					(mid 39.094156 -267.866622)
					(end 39.746936 -267.866622)
				)
			)
		)
	)
	(zone
		(layers "B.Cu" "In4.Cu" "In6.Cu" "In11.Cu" "In13.Cu" "In15.Cu")
		(hatch none 0.5)
		(connect_pads
			(clearance 0)
		)
		(min_thickness 0.25)
		(keepout
			(tracks not_allowed)
			(vias allowed)
			(pads allowed)
			(copperpour not_allowed)
			(footprints allowed)
		)
		(placement
			(enabled no)
			(sheetname "")
		)
		(fill yes
			(thermal_gap 0.5)
			(thermal_bridge_width 0.5)
			(island_removal_mode 0)
		)
		(polygon
			(pts
				(arc
					(start 51.416204 -263.616694)
					(mid 50.763424 -263.616694)
					(end 51.416204 -263.616694)
				)
			)
		)
	)
	(zone
		(layers "B.Cu" "In4.Cu" "In6.Cu" "In11.Cu" "In13.Cu" "In15.Cu")
		(hatch none 0.5)
		(connect_pads
			(clearance 0)
		)
		(min_thickness 0.25)
		(keepout
			(tracks not_allowed)
			(vias allowed)
			(pads allowed)
			(copperpour not_allowed)
			(footprints allowed)
		)
		(placement
			(enabled no)
			(sheetname "")
		)
		(fill yes
			(thermal_gap 0.5)
			(thermal_bridge_width 0.5)
			(island_removal_mode 0)
		)
		(polygon
			(pts
				(arc
					(start 425.162472 -307.816758)
					(mid 424.509692 -307.816758)
					(end 425.162472 -307.816758)
				)
			)
		)
	)
	(zone
		(layers "B.Cu" "In4.Cu" "In6.Cu" "In11.Cu" "In13.Cu" "In15.Cu")
		(hatch none 0.5)
		(connect_pads
			(clearance 0)
		)
		(min_thickness 0.25)
		(keepout
			(tracks not_allowed)
			(vias allowed)
			(pads allowed)
			(copperpour not_allowed)
			(footprints allowed)
		)
		(placement
			(enabled no)
			(sheetname "")
		)
		(fill yes
			(thermal_gap 0.5)
			(thermal_bridge_width 0.5)
			(island_removal_mode 0)
		)
		(polygon
			(pts
				(arc
					(start 51.390804 -204.96657)
					(mid 50.738024 -204.96657)
					(end 51.390804 -204.96657)
				)
			)
		)
	)
	(zone
		(layers "B.Cu" "In4.Cu" "In6.Cu" "In11.Cu" "In13.Cu" "In15.Cu")
		(hatch none 0.5)
		(connect_pads
			(clearance 0)
		)
		(min_thickness 0.25)
		(keepout
			(tracks not_allowed)
			(vias allowed)
			(pads allowed)
			(copperpour not_allowed)
			(footprints allowed)
		)
		(placement
			(enabled no)
			(sheetname "")
		)
		(fill yes
			(thermal_gap 0.5)
			(thermal_bridge_width 0.5)
			(island_removal_mode 0)
		)
		(polygon
			(pts
				(arc
					(start 421.062404 -211.766658)
					(mid 420.409624 -211.766658)
					(end 421.062404 -211.766658)
				)
			)
		)
	)
	(zone
		(layers "B.Cu" "In4.Cu" "In6.Cu" "In11.Cu" "In13.Cu" "In15.Cu")
		(hatch none 0.5)
		(connect_pads
			(clearance 0)
		)
		(min_thickness 0.25)
		(keepout
			(tracks not_allowed)
			(vias allowed)
			(pads allowed)
			(copperpour not_allowed)
			(footprints allowed)
		)
		(placement
			(enabled no)
			(sheetname "")
		)
		(fill yes
			(thermal_gap 0.5)
			(thermal_bridge_width 0.5)
			(island_removal_mode 0)
		)
		(polygon
			(pts
				(arc
					(start 173.122336 -272.966688)
					(mid 172.469556 -272.966688)
					(end 173.122336 -272.966688)
				)
			)
		)
	)
	(zone
		(layers "B.Cu" "In4.Cu" "In6.Cu" "In11.Cu" "In13.Cu" "In15.Cu")
		(hatch none 0.5)
		(connect_pads
			(clearance 0)
		)
		(min_thickness 0.25)
		(keepout
			(tracks not_allowed)
			(vias allowed)
			(pads allowed)
			(copperpour not_allowed)
			(footprints allowed)
		)
		(placement
			(enabled no)
			(sheetname "")
		)
		(fill yes
			(thermal_gap 0.5)
			(thermal_bridge_width 0.5)
			(island_removal_mode 0)
		)
		(polygon
			(pts
				(arc
					(start 47.290736 -233.86669)
					(mid 46.637956 -233.86669)
					(end 47.290736 -233.86669)
				)
			)
		)
	)
	(zone
		(layers "B.Cu" "In4.Cu" "In6.Cu" "In11.Cu" "In13.Cu" "In15.Cu")
		(hatch none 0.5)
		(connect_pads
			(clearance 0)
		)
		(min_thickness 0.25)
		(keepout
			(tracks not_allowed)
			(vias allowed)
			(pads allowed)
			(copperpour not_allowed)
			(footprints allowed)
		)
		(placement
			(enabled no)
			(sheetname "")
		)
		(fill yes
			(thermal_gap 0.5)
			(thermal_bridge_width 0.5)
			(island_removal_mode 0)
		)
		(polygon
			(pts
				(arc
					(start 51.390804 -237.266734)
					(mid 50.738024 -237.266734)
					(end 51.390804 -237.266734)
				)
			)
		)
	)
	(zone
		(layers "B.Cu" "In4.Cu" "In6.Cu" "In11.Cu" "In13.Cu" "In15.Cu")
		(hatch none 0.5)
		(connect_pads
			(clearance 0)
		)
		(min_thickness 0.25)
		(keepout
			(tracks not_allowed)
			(vias allowed)
			(pads allowed)
			(copperpour not_allowed)
			(footprints allowed)
		)
		(placement
			(enabled no)
			(sheetname "")
		)
		(fill yes
			(thermal_gap 0.5)
			(thermal_bridge_width 0.5)
			(island_removal_mode 0)
		)
		(polygon
			(pts
				(arc
					(start 47.290736 -261.066788)
					(mid 46.637956 -261.066788)
					(end 47.290736 -261.066788)
				)
			)
		)
	)
	(zone
		(layers "B.Cu" "In4.Cu" "In6.Cu" "In11.Cu" "In13.Cu" "In15.Cu")
		(hatch none 0.5)
		(connect_pads
			(clearance 0)
		)
		(min_thickness 0.25)
		(keepout
			(tracks not_allowed)
			(vias allowed)
			(pads allowed)
			(copperpour not_allowed)
			(footprints allowed)
		)
		(placement
			(enabled no)
			(sheetname "")
		)
		(fill yes
			(thermal_gap 0.5)
			(thermal_bridge_width 0.5)
			(island_removal_mode 0)
		)
		(polygon
			(pts
				(arc
					(start 133.692138 -258.80314)
					(mid 133.039358 -258.80314)
					(end 133.692138 -258.80314)
				)
			)
		)
	)
	(zone
		(layers "B.Cu" "In4.Cu" "In6.Cu" "In11.Cu" "In13.Cu" "In15.Cu")
		(hatch none 0.5)
		(connect_pads
			(clearance 0)
		)
		(min_thickness 0.25)
		(keepout
			(tracks not_allowed)
			(vias allowed)
			(pads allowed)
			(copperpour not_allowed)
			(footprints allowed)
		)
		(placement
			(enabled no)
			(sheetname "")
		)
		(fill yes
			(thermal_gap 0.5)
			(thermal_bridge_width 0.5)
			(island_removal_mode 0)
		)
		(polygon
			(pts
				(arc
					(start 96.100138 -286.475424)
					(mid 95.447358 -286.475424)
					(end 96.100138 -286.475424)
				)
			)
		)
	)
	(zone
		(layers "B.Cu" "In4.Cu" "In6.Cu" "In11.Cu" "In13.Cu" "In15.Cu")
		(hatch none 0.5)
		(connect_pads
			(clearance 0)
		)
		(min_thickness 0.25)
		(keepout
			(tracks not_allowed)
			(vias allowed)
			(pads allowed)
			(copperpour not_allowed)
			(footprints allowed)
		)
		(placement
			(enabled no)
			(sheetname "")
		)
		(fill yes
			(thermal_gap 0.5)
			(thermal_bridge_width 0.5)
			(island_removal_mode 0)
		)
		(polygon
			(pts
				(arc
					(start 133.582156 -235.783882)
					(mid 132.929376 -235.783882)
					(end 133.582156 -235.783882)
				)
			)
		)
	)
	(zone
		(layers "B.Cu" "In4.Cu" "In6.Cu" "In11.Cu" "In13.Cu" "In15.Cu")
		(hatch none 0.5)
		(connect_pads
			(clearance 0)
		)
		(min_thickness 0.25)
		(keepout
			(tracks not_allowed)
			(vias allowed)
			(pads allowed)
			(copperpour not_allowed)
			(footprints allowed)
		)
		(placement
			(enabled no)
			(sheetname "")
		)
		(fill yes
			(thermal_gap 0.5)
			(thermal_bridge_width 0.5)
			(island_removal_mode 0)
		)
		(polygon
			(pts
				(arc
					(start 51.390804 -210.916774)
					(mid 50.738024 -210.916774)
					(end 51.390804 -210.916774)
				)
			)
		)
	)
	(zone
		(layers "B.Cu" "In4.Cu" "In6.Cu" "In11.Cu" "In13.Cu" "In15.Cu")
		(hatch none 0.5)
		(connect_pads
			(clearance 0)
		)
		(min_thickness 0.25)
		(keepout
			(tracks not_allowed)
			(vias allowed)
			(pads allowed)
			(copperpour not_allowed)
			(footprints allowed)
		)
		(placement
			(enabled no)
			(sheetname "")
		)
		(fill yes
			(thermal_gap 0.5)
			(thermal_bridge_width 0.5)
			(island_removal_mode 0)
		)
		(polygon
			(pts
				(arc
					(start 421.062404 -233.86669)
					(mid 420.409624 -233.86669)
					(end 421.062404 -233.86669)
				)
			)
		)
	)
	(zone
		(layers "B.Cu" "In4.Cu" "In6.Cu" "In11.Cu" "In13.Cu" "In15.Cu")
		(hatch none 0.5)
		(connect_pads
			(clearance 0)
		)
		(min_thickness 0.25)
		(keepout
			(tracks not_allowed)
			(vias allowed)
			(pads allowed)
			(copperpour not_allowed)
			(footprints allowed)
		)
		(placement
			(enabled no)
			(sheetname "")
		)
		(fill yes
			(thermal_gap 0.5)
			(thermal_bridge_width 0.5)
			(island_removal_mode 0)
		)
		(polygon
			(pts
				(arc
					(start 314.385198 -400.858228)
					(mid 313.681618 -400.858228)
					(end 314.385198 -400.858228)
				)
			)
		)
	)
	(zone
		(layers "B.Cu" "In4.Cu" "In6.Cu" "In11.Cu" "In13.Cu" "In15.Cu")
		(hatch none 0.5)
		(connect_pads
			(clearance 0)
		)
		(min_thickness 0.25)
		(keepout
			(tracks not_allowed)
			(vias allowed)
			(pads allowed)
			(copperpour not_allowed)
			(footprints allowed)
		)
		(placement
			(enabled no)
			(sheetname "")
		)
		(fill yes
			(thermal_gap 0.5)
			(thermal_bridge_width 0.5)
			(island_removal_mode 0)
		)
		(polygon
			(pts
				(arc
					(start 299.356272 -260.21665)
					(mid 298.703492 -260.21665)
					(end 299.356272 -260.21665)
				)
			)
		)
	)
	(zone
		(layers "B.Cu" "In4.Cu" "In6.Cu" "In11.Cu" "In13.Cu" "In15.Cu")
		(hatch none 0.5)
		(connect_pads
			(clearance 0)
		)
		(min_thickness 0.25)
		(keepout
			(tracks not_allowed)
			(vias allowed)
			(pads allowed)
			(copperpour not_allowed)
			(footprints allowed)
		)
		(placement
			(enabled no)
			(sheetname "")
		)
		(fill yes
			(thermal_gap 0.5)
			(thermal_bridge_width 0.5)
			(island_removal_mode 0)
		)
		(polygon
			(pts
				(arc
					(start 339.231224 -237.411514)
					(mid 338.578444 -237.411514)
					(end 339.231224 -237.411514)
				)
			)
		)
	)
	(zone
		(layers "B.Cu" "In4.Cu" "In6.Cu" "In11.Cu" "In13.Cu" "In15.Cu")
		(hatch none 0.5)
		(connect_pads
			(clearance 0)
		)
		(min_thickness 0.25)
		(keepout
			(tracks not_allowed)
			(vias allowed)
			(pads allowed)
			(copperpour not_allowed)
			(footprints allowed)
		)
		(placement
			(enabled no)
			(sheetname "")
		)
		(fill yes
			(thermal_gap 0.5)
			(thermal_bridge_width 0.5)
			(island_removal_mode 0)
		)
		(polygon
			(pts
				(arc
					(start 84.237068 -407.00452)
					(mid 83.533488 -407.00452)
					(end 84.237068 -407.00452)
				)
			)
		)
	)
	(zone
		(layers "B.Cu" "In4.Cu" "In6.Cu" "In11.Cu" "In13.Cu" "In15.Cu")
		(hatch none 0.5)
		(connect_pads
			(clearance 0)
		)
		(min_thickness 0.25)
		(keepout
			(tracks not_allowed)
			(vias allowed)
			(pads allowed)
			(copperpour not_allowed)
			(footprints allowed)
		)
		(placement
			(enabled no)
			(sheetname "")
		)
		(fill yes
			(thermal_gap 0.5)
			(thermal_bridge_width 0.5)
			(island_removal_mode 0)
		)
		(polygon
			(pts
				(arc
					(start 355.67747 -223.575626)
					(mid 355.02469 -223.575626)
					(end 355.67747 -223.575626)
				)
			)
		)
	)
	(zone
		(layers "B.Cu" "In4.Cu" "In6.Cu" "In11.Cu" "In13.Cu" "In15.Cu")
		(hatch none 0.5)
		(connect_pads
			(clearance 0)
		)
		(min_thickness 0.25)
		(keepout
			(tracks not_allowed)
			(vias allowed)
			(pads allowed)
			(copperpour not_allowed)
			(footprints allowed)
		)
		(placement
			(enabled no)
			(sheetname "")
		)
		(fill yes
			(thermal_gap 0.5)
			(thermal_bridge_width 0.5)
			(island_removal_mode 0)
		)
		(polygon
			(pts
				(arc
					(start 135.461756 -235.783882)
					(mid 134.808976 -235.783882)
					(end 135.461756 -235.783882)
				)
			)
		)
	)
	(zone
		(layers "B.Cu" "In4.Cu" "In6.Cu" "In11.Cu" "In13.Cu" "In15.Cu")
		(hatch none 0.5)
		(connect_pads
			(clearance 0)
		)
		(min_thickness 0.25)
		(keepout
			(tracks not_allowed)
			(vias allowed)
			(pads allowed)
			(copperpour not_allowed)
			(footprints allowed)
		)
		(placement
			(enabled no)
			(sheetname "")
		)
		(fill yes
			(thermal_gap 0.5)
			(thermal_bridge_width 0.5)
			(island_removal_mode 0)
		)
		(polygon
			(pts
				(arc
					(start 298.34967 -161.557208)
					(mid 297.64609 -161.557208)
					(end 298.34967 -161.557208)
				)
			)
		)
	)
	(zone
		(layers "B.Cu" "In4.Cu" "In6.Cu" "In11.Cu" "In13.Cu" "In15.Cu")
		(hatch none 0.5)
		(connect_pads
			(clearance 0)
		)
		(min_thickness 0.25)
		(keepout
			(tracks not_allowed)
			(vias allowed)
			(pads allowed)
			(copperpour not_allowed)
			(footprints allowed)
		)
		(placement
			(enabled no)
			(sheetname "")
		)
		(fill yes
			(thermal_gap 0.5)
			(thermal_bridge_width 0.5)
			(island_removal_mode 0)
		)
		(polygon
			(pts
				(arc
					(start 385.37388 -407.00452)
					(mid 384.6703 -407.00452)
					(end 385.37388 -407.00452)
				)
			)
		)
	)
	(zone
		(layers "B.Cu" "In4.Cu" "In6.Cu" "In11.Cu" "In13.Cu" "In15.Cu")
		(hatch none 0.5)
		(connect_pads
			(clearance 0)
		)
		(min_thickness 0.25)
		(keepout
			(tracks not_allowed)
			(vias allowed)
			(pads allowed)
			(copperpour not_allowed)
			(footprints allowed)
		)
		(placement
			(enabled no)
			(sheetname "")
		)
		(fill yes
			(thermal_gap 0.5)
			(thermal_bridge_width 0.5)
			(island_removal_mode 0)
		)
		(polygon
			(pts
				(arc
					(start 432.643026 -19.125438)
					(mid 431.939446 -19.125438)
					(end 432.643026 -19.125438)
				)
			)
		)
	)
	(zone
		(layers "B.Cu" "In4.Cu" "In6.Cu" "In11.Cu" "In13.Cu" "In15.Cu")
		(hatch none 0.5)
		(connect_pads
			(clearance 0)
		)
		(min_thickness 0.25)
		(keepout
			(tracks not_allowed)
			(vias allowed)
			(pads allowed)
			(copperpour not_allowed)
			(footprints allowed)
		)
		(placement
			(enabled no)
			(sheetname "")
		)
		(fill yes
			(thermal_gap 0.5)
			(thermal_bridge_width 0.5)
			(island_removal_mode 0)
		)
		(polygon
			(pts
				(arc
					(start 133.692138 -268.569694)
					(mid 133.039358 -268.569694)
					(end 133.692138 -268.569694)
				)
			)
		)
	)
	(zone
		(layers "B.Cu" "In4.Cu" "In6.Cu" "In11.Cu" "In13.Cu" "In15.Cu")
		(hatch none 0.5)
		(connect_pads
			(clearance 0)
		)
		(min_thickness 0.25)
		(keepout
			(tracks not_allowed)
			(vias allowed)
			(pads allowed)
			(copperpour not_allowed)
			(footprints allowed)
		)
		(placement
			(enabled no)
			(sheetname "")
		)
		(fill yes
			(thermal_gap 0.5)
			(thermal_bridge_width 0.5)
			(island_removal_mode 0)
		)
		(polygon
			(pts
				(arc
					(start 381.992124 -228.45903)
					(mid 381.339344 -228.45903)
					(end 381.992124 -228.45903)
				)
			)
		)
	)
	(zone
		(layers "B.Cu" "In4.Cu" "In6.Cu" "In11.Cu" "In13.Cu" "In15.Cu")
		(hatch none 0.5)
		(connect_pads
			(clearance 0)
		)
		(min_thickness 0.25)
		(keepout
			(tracks not_allowed)
			(vias allowed)
			(pads allowed)
			(copperpour not_allowed)
			(footprints allowed)
		)
		(placement
			(enabled no)
			(sheetname "")
		)
		(fill yes
			(thermal_gap 0.5)
			(thermal_bridge_width 0.5)
			(island_removal_mode 0)
		)
		(polygon
			(pts
				(arc
					(start 90.461338 -260.430772)
					(mid 89.808558 -260.430772)
					(end 90.461338 -260.430772)
				)
			)
		)
	)
	(zone
		(layers "B.Cu" "In4.Cu" "In6.Cu" "In11.Cu" "In13.Cu" "In15.Cu")
		(hatch none 0.5)
		(connect_pads
			(clearance 0)
		)
		(min_thickness 0.25)
		(keepout
			(tracks not_allowed)
			(vias allowed)
			(pads allowed)
			(copperpour not_allowed)
			(footprints allowed)
		)
		(placement
			(enabled no)
			(sheetname "")
		)
		(fill yes
			(thermal_gap 0.5)
			(thermal_bridge_width 0.5)
			(island_removal_mode 0)
		)
		(polygon
			(pts
				(arc
					(start 381.522224 -239.0394)
					(mid 380.869444 -239.0394)
					(end 381.522224 -239.0394)
				)
			)
		)
	)
	(zone
		(layers "B.Cu" "In4.Cu" "In6.Cu" "In11.Cu" "In13.Cu" "In15.Cu")
		(hatch none 0.5)
		(connect_pads
			(clearance 0)
		)
		(min_thickness 0.25)
		(keepout
			(tracks not_allowed)
			(vias allowed)
			(pads allowed)
			(copperpour not_allowed)
			(footprints allowed)
		)
		(placement
			(enabled no)
			(sheetname "")
		)
		(fill yes
			(thermal_gap 0.5)
			(thermal_bridge_width 0.5)
			(island_removal_mode 0)
		)
		(polygon
			(pts
				(arc
					(start 314.418472 -225.36658)
					(mid 313.765692 -225.36658)
					(end 314.418472 -225.36658)
				)
			)
		)
	)
	(zone
		(layers "B.Cu" "In4.Cu" "In6.Cu" "In11.Cu" "In13.Cu" "In15.Cu")
		(hatch none 0.5)
		(connect_pads
			(clearance 0)
		)
		(min_thickness 0.25)
		(keepout
			(tracks not_allowed)
			(vias allowed)
			(pads allowed)
			(copperpour not_allowed)
			(footprints allowed)
		)
		(placement
			(enabled no)
			(sheetname "")
		)
		(fill yes
			(thermal_gap 0.5)
			(thermal_bridge_width 0.5)
			(island_removal_mode 0)
		)
		(polygon
			(pts
				(arc
					(start 90.461084 -253.919736)
					(mid 89.808304 -253.919736)
					(end 90.461084 -253.919736)
				)
			)
		)
	)
	(zone
		(layers "B.Cu" "In4.Cu" "In6.Cu" "In11.Cu" "In13.Cu" "In15.Cu")
		(hatch none 0.5)
		(connect_pads
			(clearance 0)
		)
		(min_thickness 0.25)
		(keepout
			(tracks not_allowed)
			(vias allowed)
			(pads allowed)
			(copperpour not_allowed)
			(footprints allowed)
		)
		(placement
			(enabled no)
			(sheetname "")
		)
		(fill yes
			(thermal_gap 0.5)
			(thermal_bridge_width 0.5)
			(island_removal_mode 0)
		)
		(polygon
			(pts
				(arc
					(start 310.318404 -306.96662)
					(mid 309.665624 -306.96662)
					(end 310.318404 -306.96662)
				)
			)
		)
	)
	(zone
		(layers "B.Cu" "In4.Cu" "In6.Cu" "In11.Cu" "In13.Cu" "In15.Cu")
		(hatch none 0.5)
		(connect_pads
			(clearance 0)
		)
		(min_thickness 0.25)
		(keepout
			(tracks not_allowed)
			(vias allowed)
			(pads allowed)
			(copperpour not_allowed)
			(footprints allowed)
		)
		(placement
			(enabled no)
			(sheetname "")
		)
		(fill yes
			(thermal_gap 0.5)
			(thermal_bridge_width 0.5)
			(island_removal_mode 0)
		)
		(polygon
			(pts
				(arc
					(start 51.390804 -209.216752)
					(mid 50.738024 -209.216752)
					(end 51.390804 -209.216752)
				)
			)
		)
	)
	(zone
		(layers "B.Cu" "In4.Cu" "In6.Cu" "In11.Cu" "In13.Cu" "In15.Cu")
		(hatch none 0.5)
		(connect_pads
			(clearance 0)
		)
		(min_thickness 0.25)
		(keepout
			(tracks not_allowed)
			(vias allowed)
			(pads allowed)
			(copperpour not_allowed)
			(footprints allowed)
		)
		(placement
			(enabled no)
			(sheetname "")
		)
		(fill yes
			(thermal_gap 0.5)
			(thermal_bridge_width 0.5)
			(island_removal_mode 0)
		)
		(polygon
			(pts
				(arc
					(start 383.041652 -271.011396)
					(mid 382.388872 -271.011396)
					(end 383.041652 -271.011396)
				)
			)
		)
	)
	(zone
		(layers "B.Cu" "In4.Cu" "In6.Cu" "In11.Cu" "In13.Cu" "In15.Cu")
		(hatch none 0.5)
		(connect_pads
			(clearance 0)
		)
		(min_thickness 0.25)
		(keepout
			(tracks not_allowed)
			(vias allowed)
			(pads allowed)
			(copperpour not_allowed)
			(footprints allowed)
		)
		(placement
			(enabled no)
			(sheetname "")
		)
		(fill yes
			(thermal_gap 0.5)
			(thermal_bridge_width 0.5)
			(island_removal_mode 0)
		)
		(polygon
			(pts
				(arc
					(start 337.461352 -273.453098)
					(mid 336.808572 -273.453098)
					(end 337.461352 -273.453098)
				)
			)
		)
	)
	(zone
		(layers "B.Cu" "In4.Cu" "In6.Cu" "In11.Cu" "In13.Cu" "In15.Cu")
		(hatch none 0.5)
		(connect_pads
			(clearance 0)
		)
		(min_thickness 0.25)
		(keepout
			(tracks not_allowed)
			(vias allowed)
			(pads allowed)
			(copperpour not_allowed)
			(footprints allowed)
		)
		(placement
			(enabled no)
			(sheetname "")
		)
		(fill yes
			(thermal_gap 0.5)
			(thermal_bridge_width 0.5)
			(island_removal_mode 0)
		)
		(polygon
			(pts
				(arc
					(start 89.521284 -275.08073)
					(mid 88.868504 -275.08073)
					(end 89.521284 -275.08073)
				)
			)
		)
	)
	(zone
		(layers "B.Cu" "In4.Cu" "In6.Cu" "In11.Cu" "In13.Cu" "In15.Cu")
		(hatch none 0.5)
		(connect_pads
			(clearance 0)
		)
		(min_thickness 0.25)
		(keepout
			(tracks not_allowed)
			(vias allowed)
			(pads allowed)
			(copperpour not_allowed)
			(footprints allowed)
		)
		(placement
			(enabled no)
			(sheetname "")
		)
		(fill yes
			(thermal_gap 0.5)
			(thermal_bridge_width 0.5)
			(island_removal_mode 0)
		)
		(polygon
			(pts
				(arc
					(start 381.522224 -245.55069)
					(mid 380.869444 -245.55069)
					(end 381.522224 -245.55069)
				)
			)
		)
	)
	(zone
		(layers "B.Cu" "In4.Cu" "In6.Cu" "In11.Cu" "In13.Cu" "In15.Cu")
		(hatch none 0.5)
		(connect_pads
			(clearance 0)
		)
		(min_thickness 0.25)
		(keepout
			(tracks not_allowed)
			(vias allowed)
			(pads allowed)
			(copperpour not_allowed)
			(footprints allowed)
		)
		(placement
			(enabled no)
			(sheetname "")
		)
		(fill yes
			(thermal_gap 0.5)
			(thermal_bridge_width 0.5)
			(island_removal_mode 0)
		)
		(polygon
			(pts
				(arc
					(start 173.122336 -210.066636)
					(mid 172.469556 -210.066636)
					(end 173.122336 -210.066636)
				)
			)
		)
	)
	(zone
		(layers "B.Cu" "In4.Cu" "In6.Cu" "In11.Cu" "In13.Cu" "In15.Cu")
		(hatch none 0.5)
		(connect_pads
			(clearance 0)
		)
		(min_thickness 0.25)
		(keepout
			(tracks not_allowed)
			(vias allowed)
			(pads allowed)
			(copperpour not_allowed)
			(footprints allowed)
		)
		(placement
			(enabled no)
			(sheetname "")
		)
		(fill yes
			(thermal_gap 0.5)
			(thermal_bridge_width 0.5)
			(island_removal_mode 0)
		)
		(polygon
			(pts
				(arc
					(start 400.69008 -407.00452)
					(mid 399.9865 -407.00452)
					(end 400.69008 -407.00452)
				)
			)
		)
	)
	(zone
		(layers "B.Cu" "In4.Cu" "In6.Cu" "In11.Cu" "In13.Cu" "In15.Cu")
		(hatch none 0.5)
		(connect_pads
			(clearance 0)
		)
		(min_thickness 0.25)
		(keepout
			(tracks not_allowed)
			(vias allowed)
			(pads allowed)
			(copperpour not_allowed)
			(footprints allowed)
		)
		(placement
			(enabled no)
			(sheetname "")
		)
		(fill yes
			(thermal_gap 0.5)
			(thermal_bridge_width 0.5)
			(island_removal_mode 0)
		)
		(polygon
			(pts
				(arc
					(start 310.318404 -224.516696)
					(mid 309.665624 -224.516696)
					(end 310.318404 -224.516696)
				)
			)
		)
	)
	(zone
		(layers "B.Cu" "In4.Cu" "In6.Cu" "In11.Cu" "In13.Cu" "In15.Cu")
		(hatch none 0.5)
		(connect_pads
			(clearance 0)
		)
		(min_thickness 0.25)
		(keepout
			(tracks not_allowed)
			(vias allowed)
			(pads allowed)
			(copperpour not_allowed)
			(footprints allowed)
		)
		(placement
			(enabled no)
			(sheetname "")
		)
		(fill yes
			(thermal_gap 0.5)
			(thermal_bridge_width 0.5)
			(island_removal_mode 0)
		)
		(polygon
			(pts
				(arc
					(start 421.062404 -209.216752)
					(mid 420.409624 -209.216752)
					(end 421.062404 -209.216752)
				)
			)
		)
	)
	(zone
		(layers "B.Cu" "In4.Cu" "In6.Cu" "In11.Cu" "In13.Cu" "In15.Cu")
		(hatch none 0.5)
		(connect_pads
			(clearance 0)
		)
		(min_thickness 0.25)
		(keepout
			(tracks not_allowed)
			(vias allowed)
			(pads allowed)
			(copperpour not_allowed)
			(footprints allowed)
		)
		(placement
			(enabled no)
			(sheetname "")
		)
		(fill yes
			(thermal_gap 0.5)
			(thermal_bridge_width 0.5)
			(island_removal_mode 0)
		)
		(polygon
			(pts
				(arc
					(start 383.981198 -277.522432)
					(mid 383.328418 -277.522432)
					(end 383.981198 -277.522432)
				)
			)
		)
	)
	(zone
		(layers "B.Cu" "In4.Cu" "In6.Cu" "In11.Cu" "In13.Cu" "In15.Cu")
		(hatch none 0.5)
		(connect_pads
			(clearance 0)
		)
		(min_thickness 0.25)
		(keepout
			(tracks not_allowed)
			(vias allowed)
			(pads allowed)
			(copperpour not_allowed)
			(footprints allowed)
		)
		(placement
			(enabled no)
			(sheetname "")
		)
		(fill yes
			(thermal_gap 0.5)
			(thermal_bridge_width 0.5)
			(island_removal_mode 0)
		)
		(polygon
			(pts
				(arc
					(start 133.582156 -240.667286)
					(mid 132.929376 -240.667286)
					(end 133.582156 -240.667286)
				)
			)
		)
	)
	(zone
		(layers "B.Cu" "In4.Cu" "In6.Cu" "In11.Cu" "In13.Cu" "In15.Cu")
		(hatch none 0.5)
		(connect_pads
			(clearance 0)
		)
		(min_thickness 0.25)
		(keepout
			(tracks not_allowed)
			(vias allowed)
			(pads allowed)
			(copperpour not_allowed)
			(footprints allowed)
		)
		(placement
			(enabled no)
			(sheetname "")
		)
		(fill yes
			(thermal_gap 0.5)
			(thermal_bridge_width 0.5)
			(island_removal_mode 0)
		)
		(polygon
			(pts
				(arc
					(start 89.051384 -261.244842)
					(mid 88.398604 -261.244842)
					(end 89.051384 -261.244842)
				)
			)
		)
	)
	(zone
		(layers "B.Cu" "In4.Cu" "In6.Cu" "In11.Cu" "In13.Cu" "In15.Cu")
		(hatch none 0.5)
		(connect_pads
			(clearance 0)
		)
		(min_thickness 0.25)
		(keepout
			(tracks not_allowed)
			(vias allowed)
			(pads allowed)
			(copperpour not_allowed)
			(footprints allowed)
		)
		(placement
			(enabled no)
			(sheetname "")
		)
		(fill yes
			(thermal_gap 0.5)
			(thermal_bridge_width 0.5)
			(island_removal_mode 0)
		)
		(polygon
			(pts
				(arc
					(start 425.162472 -220.266768)
					(mid 424.509692 -220.266768)
					(end 425.162472 -220.266768)
				)
			)
		)
	)
	(zone
		(layers "B.Cu" "In4.Cu" "In6.Cu" "In11.Cu" "In13.Cu" "In15.Cu")
		(hatch none 0.5)
		(connect_pads
			(clearance 0)
		)
		(min_thickness 0.25)
		(keepout
			(tracks not_allowed)
			(vias allowed)
			(pads allowed)
			(copperpour not_allowed)
			(footprints allowed)
		)
		(placement
			(enabled no)
			(sheetname "")
		)
		(fill yes
			(thermal_gap 0.5)
			(thermal_bridge_width 0.5)
			(island_removal_mode 0)
		)
		(polygon
			(pts
				(arc
					(start 425.162472 -246.616728)
					(mid 424.509692 -246.616728)
					(end 425.162472 -246.616728)
				)
			)
		)
	)
	(zone
		(layers "B.Cu" "In4.Cu" "In6.Cu" "In11.Cu" "In13.Cu" "In15.Cu")
		(hatch none 0.5)
		(connect_pads
			(clearance 0)
		)
		(min_thickness 0.25)
		(keepout
			(tracks not_allowed)
			(vias allowed)
			(pads allowed)
			(copperpour not_allowed)
			(footprints allowed)
		)
		(placement
			(enabled no)
			(sheetname "")
		)
		(fill yes
			(thermal_gap 0.5)
			(thermal_bridge_width 0.5)
			(island_removal_mode 0)
		)
		(polygon
			(pts
				(arc
					(start 403.75332 -407.00452)
					(mid 403.04974 -407.00452)
					(end 403.75332 -407.00452)
				)
			)
		)
	)
	(zone
		(layers "B.Cu" "In4.Cu" "In6.Cu" "In11.Cu" "In13.Cu" "In15.Cu")
		(hatch none 0.5)
		(connect_pads
			(clearance 0)
		)
		(min_thickness 0.25)
		(keepout
			(tracks not_allowed)
			(vias allowed)
			(pads allowed)
			(copperpour not_allowed)
			(footprints allowed)
		)
		(placement
			(enabled no)
			(sheetname "")
		)
		(fill yes
			(thermal_gap 0.5)
			(thermal_bridge_width 0.5)
			(island_removal_mode 0)
		)
		(polygon
			(pts
				(arc
					(start 137.341356 -224.389442)
					(mid 136.688576 -224.389442)
					(end 137.341356 -224.389442)
				)
			)
		)
	)
	(zone
		(layers "B.Cu" "In4.Cu" "In6.Cu" "In11.Cu" "In13.Cu" "In15.Cu")
		(hatch none 0.5)
		(connect_pads
			(clearance 0)
		)
		(min_thickness 0.25)
		(keepout
			(tracks not_allowed)
			(vias allowed)
			(pads allowed)
			(copperpour not_allowed)
			(footprints allowed)
		)
		(placement
			(enabled no)
			(sheetname "")
		)
		(fill yes
			(thermal_gap 0.5)
			(thermal_bridge_width 0.5)
			(island_removal_mode 0)
		)
		(polygon
			(pts
				(arc
					(start 391.256774 -17.601438)
					(mid 390.553194 -17.601438)
					(end 391.256774 -17.601438)
				)
			)
		)
	)
	(zone
		(layers "B.Cu" "In4.Cu" "In6.Cu" "In11.Cu" "In13.Cu" "In15.Cu")
		(hatch none 0.5)
		(connect_pads
			(clearance 0)
		)
		(min_thickness 0.25)
		(keepout
			(tracks not_allowed)
			(vias allowed)
			(pads allowed)
			(copperpour not_allowed)
			(footprints allowed)
		)
		(placement
			(enabled no)
			(sheetname "")
		)
		(fill yes
			(thermal_gap 0.5)
			(thermal_bridge_width 0.5)
			(island_removal_mode 0)
		)
		(polygon
			(pts
				(arc
					(start 314.418472 -298.466764)
					(mid 313.765692 -298.466764)
					(end 314.418472 -298.466764)
				)
			)
		)
	)
	(zone
		(layers "B.Cu" "In4.Cu" "In6.Cu" "In11.Cu" "In13.Cu" "In15.Cu")
		(hatch none 0.5)
		(connect_pads
			(clearance 0)
		)
		(min_thickness 0.25)
		(keepout
			(tracks not_allowed)
			(vias allowed)
			(pads allowed)
			(copperpour not_allowed)
			(footprints allowed)
		)
		(placement
			(enabled no)
			(sheetname "")
		)
		(fill yes
			(thermal_gap 0.5)
			(thermal_bridge_width 0.5)
			(island_removal_mode 0)
		)
		(polygon
			(pts
				(arc
					(start 381.162052 -257.98907)
					(mid 380.509272 -257.98907)
					(end 381.162052 -257.98907)
				)
			)
		)
	)
	(zone
		(layers "B.Cu" "In4.Cu" "In6.Cu" "In11.Cu" "In13.Cu" "In15.Cu")
		(hatch none 0.5)
		(connect_pads
			(clearance 0)
		)
		(min_thickness 0.25)
		(keepout
			(tracks not_allowed)
			(vias allowed)
			(pads allowed)
			(copperpour not_allowed)
			(footprints allowed)
		)
		(placement
			(enabled no)
			(sheetname "")
		)
		(fill yes
			(thermal_gap 0.5)
			(thermal_bridge_width 0.5)
			(island_removal_mode 0)
		)
		(polygon
			(pts
				(arc
					(start 90.821002 -231.714548)
					(mid 90.168222 -231.714548)
					(end 90.821002 -231.714548)
				)
			)
		)
	)
	(zone
		(layers "B.Cu" "In4.Cu" "In6.Cu" "In11.Cu" "In13.Cu" "In15.Cu")
		(hatch none 0.5)
		(connect_pads
			(clearance 0)
		)
		(min_thickness 0.25)
		(keepout
			(tracks not_allowed)
			(vias allowed)
			(pads allowed)
			(copperpour not_allowed)
			(footprints allowed)
		)
		(placement
			(enabled no)
			(sheetname "")
		)
		(fill yes
			(thermal_gap 0.5)
			(thermal_bridge_width 0.5)
			(island_removal_mode 0)
		)
		(polygon
			(pts
				(arc
					(start 134.105904 -407.00452)
					(mid 133.402324 -407.00452)
					(end 134.105904 -407.00452)
				)
			)
		)
	)
	(zone
		(layers "B.Cu" "In4.Cu" "In6.Cu" "In11.Cu" "In13.Cu" "In15.Cu")
		(hatch none 0.5)
		(connect_pads
			(clearance 0)
		)
		(min_thickness 0.25)
		(keepout
			(tracks not_allowed)
			(vias allowed)
			(pads allowed)
			(copperpour not_allowed)
			(footprints allowed)
		)
		(placement
			(enabled no)
			(sheetname "")
		)
		(fill yes
			(thermal_gap 0.5)
			(thermal_bridge_width 0.5)
			(island_removal_mode 0)
		)
		(polygon
			(pts
				(arc
					(start 92.700602 -249.620024)
					(mid 92.047822 -249.620024)
					(end 92.700602 -249.620024)
				)
			)
		)
	)
	(zone
		(layers "B.Cu" "In4.Cu" "In6.Cu" "In11.Cu" "In13.Cu" "In15.Cu")
		(hatch none 0.5)
		(connect_pads
			(clearance 0)
		)
		(min_thickness 0.25)
		(keepout
			(tracks not_allowed)
			(vias allowed)
			(pads allowed)
			(copperpour not_allowed)
			(footprints allowed)
		)
		(placement
			(enabled no)
			(sheetname "")
		)
		(fill yes
			(thermal_gap 0.5)
			(thermal_bridge_width 0.5)
			(island_removal_mode 0)
		)
		(polygon
			(pts
				(arc
					(start 405.949404 -226.216718)
					(mid 405.296624 -226.216718)
					(end 405.949404 -226.216718)
				)
			)
		)
	)
	(zone
		(layers "B.Cu" "In4.Cu" "In6.Cu" "In11.Cu" "In13.Cu" "In15.Cu")
		(hatch none 0.5)
		(connect_pads
			(clearance 0)
		)
		(min_thickness 0.25)
		(keepout
			(tracks not_allowed)
			(vias allowed)
			(pads allowed)
			(copperpour not_allowed)
			(footprints allowed)
		)
		(placement
			(enabled no)
			(sheetname "")
		)
		(fill yes
			(thermal_gap 0.5)
			(thermal_bridge_width 0.5)
			(island_removal_mode 0)
		)
		(polygon
			(pts
				(arc
					(start 350.280478 -400.858228)
					(mid 349.576898 -400.858228)
					(end 350.280478 -400.858228)
				)
			)
		)
	)
	(zone
		(layers "B.Cu" "In4.Cu" "In6.Cu" "In11.Cu" "In13.Cu" "In15.Cu")
		(hatch none 0.5)
		(connect_pads
			(clearance 0)
		)
		(min_thickness 0.25)
		(keepout
			(tracks not_allowed)
			(vias allowed)
			(pads allowed)
			(copperpour not_allowed)
			(footprints allowed)
		)
		(placement
			(enabled no)
			(sheetname "")
		)
		(fill yes
			(thermal_gap 0.5)
			(thermal_bridge_width 0.5)
			(island_removal_mode 0)
		)
		(polygon
			(pts
				(arc
					(start 110.556802 -225.203258)
					(mid 109.904022 -225.203258)
					(end 110.556802 -225.203258)
				)
			)
		)
	)
	(zone
		(layers "B.Cu" "In4.Cu" "In6.Cu" "In11.Cu" "In13.Cu" "In15.Cu")
		(hatch none 0.5)
		(connect_pads
			(clearance 0)
		)
		(min_thickness 0.25)
		(keepout
			(tracks not_allowed)
			(vias allowed)
			(pads allowed)
			(copperpour not_allowed)
			(footprints allowed)
		)
		(placement
			(enabled no)
			(sheetname "")
		)
		(fill yes
			(thermal_gap 0.5)
			(thermal_bridge_width 0.5)
			(island_removal_mode 0)
		)
		(polygon
			(pts
				(arc
					(start 90.930984 -266.128246)
					(mid 90.278204 -266.128246)
					(end 90.930984 -266.128246)
				)
			)
		)
	)
	(zone
		(layers "B.Cu" "In4.Cu" "In6.Cu" "In11.Cu" "In13.Cu" "In15.Cu")
		(hatch none 0.5)
		(connect_pads
			(clearance 0)
		)
		(min_thickness 0.25)
		(keepout
			(tracks not_allowed)
			(vias allowed)
			(pads allowed)
			(copperpour not_allowed)
			(footprints allowed)
		)
		(placement
			(enabled no)
			(sheetname "")
		)
		(fill yes
			(thermal_gap 0.5)
			(thermal_bridge_width 0.5)
			(island_removal_mode 0)
		)
		(polygon
			(pts
				(arc
					(start 173.122336 -293.366698)
					(mid 172.469556 -293.366698)
					(end 173.122336 -293.366698)
				)
			)
		)
	)
	(zone
		(layers "B.Cu" "In4.Cu" "In6.Cu" "In11.Cu" "In13.Cu" "In15.Cu")
		(hatch none 0.5)
		(connect_pads
			(clearance 0)
		)
		(min_thickness 0.25)
		(keepout
			(tracks not_allowed)
			(vias allowed)
			(pads allowed)
			(copperpour not_allowed)
			(footprints allowed)
		)
		(placement
			(enabled no)
			(sheetname "")
		)
		(fill yes
			(thermal_gap 0.5)
			(thermal_bridge_width 0.5)
			(island_removal_mode 0)
		)
		(polygon
			(pts
				(arc
					(start 52.54752 -19.13636)
					(mid 51.84394 -19.13636)
					(end 52.54752 -19.13636)
				)
			)
		)
	)
	(zone
		(layers "B.Cu" "In4.Cu" "In6.Cu" "In11.Cu" "In13.Cu" "In15.Cu")
		(hatch none 0.5)
		(connect_pads
			(clearance 0)
		)
		(min_thickness 0.25)
		(keepout
			(tracks not_allowed)
			(vias allowed)
			(pads allowed)
			(copperpour not_allowed)
			(footprints allowed)
		)
		(placement
			(enabled no)
			(sheetname "")
		)
		(fill yes
			(thermal_gap 0.5)
			(thermal_bridge_width 0.5)
			(island_removal_mode 0)
		)
		(polygon
			(pts
				(arc
					(start 425.162472 -236.416596)
					(mid 424.509692 -236.416596)
					(end 425.162472 -236.416596)
				)
			)
		)
	)
	(zone
		(layers "B.Cu" "In4.Cu" "In6.Cu" "In11.Cu" "In13.Cu" "In15.Cu")
		(hatch none 0.5)
		(connect_pads
			(clearance 0)
		)
		(min_thickness 0.25)
		(keepout
			(tracks not_allowed)
			(vias allowed)
			(pads allowed)
			(copperpour not_allowed)
			(footprints allowed)
		)
		(placement
			(enabled no)
			(sheetname "")
		)
		(fill yes
			(thermal_gap 0.5)
			(thermal_bridge_width 0.5)
			(island_removal_mode 0)
		)
		(polygon
			(pts
				(arc
					(start 133.582156 -243.922804)
					(mid 132.929376 -243.922804)
					(end 133.582156 -243.922804)
				)
			)
		)
	)
	(zone
		(layers "B.Cu" "In4.Cu" "In6.Cu" "In11.Cu" "In13.Cu" "In15.Cu")
		(hatch none 0.5)
		(connect_pads
			(clearance 0)
		)
		(min_thickness 0.25)
		(keepout
			(tracks not_allowed)
			(vias allowed)
			(pads allowed)
			(copperpour not_allowed)
			(footprints allowed)
		)
		(placement
			(enabled no)
			(sheetname "")
		)
		(fill yes
			(thermal_gap 0.5)
			(thermal_bridge_width 0.5)
			(island_removal_mode 0)
		)
		(polygon
			(pts
				(arc
					(start 336.521552 -265.314176)
					(mid 335.868772 -265.314176)
					(end 336.521552 -265.314176)
				)
			)
		)
	)
	(zone
		(layers "B.Cu" "In4.Cu" "In6.Cu" "In11.Cu" "In13.Cu" "In15.Cu")
		(hatch none 0.5)
		(connect_pads
			(clearance 0)
		)
		(min_thickness 0.25)
		(keepout
			(tracks not_allowed)
			(vias allowed)
			(pads allowed)
			(copperpour not_allowed)
			(footprints allowed)
		)
		(placement
			(enabled no)
			(sheetname "")
		)
		(fill yes
			(thermal_gap 0.5)
			(thermal_bridge_width 0.5)
			(island_removal_mode 0)
		)
		(polygon
			(pts
				(arc
					(start 89.411556 -248.806208)
					(mid 88.758776 -248.806208)
					(end 89.411556 -248.806208)
				)
			)
		)
	)
	(zone
		(layers "B.Cu" "In4.Cu" "In6.Cu" "In11.Cu" "In13.Cu" "In15.Cu")
		(hatch none 0.5)
		(connect_pads
			(clearance 0)
		)
		(min_thickness 0.25)
		(keepout
			(tracks not_allowed)
			(vias allowed)
			(pads allowed)
			(copperpour not_allowed)
			(footprints allowed)
		)
		(placement
			(enabled no)
			(sheetname "")
		)
		(fill yes
			(thermal_gap 0.5)
			(thermal_bridge_width 0.5)
			(island_removal_mode 0)
		)
		(polygon
			(pts
				(arc
					(start 295.230804 -267.866622)
					(mid 294.578024 -267.866622)
					(end 295.230804 -267.866622)
				)
			)
		)
	)
	(zone
		(layers "B.Cu" "In4.Cu" "In6.Cu" "In11.Cu" "In13.Cu" "In15.Cu")
		(hatch none 0.5)
		(connect_pads
			(clearance 0)
		)
		(min_thickness 0.25)
		(keepout
			(tracks not_allowed)
			(vias allowed)
			(pads allowed)
			(copperpour not_allowed)
			(footprints allowed)
		)
		(placement
			(enabled no)
			(sheetname "")
		)
		(fill yes
			(thermal_gap 0.5)
			(thermal_bridge_width 0.5)
			(island_removal_mode 0)
		)
		(polygon
			(pts
				(arc
					(start 62.378336 -306.96662)
					(mid 61.725556 -306.96662)
					(end 62.378336 -306.96662)
				)
			)
		)
	)
	(zone
		(layers "B.Cu" "In4.Cu" "In6.Cu" "In11.Cu" "In13.Cu" "In15.Cu")
		(hatch none 0.5)
		(connect_pads
			(clearance 0)
		)
		(min_thickness 0.25)
		(keepout
			(tracks not_allowed)
			(vias allowed)
			(pads allowed)
			(copperpour not_allowed)
			(footprints allowed)
		)
		(placement
			(enabled no)
			(sheetname "")
		)
		(fill yes
			(thermal_gap 0.5)
			(thermal_bridge_width 0.5)
			(island_removal_mode 0)
		)
		(polygon
			(pts
				(arc
					(start 351.088452 -285.661354)
					(mid 350.435672 -285.661354)
					(end 351.088452 -285.661354)
				)
			)
		)
	)
	(zone
		(layers "B.Cu" "In4.Cu" "In6.Cu" "In11.Cu" "In13.Cu" "In15.Cu")
		(hatch none 0.5)
		(connect_pads
			(clearance 0)
		)
		(min_thickness 0.25)
		(keepout
			(tracks not_allowed)
			(vias allowed)
			(pads allowed)
			(copperpour not_allowed)
			(footprints allowed)
		)
		(placement
			(enabled no)
			(sheetname "")
		)
		(fill yes
			(thermal_gap 0.5)
			(thermal_bridge_width 0.5)
			(island_removal_mode 0)
		)
		(polygon
			(pts
				(arc
					(start 337.351624 -248.806208)
					(mid 336.698844 -248.806208)
					(end 337.351624 -248.806208)
				)
			)
		)
	)
	(zone
		(layers "B.Cu" "In4.Cu" "In6.Cu" "In11.Cu" "In13.Cu" "In15.Cu")
		(hatch none 0.5)
		(connect_pads
			(clearance 0)
		)
		(min_thickness 0.25)
		(keepout
			(tracks not_allowed)
			(vias allowed)
			(pads allowed)
			(copperpour not_allowed)
			(footprints allowed)
		)
		(placement
			(enabled no)
			(sheetname "")
		)
		(fill yes
			(thermal_gap 0.5)
			(thermal_bridge_width 0.5)
			(island_removal_mode 0)
		)
		(polygon
			(pts
				(arc
					(start 382.101852 -275.8948)
					(mid 381.449072 -275.8948)
					(end 382.101852 -275.8948)
				)
			)
		)
	)
	(zone
		(layers "B.Cu" "In4.Cu" "In6.Cu" "In11.Cu" "In13.Cu" "In15.Cu")
		(hatch none 0.5)
		(connect_pads
			(clearance 0)
		)
		(min_thickness 0.25)
		(keepout
			(tracks not_allowed)
			(vias allowed)
			(pads allowed)
			(copperpour not_allowed)
			(footprints allowed)
		)
		(placement
			(enabled no)
			(sheetname "")
		)
		(fill yes
			(thermal_gap 0.5)
			(thermal_bridge_width 0.5)
			(island_removal_mode 0)
		)
		(polygon
			(pts
				(arc
					(start 135.571484 -262.058658)
					(mid 134.918704 -262.058658)
					(end 135.571484 -262.058658)
				)
			)
		)
	)
	(zone
		(layers "B.Cu" "In4.Cu" "In6.Cu" "In11.Cu" "In13.Cu" "In15.Cu")
		(hatch none 0.5)
		(connect_pads
			(clearance 0)
		)
		(min_thickness 0.25)
		(keepout
			(tracks not_allowed)
			(vias allowed)
			(pads allowed)
			(copperpour not_allowed)
			(footprints allowed)
		)
		(placement
			(enabled no)
			(sheetname "")
		)
		(fill yes
			(thermal_gap 0.5)
			(thermal_bridge_width 0.5)
			(island_removal_mode 0)
		)
		(polygon
			(pts
				(arc
					(start 113.846356 -224.389442)
					(mid 113.193576 -224.389442)
					(end 113.846356 -224.389442)
				)
			)
		)
	)
	(zone
		(layers "B.Cu" "In4.Cu" "In6.Cu" "In11.Cu" "In13.Cu" "In15.Cu")
		(hatch none 0.5)
		(connect_pads
			(clearance 0)
		)
		(min_thickness 0.25)
		(keepout
			(tracks not_allowed)
			(vias allowed)
			(pads allowed)
			(copperpour not_allowed)
			(footprints allowed)
		)
		(placement
			(enabled no)
			(sheetname "")
		)
		(fill yes
			(thermal_gap 0.5)
			(thermal_bridge_width 0.5)
			(island_removal_mode 0)
		)
		(polygon
			(pts
				(arc
					(start 135.461756 -234.15625)
					(mid 134.808976 -234.15625)
					(end 135.461756 -234.15625)
				)
			)
		)
	)
	(zone
		(layers "B.Cu" "In4.Cu" "In6.Cu" "In11.Cu" "In13.Cu" "In15.Cu")
		(hatch none 0.5)
		(connect_pads
			(clearance 0)
		)
		(min_thickness 0.25)
		(keepout
			(tracks not_allowed)
			(vias allowed)
			(pads allowed)
			(copperpour not_allowed)
			(footprints allowed)
		)
		(placement
			(enabled no)
			(sheetname "")
		)
		(fill yes
			(thermal_gap 0.5)
			(thermal_bridge_width 0.5)
			(island_removal_mode 0)
		)
		(polygon
			(pts
				(arc
					(start 47.290736 -316.316614)
					(mid 46.637956 -316.316614)
					(end 47.290736 -316.316614)
				)
			)
		)
	)
	(zone
		(layers "B.Cu" "In4.Cu" "In6.Cu" "In11.Cu" "In13.Cu" "In15.Cu")
		(hatch none 0.5)
		(connect_pads
			(clearance 0)
		)
		(min_thickness 0.25)
		(keepout
			(tracks not_allowed)
			(vias allowed)
			(pads allowed)
			(copperpour not_allowed)
			(footprints allowed)
		)
		(placement
			(enabled no)
			(sheetname "")
		)
		(fill yes
			(thermal_gap 0.5)
			(thermal_bridge_width 0.5)
			(island_removal_mode 0)
		)
		(polygon
			(pts
				(arc
					(start 299.356272 -312.066686)
					(mid 298.703492 -312.066686)
					(end 299.356272 -312.066686)
				)
			)
		)
	)
	(zone
		(layers "B.Cu" "In4.Cu" "In6.Cu" "In11.Cu" "In13.Cu" "In15.Cu")
		(hatch none 0.5)
		(connect_pads
			(clearance 0)
		)
		(min_thickness 0.25)
		(keepout
			(tracks not_allowed)
			(vias allowed)
			(pads allowed)
			(copperpour not_allowed)
			(footprints allowed)
		)
		(placement
			(enabled no)
			(sheetname "")
		)
		(fill yes
			(thermal_gap 0.5)
			(thermal_bridge_width 0.5)
			(island_removal_mode 0)
		)
		(polygon
			(pts
				(arc
					(start 383.511552 -262.058658)
					(mid 382.858772 -262.058658)
					(end 383.511552 -262.058658)
				)
			)
		)
	)
	(zone
		(layers "B.Cu" "In4.Cu" "In6.Cu" "In11.Cu" "In13.Cu" "In15.Cu")
		(hatch none 0.5)
		(connect_pads
			(clearance 0)
		)
		(min_thickness 0.25)
		(keepout
			(tracks not_allowed)
			(vias allowed)
			(pads allowed)
			(copperpour not_allowed)
			(footprints allowed)
		)
		(placement
			(enabled no)
			(sheetname "")
		)
		(fill yes
			(thermal_gap 0.5)
			(thermal_bridge_width 0.5)
			(island_removal_mode 0)
		)
		(polygon
			(pts
				(arc
					(start 133.112002 -239.853216)
					(mid 132.459222 -239.853216)
					(end 133.112002 -239.853216)
				)
			)
		)
	)
	(zone
		(layers "B.Cu" "In4.Cu" "In6.Cu" "In11.Cu" "In13.Cu" "In15.Cu")
		(hatch none 0.5)
		(connect_pads
			(clearance 0)
		)
		(min_thickness 0.25)
		(keepout
			(tracks not_allowed)
			(vias allowed)
			(pads allowed)
			(copperpour not_allowed)
			(footprints allowed)
		)
		(placement
			(enabled no)
			(sheetname "")
		)
		(fill yes
			(thermal_gap 0.5)
			(thermal_bridge_width 0.5)
			(island_removal_mode 0)
		)
		(polygon
			(pts
				(arc
					(start 383.401824 -229.272846)
					(mid 382.749044 -229.272846)
					(end 383.401824 -229.272846)
				)
			)
		)
	)
	(zone
		(layers "B.Cu" "In4.Cu" "In6.Cu" "In11.Cu" "In13.Cu" "In15.Cu")
		(hatch none 0.5)
		(connect_pads
			(clearance 0)
		)
		(min_thickness 0.25)
		(keepout
			(tracks not_allowed)
			(vias allowed)
			(pads allowed)
			(copperpour not_allowed)
			(footprints allowed)
		)
		(placement
			(enabled no)
			(sheetname "")
		)
		(fill yes
			(thermal_gap 0.5)
			(thermal_bridge_width 0.5)
			(island_removal_mode 0)
		)
		(polygon
			(pts
				(arc
					(start 47.290736 -238.116618)
					(mid 46.637956 -238.116618)
					(end 47.290736 -238.116618)
				)
			)
		)
	)
	(zone
		(layers "B.Cu" "In4.Cu" "In6.Cu" "In11.Cu" "In13.Cu" "In15.Cu")
		(hatch none 0.5)
		(connect_pads
			(clearance 0)
		)
		(min_thickness 0.25)
		(keepout
			(tracks not_allowed)
			(vias allowed)
			(pads allowed)
			(copperpour not_allowed)
			(footprints allowed)
		)
		(placement
			(enabled no)
			(sheetname "")
		)
		(fill yes
			(thermal_gap 0.5)
			(thermal_bridge_width 0.5)
			(island_removal_mode 0)
		)
		(polygon
			(pts
				(arc
					(start 132.752338 -278.336502)
					(mid 132.099558 -278.336502)
					(end 132.752338 -278.336502)
				)
			)
		)
	)
	(zone
		(layers "B.Cu" "In4.Cu" "In6.Cu" "In11.Cu" "In13.Cu" "In15.Cu")
		(hatch none 0.5)
		(connect_pads
			(clearance 0)
		)
		(min_thickness 0.25)
		(keepout
			(tracks not_allowed)
			(vias allowed)
			(pads allowed)
			(copperpour not_allowed)
			(footprints allowed)
		)
		(placement
			(enabled no)
			(sheetname "")
		)
		(fill yes
			(thermal_gap 0.5)
			(thermal_bridge_width 0.5)
			(island_removal_mode 0)
		)
		(polygon
			(pts
				(arc
					(start 421.062404 -222.816674)
					(mid 420.409624 -222.816674)
					(end 421.062404 -222.816674)
				)
			)
		)
	)
	(zone
		(layers "B.Cu" "In4.Cu" "In6.Cu" "In11.Cu" "In13.Cu" "In15.Cu")
		(hatch none 0.5)
		(connect_pads
			(clearance 0)
		)
		(min_thickness 0.25)
		(keepout
			(tracks not_allowed)
			(vias allowed)
			(pads allowed)
			(copperpour not_allowed)
			(footprints allowed)
		)
		(placement
			(enabled no)
			(sheetname "")
		)
		(fill yes
			(thermal_gap 0.5)
			(thermal_bridge_width 0.5)
			(island_removal_mode 0)
		)
		(polygon
			(pts
				(arc
					(start 299.330872 -210.916774)
					(mid 298.678092 -210.916774)
					(end 299.330872 -210.916774)
				)
			)
		)
	)
	(zone
		(layers "B.Cu" "In4.Cu" "In6.Cu" "In11.Cu" "In13.Cu" "In15.Cu")
		(hatch none 0.5)
		(connect_pads
			(clearance 0)
		)
		(min_thickness 0.25)
		(keepout
			(tracks not_allowed)
			(vias allowed)
			(pads allowed)
			(copperpour not_allowed)
			(footprints allowed)
		)
		(placement
			(enabled no)
			(sheetname "")
		)
		(fill yes
			(thermal_gap 0.5)
			(thermal_bridge_width 0.5)
			(island_removal_mode 0)
		)
		(polygon
			(pts
				(arc
					(start 337.461606 -260.430772)
					(mid 336.808826 -260.430772)
					(end 337.461606 -260.430772)
				)
			)
		)
	)
	(zone
		(layers "B.Cu" "In4.Cu" "In6.Cu" "In11.Cu" "In13.Cu" "In15.Cu")
		(hatch none 0.5)
		(connect_pads
			(clearance 0)
		)
		(min_thickness 0.25)
		(keepout
			(tracks not_allowed)
			(vias allowed)
			(pads allowed)
			(copperpour not_allowed)
			(footprints allowed)
		)
		(placement
			(enabled no)
			(sheetname "")
		)
		(fill yes
			(thermal_gap 0.5)
			(thermal_bridge_width 0.5)
			(island_removal_mode 0)
		)
		(polygon
			(pts
				(arc
					(start 101.738938 -286.475424)
					(mid 101.086158 -286.475424)
					(end 101.738938 -286.475424)
				)
			)
		)
	)
	(zone
		(layers "B.Cu" "In4.Cu" "In6.Cu" "In11.Cu" "In13.Cu" "In15.Cu")
		(hatch none 0.5)
		(connect_pads
			(clearance 0)
		)
		(min_thickness 0.25)
		(keepout
			(tracks not_allowed)
			(vias allowed)
			(pads allowed)
			(copperpour not_allowed)
			(footprints allowed)
		)
		(placement
			(enabled no)
			(sheetname "")
		)
		(fill yes
			(thermal_gap 0.5)
			(thermal_bridge_width 0.5)
			(island_removal_mode 0)
		)
		(polygon
			(pts
				(arc
					(start 51.390804 -246.616728)
					(mid 50.738024 -246.616728)
					(end 51.390804 -246.616728)
				)
			)
		)
	)
	(zone
		(layers "B.Cu" "In4.Cu" "In6.Cu" "In11.Cu" "In13.Cu" "In15.Cu")
		(hatch none 0.5)
		(connect_pads
			(clearance 0)
		)
		(min_thickness 0.25)
		(keepout
			(tracks not_allowed)
			(vias allowed)
			(pads allowed)
			(copperpour not_allowed)
			(footprints allowed)
		)
		(placement
			(enabled no)
			(sheetname "")
		)
		(fill yes
			(thermal_gap 0.5)
			(thermal_bridge_width 0.5)
			(island_removal_mode 0)
		)
		(polygon
			(pts
				(arc
					(start 299.330872 -250.016772)
					(mid 298.678092 -250.016772)
					(end 299.330872 -250.016772)
				)
			)
		)
	)
	(zone
		(layers "B.Cu" "In4.Cu" "In6.Cu" "In11.Cu" "In13.Cu" "In15.Cu")
		(hatch none 0.5)
		(connect_pads
			(clearance 0)
		)
		(min_thickness 0.25)
		(keepout
			(tracks not_allowed)
			(vias allowed)
			(pads allowed)
			(copperpour not_allowed)
			(footprints allowed)
		)
		(placement
			(enabled no)
			(sheetname "")
		)
		(fill yes
			(thermal_gap 0.5)
			(thermal_bridge_width 0.5)
			(island_removal_mode 0)
		)
		(polygon
			(pts
				(arc
					(start 158.009336 -226.216718)
					(mid 157.356556 -226.216718)
					(end 158.009336 -226.216718)
				)
			)
		)
	)
	(zone
		(layers "B.Cu" "In4.Cu" "In6.Cu" "In11.Cu" "In13.Cu" "In15.Cu")
		(hatch none 0.5)
		(connect_pads
			(clearance 0)
		)
		(min_thickness 0.25)
		(keepout
			(tracks not_allowed)
			(vias allowed)
			(pads allowed)
			(copperpour not_allowed)
			(footprints allowed)
		)
		(placement
			(enabled no)
			(sheetname "")
		)
		(fill yes
			(thermal_gap 0.5)
			(thermal_bridge_width 0.5)
			(island_removal_mode 0)
		)
		(polygon
			(pts
				(arc
					(start 128.522984 -285.661354)
					(mid 127.870204 -285.661354)
					(end 128.522984 -285.661354)
				)
			)
		)
	)
	(zone
		(layers "B.Cu" "In4.Cu" "In6.Cu" "In11.Cu" "In13.Cu" "In15.Cu")
		(hatch none 0.5)
		(connect_pads
			(clearance 0)
		)
		(min_thickness 0.25)
		(keepout
			(tracks not_allowed)
			(vias allowed)
			(pads allowed)
			(copperpour not_allowed)
			(footprints allowed)
		)
		(placement
			(enabled no)
			(sheetname "")
		)
		(fill yes
			(thermal_gap 0.5)
			(thermal_bridge_width 0.5)
			(island_removal_mode 0)
		)
		(polygon
			(pts
				(arc
					(start 383.871724 -230.086662)
					(mid 383.218944 -230.086662)
					(end 383.871724 -230.086662)
				)
			)
		)
	)
	(zone
		(layers "B.Cu" "In4.Cu" "In6.Cu" "In11.Cu" "In13.Cu" "In15.Cu")
		(hatch none 0.5)
		(connect_pads
			(clearance 0)
		)
		(min_thickness 0.25)
		(keepout
			(tracks not_allowed)
			(vias allowed)
			(pads allowed)
			(copperpour not_allowed)
			(footprints allowed)
		)
		(placement
			(enabled no)
			(sheetname "")
		)
		(fill yes
			(thermal_gap 0.5)
			(thermal_bridge_width 0.5)
			(island_removal_mode 0)
		)
		(polygon
			(pts
				(arc
					(start 90.461084 -265.314176)
					(mid 89.808304 -265.314176)
					(end 90.461084 -265.314176)
				)
			)
		)
	)
	(zone
		(layers "B.Cu" "In4.Cu" "In6.Cu" "In11.Cu" "In13.Cu" "In15.Cu")
		(hatch none 0.5)
		(connect_pads
			(clearance 0)
		)
		(min_thickness 0.25)
		(keepout
			(tracks not_allowed)
			(vias allowed)
			(pads allowed)
			(copperpour not_allowed)
			(footprints allowed)
		)
		(placement
			(enabled no)
			(sheetname "")
		)
		(fill yes
			(thermal_gap 0.5)
			(thermal_bridge_width 0.5)
			(island_removal_mode 0)
		)
		(polygon
			(pts
				(arc
					(start 352.498406 -284.847538)
					(mid 351.845626 -284.847538)
					(end 352.498406 -284.847538)
				)
			)
		)
	)
	(zone
		(layers "B.Cu" "In4.Cu" "In6.Cu" "In11.Cu" "In13.Cu" "In15.Cu")
		(hatch none 0.5)
		(connect_pads
			(clearance 0)
		)
		(min_thickness 0.25)
		(keepout
			(tracks not_allowed)
			(vias allowed)
			(pads allowed)
			(copperpour not_allowed)
			(footprints allowed)
		)
		(placement
			(enabled no)
			(sheetname "")
		)
		(fill yes
			(thermal_gap 0.5)
			(thermal_bridge_width 0.5)
			(island_removal_mode 0)
		)
		(polygon
			(pts
				(arc
					(start 177.222404 -244.916706)
					(mid 176.569624 -244.916706)
					(end 177.222404 -244.916706)
				)
			)
		)
	)
	(zone
		(layers "B.Cu" "In4.Cu" "In6.Cu" "In11.Cu" "In13.Cu" "In15.Cu")
		(hatch none 0.5)
		(connect_pads
			(clearance 0)
		)
		(min_thickness 0.25)
		(keepout
			(tracks not_allowed)
			(vias allowed)
			(pads allowed)
			(copperpour not_allowed)
			(footprints allowed)
		)
		(placement
			(enabled no)
			(sheetname "")
		)
		(fill yes
			(thermal_gap 0.5)
			(thermal_bridge_width 0.5)
			(island_removal_mode 0)
		)
		(polygon
			(pts
				(arc
					(start 71.120508 -407.00452)
					(mid 70.416928 -407.00452)
					(end 71.120508 -407.00452)
				)
			)
		)
	)
	(zone
		(layers "B.Cu" "In4.Cu" "In6.Cu" "In11.Cu" "In13.Cu" "In15.Cu")
		(hatch none 0.5)
		(connect_pads
			(clearance 0)
		)
		(min_thickness 0.25)
		(keepout
			(tracks not_allowed)
			(vias allowed)
			(pads allowed)
			(copperpour not_allowed)
			(footprints allowed)
		)
		(placement
			(enabled no)
			(sheetname "")
		)
		(fill yes
			(thermal_gap 0.5)
			(thermal_bridge_width 0.5)
			(island_removal_mode 0)
		)
		(polygon
			(pts
				(arc
					(start 62.378336 -230.466646)
					(mid 61.725556 -230.466646)
					(end 62.378336 -230.466646)
				)
			)
		)
	)
	(zone
		(layers "B.Cu" "In4.Cu" "In6.Cu" "In11.Cu" "In13.Cu" "In15.Cu")
		(hatch none 0.5)
		(connect_pads
			(clearance 0)
		)
		(min_thickness 0.25)
		(keepout
			(tracks not_allowed)
			(vias allowed)
			(pads allowed)
			(copperpour not_allowed)
			(footprints allowed)
		)
		(placement
			(enabled no)
			(sheetname "")
		)
		(fill yes
			(thermal_gap 0.5)
			(thermal_bridge_width 0.5)
			(island_removal_mode 0)
		)
		(polygon
			(pts
				(arc
					(start 381.05207 -239.853216)
					(mid 380.39929 -239.853216)
					(end 381.05207 -239.853216)
				)
			)
		)
	)
	(zone
		(layers "B.Cu" "In4.Cu" "In6.Cu" "In11.Cu" "In13.Cu" "In15.Cu")
		(hatch none 0.5)
		(connect_pads
			(clearance 0)
		)
		(min_thickness 0.25)
		(keepout
			(tracks not_allowed)
			(vias allowed)
			(pads allowed)
			(copperpour not_allowed)
			(footprints allowed)
		)
		(placement
			(enabled no)
			(sheetname "")
		)
		(fill yes
			(thermal_gap 0.5)
			(thermal_bridge_width 0.5)
			(island_removal_mode 0)
		)
		(polygon
			(pts
				(arc
					(start 89.411556 -239.0394)
					(mid 88.758776 -239.0394)
					(end 89.411556 -239.0394)
				)
			)
		)
	)
	(zone
		(layers "B.Cu" "In4.Cu" "In6.Cu" "In11.Cu" "In13.Cu" "In15.Cu")
		(hatch none 0.5)
		(connect_pads
			(clearance 0)
		)
		(min_thickness 0.25)
		(keepout
			(tracks not_allowed)
			(vias allowed)
			(pads allowed)
			(copperpour not_allowed)
			(footprints allowed)
		)
		(placement
			(enabled no)
			(sheetname "")
		)
		(fill yes
			(thermal_gap 0.5)
			(thermal_bridge_width 0.5)
			(island_removal_mode 0)
		)
		(polygon
			(pts
				(arc
					(start 338.291424 -248.806208)
					(mid 337.638644 -248.806208)
					(end 338.291424 -248.806208)
				)
			)
		)
	)
	(zone
		(layers "B.Cu" "In4.Cu" "In6.Cu" "In11.Cu" "In13.Cu" "In15.Cu")
		(hatch none 0.5)
		(connect_pads
			(clearance 0)
		)
		(min_thickness 0.25)
		(keepout
			(tracks not_allowed)
			(vias allowed)
			(pads allowed)
			(copperpour not_allowed)
			(footprints allowed)
		)
		(placement
			(enabled no)
			(sheetname "")
		)
		(fill yes
			(thermal_gap 0.5)
			(thermal_bridge_width 0.5)
			(island_removal_mode 0)
		)
		(polygon
			(pts
				(arc
					(start 383.17424 -407.00452)
					(mid 382.47066 -407.00452)
					(end 383.17424 -407.00452)
				)
			)
		)
	)
	(zone
		(layers "B.Cu" "In4.Cu" "In6.Cu" "In11.Cu" "In13.Cu" "In15.Cu")
		(hatch none 0.5)
		(connect_pads
			(clearance 0)
		)
		(min_thickness 0.25)
		(keepout
			(tracks not_allowed)
			(vias allowed)
			(pads allowed)
			(copperpour not_allowed)
			(footprints allowed)
		)
		(placement
			(enabled no)
			(sheetname "")
		)
		(fill yes
			(thermal_gap 0.5)
			(thermal_bridge_width 0.5)
			(island_removal_mode 0)
		)
		(polygon
			(pts
				(arc
					(start 109.617002 -223.575626)
					(mid 108.964222 -223.575626)
					(end 109.617002 -223.575626)
				)
			)
		)
	)
	(zone
		(layers "B.Cu" "In4.Cu" "In6.Cu" "In11.Cu" "In13.Cu" "In15.Cu")
		(hatch none 0.5)
		(connect_pads
			(clearance 0)
		)
		(min_thickness 0.25)
		(keepout
			(tracks not_allowed)
			(vias allowed)
			(pads allowed)
			(copperpour not_allowed)
			(footprints allowed)
		)
		(placement
			(enabled no)
			(sheetname "")
		)
		(fill yes
			(thermal_gap 0.5)
			(thermal_bridge_width 0.5)
			(island_removal_mode 0)
		)
		(polygon
			(pts
				(arc
					(start 100.328984 -285.661354)
					(mid 99.676204 -285.661354)
					(end 100.328984 -285.661354)
				)
			)
		)
	)
	(zone
		(layers "B.Cu" "In4.Cu" "In6.Cu" "In11.Cu" "In13.Cu" "In15.Cu")
		(hatch none 0.5)
		(connect_pads
			(clearance 0)
		)
		(min_thickness 0.25)
		(keepout
			(tracks not_allowed)
			(vias allowed)
			(pads allowed)
			(copperpour not_allowed)
			(footprints allowed)
		)
		(placement
			(enabled no)
			(sheetname "")
		)
		(fill yes
			(thermal_gap 0.5)
			(thermal_bridge_width 0.5)
			(island_removal_mode 0)
		)
		(polygon
			(pts
				(arc
					(start 381.522224 -230.900478)
					(mid 380.869444 -230.900478)
					(end 381.522224 -230.900478)
				)
			)
		)
	)
	(zone
		(layers "B.Cu" "In4.Cu" "In6.Cu" "In11.Cu" "In13.Cu" "In15.Cu")
		(hatch none 0.5)
		(connect_pads
			(clearance 0)
		)
		(min_thickness 0.25)
		(keepout
			(tracks not_allowed)
			(vias allowed)
			(pads allowed)
			(copperpour not_allowed)
			(footprints allowed)
		)
		(placement
			(enabled no)
			(sheetname "")
		)
		(fill yes
			(thermal_gap 0.5)
			(thermal_bridge_width 0.5)
			(island_removal_mode 0)
		)
		(polygon
			(pts
				(arc
					(start 47.290736 -241.516662)
					(mid 46.637956 -241.516662)
					(end 47.290736 -241.516662)
				)
			)
		)
	)
	(zone
		(layers "B.Cu" "In4.Cu" "In6.Cu" "In11.Cu" "In13.Cu" "In15.Cu")
		(hatch none 0.5)
		(connect_pads
			(clearance 0)
		)
		(min_thickness 0.25)
		(keepout
			(tracks not_allowed)
			(vias allowed)
			(pads allowed)
			(copperpour not_allowed)
			(footprints allowed)
		)
		(placement
			(enabled no)
			(sheetname "")
		)
		(fill yes
			(thermal_gap 0.5)
			(thermal_bridge_width 0.5)
			(island_removal_mode 0)
		)
		(polygon
			(pts
				(arc
					(start 62.378336 -305.266598)
					(mid 61.725556 -305.266598)
					(end 62.378336 -305.266598)
				)
			)
		)
	)
	(zone
		(layers "B.Cu" "In4.Cu" "In6.Cu" "In11.Cu" "In13.Cu" "In15.Cu")
		(hatch none 0.5)
		(connect_pads
			(clearance 0)
		)
		(min_thickness 0.25)
		(keepout
			(tracks not_allowed)
			(vias allowed)
			(pads allowed)
			(copperpour not_allowed)
			(footprints allowed)
		)
		(placement
			(enabled no)
			(sheetname "")
		)
		(fill yes
			(thermal_gap 0.5)
			(thermal_bridge_width 0.5)
			(island_removal_mode 0)
		)
		(polygon
			(pts
				(arc
					(start 134.161784 -264.50036)
					(mid 133.509004 -264.50036)
					(end 134.161784 -264.50036)
				)
			)
		)
	)
	(zone
		(layers "B.Cu" "In4.Cu" "In6.Cu" "In11.Cu" "In13.Cu" "In15.Cu")
		(hatch none 0.5)
		(connect_pads
			(clearance 0)
		)
		(min_thickness 0.25)
		(keepout
			(tracks not_allowed)
			(vias allowed)
			(pads allowed)
			(copperpour not_allowed)
			(footprints allowed)
		)
		(placement
			(enabled no)
			(sheetname "")
		)
		(fill yes
			(thermal_gap 0.5)
			(thermal_bridge_width 0.5)
			(island_removal_mode 0)
		)
		(polygon
			(pts
				(arc
					(start 428.606204 -245.76659)
					(mid 427.953424 -245.76659)
					(end 428.606204 -245.76659)
				)
			)
		)
	)
	(zone
		(layers "B.Cu" "In4.Cu" "In6.Cu" "In11.Cu" "In13.Cu" "In15.Cu")
		(hatch none 0.5)
		(connect_pads
			(clearance 0)
		)
		(min_thickness 0.25)
		(keepout
			(tracks not_allowed)
			(vias allowed)
			(pads allowed)
			(copperpour not_allowed)
			(footprints allowed)
		)
		(placement
			(enabled no)
			(sheetname "")
		)
		(fill yes
			(thermal_gap 0.5)
			(thermal_bridge_width 0.5)
			(island_removal_mode 0)
		)
		(polygon
			(pts
				(arc
					(start 47.290736 -221.116652)
					(mid 46.637956 -221.116652)
					(end 47.290736 -221.116652)
				)
			)
		)
	)
	(zone
		(layers "B.Cu" "In4.Cu" "In6.Cu" "In11.Cu" "In13.Cu" "In15.Cu")
		(hatch none 0.5)
		(connect_pads
			(clearance 0)
		)
		(min_thickness 0.25)
		(keepout
			(tracks not_allowed)
			(vias allowed)
			(pads allowed)
			(copperpour not_allowed)
			(footprints allowed)
		)
		(placement
			(enabled no)
			(sheetname "")
		)
		(fill yes
			(thermal_gap 0.5)
			(thermal_bridge_width 0.5)
			(island_removal_mode 0)
		)
		(polygon
			(pts
				(arc
					(start 382.931924 -231.714548)
					(mid 382.279144 -231.714548)
					(end 382.931924 -231.714548)
				)
			)
		)
	)
	(zone
		(layers "B.Cu" "In4.Cu" "In6.Cu" "In11.Cu" "In13.Cu" "In15.Cu")
		(hatch none 0.5)
		(connect_pads
			(clearance 0)
		)
		(min_thickness 0.25)
		(keepout
			(tracks not_allowed)
			(vias allowed)
			(pads allowed)
			(copperpour not_allowed)
			(footprints allowed)
		)
		(placement
			(enabled no)
			(sheetname "")
		)
		(fill yes
			(thermal_gap 0.5)
			(thermal_bridge_width 0.5)
			(island_removal_mode 0)
		)
		(polygon
			(pts
				(arc
					(start 392.36396 -407.00452)
					(mid 391.66038 -407.00452)
					(end 392.36396 -407.00452)
				)
			)
		)
	)
	(zone
		(layers "B.Cu" "In4.Cu" "In6.Cu" "In11.Cu" "In13.Cu" "In15.Cu")
		(hatch none 0.5)
		(connect_pads
			(clearance 0)
		)
		(min_thickness 0.25)
		(keepout
			(tracks not_allowed)
			(vias allowed)
			(pads allowed)
			(copperpour not_allowed)
			(footprints allowed)
		)
		(placement
			(enabled no)
			(sheetname "")
		)
		(fill yes
			(thermal_gap 0.5)
			(thermal_bridge_width 0.5)
			(island_removal_mode 0)
		)
		(polygon
			(pts
				(arc
					(start 409.8798 -407.00452)
					(mid 409.17622 -407.00452)
					(end 409.8798 -407.00452)
				)
			)
		)
	)
	(zone
		(layers "B.Cu" "In4.Cu" "In6.Cu" "In11.Cu" "In13.Cu" "In15.Cu")
		(hatch none 0.5)
		(connect_pads
			(clearance 0)
		)
		(min_thickness 0.25)
		(keepout
			(tracks not_allowed)
			(vias allowed)
			(pads allowed)
			(copperpour not_allowed)
			(footprints allowed)
		)
		(placement
			(enabled no)
			(sheetname "")
		)
		(fill yes
			(thermal_gap 0.5)
			(thermal_bridge_width 0.5)
			(island_removal_mode 0)
		)
		(polygon
			(pts
				(arc
					(start 138.281156 -224.389442)
					(mid 137.628376 -224.389442)
					(end 138.281156 -224.389442)
				)
			)
		)
	)
	(zone
		(layers "B.Cu" "In4.Cu" "In6.Cu" "In11.Cu" "In13.Cu" "In15.Cu")
		(hatch none 0.5)
		(connect_pads
			(clearance 0)
		)
		(min_thickness 0.25)
		(keepout
			(tracks not_allowed)
			(vias allowed)
			(pads allowed)
			(copperpour not_allowed)
			(footprints allowed)
		)
		(placement
			(enabled no)
			(sheetname "")
		)
		(fill yes
			(thermal_gap 0.5)
			(thermal_bridge_width 0.5)
			(island_removal_mode 0)
		)
		(polygon
			(pts
				(arc
					(start 133.221984 -272.639282)
					(mid 132.569204 -272.639282)
					(end 133.221984 -272.639282)
				)
			)
		)
	)
	(zone
		(layers "B.Cu" "In4.Cu" "In6.Cu" "In11.Cu" "In13.Cu" "In15.Cu")
		(hatch none 0.5)
		(connect_pads
			(clearance 0)
		)
		(min_thickness 0.25)
		(keepout
			(tracks not_allowed)
			(vias allowed)
			(pads allowed)
			(copperpour not_allowed)
			(footprints allowed)
		)
		(placement
			(enabled no)
			(sheetname "")
		)
		(fill yes
			(thermal_gap 0.5)
			(thermal_bridge_width 0.5)
			(island_removal_mode 0)
		)
		(polygon
			(pts
				(arc
					(start 91.401138 -265.314176)
					(mid 90.748358 -265.314176)
					(end 91.401138 -265.314176)
				)
			)
		)
	)
	(zone
		(layers "B.Cu" "In4.Cu" "In6.Cu" "In11.Cu" "In13.Cu" "In15.Cu")
		(hatch none 0.5)
		(connect_pads
			(clearance 0)
		)
		(min_thickness 0.25)
		(keepout
			(tracks not_allowed)
			(vias allowed)
			(pads allowed)
			(copperpour not_allowed)
			(footprints allowed)
		)
		(placement
			(enabled no)
			(sheetname "")
		)
		(fill yes
			(thermal_gap 0.5)
			(thermal_bridge_width 0.5)
			(island_removal_mode 0)
		)
		(polygon
			(pts
				(arc
					(start 168.665144 -407.00452)
					(mid 167.961564 -407.00452)
					(end 168.665144 -407.00452)
				)
			)
		)
	)
	(zone
		(layers "B.Cu" "In4.Cu" "In6.Cu" "In11.Cu" "In13.Cu" "In15.Cu")
		(hatch none 0.5)
		(connect_pads
			(clearance 0)
		)
		(min_thickness 0.25)
		(keepout
			(tracks not_allowed)
			(vias allowed)
			(pads allowed)
			(copperpour not_allowed)
			(footprints allowed)
		)
		(placement
			(enabled no)
			(sheetname "")
		)
		(fill yes
			(thermal_gap 0.5)
			(thermal_bridge_width 0.5)
			(island_removal_mode 0)
		)
		(polygon
			(pts
				(arc
					(start 138.281156 -222.761556)
					(mid 137.628376 -222.761556)
					(end 138.281156 -222.761556)
				)
			)
		)
	)
	(zone
		(layers "B.Cu" "In4.Cu" "In6.Cu" "In11.Cu" "In13.Cu" "In15.Cu")
		(hatch none 0.5)
		(connect_pads
			(clearance 0)
		)
		(min_thickness 0.25)
		(keepout
			(tracks not_allowed)
			(vias allowed)
			(pads allowed)
			(copperpour not_allowed)
			(footprints allowed)
		)
		(placement
			(enabled no)
			(sheetname "")
		)
		(fill yes
			(thermal_gap 0.5)
			(thermal_bridge_width 0.5)
			(island_removal_mode 0)
		)
		(polygon
			(pts
				(arc
					(start 90.351356 -248.806208)
					(mid 89.698576 -248.806208)
					(end 90.351356 -248.806208)
				)
			)
		)
	)
	(zone
		(layers "B.Cu" "In4.Cu" "In6.Cu" "In11.Cu" "In13.Cu" "In15.Cu")
		(hatch none 0.5)
		(connect_pads
			(clearance 0)
		)
		(min_thickness 0.25)
		(keepout
			(tracks not_allowed)
			(vias allowed)
			(pads allowed)
			(copperpour not_allowed)
			(footprints allowed)
		)
		(placement
			(enabled no)
			(sheetname "")
		)
		(fill yes
			(thermal_gap 0.5)
			(thermal_bridge_width 0.5)
			(island_removal_mode 0)
		)
		(polygon
			(pts
				(arc
					(start 338.401152 -266.941808)
					(mid 337.748372 -266.941808)
					(end 338.401152 -266.941808)
				)
			)
		)
	)
	(zone
		(layers "B.Cu" "In4.Cu" "In6.Cu" "In11.Cu" "In13.Cu" "In15.Cu")
		(hatch none 0.5)
		(connect_pads
			(clearance 0)
		)
		(min_thickness 0.25)
		(keepout
			(tracks not_allowed)
			(vias allowed)
			(pads allowed)
			(copperpour not_allowed)
			(footprints allowed)
		)
		(placement
			(enabled no)
			(sheetname "")
		)
		(fill yes
			(thermal_gap 0.5)
			(thermal_bridge_width 0.5)
			(island_removal_mode 0)
		)
		(polygon
			(pts
				(arc
					(start 43.847004 -260.21665)
					(mid 43.194224 -260.21665)
					(end 43.847004 -260.21665)
				)
			)
		)
	)
	(zone
		(layers "B.Cu" "In4.Cu" "In6.Cu" "In11.Cu" "In13.Cu" "In15.Cu")
		(hatch none 0.5)
		(connect_pads
			(clearance 0)
		)
		(min_thickness 0.25)
		(keepout
			(tracks not_allowed)
			(vias allowed)
			(pads allowed)
			(copperpour not_allowed)
			(footprints allowed)
		)
		(placement
			(enabled no)
			(sheetname "")
		)
		(fill yes
			(thermal_gap 0.5)
			(thermal_bridge_width 0.5)
			(island_removal_mode 0)
		)
		(polygon
			(pts
				(arc
					(start 421.062404 -247.466612)
					(mid 420.409624 -247.466612)
					(end 421.062404 -247.466612)
				)
			)
		)
	)
	(zone
		(layers "B.Cu" "In4.Cu" "In6.Cu" "In11.Cu" "In13.Cu" "In15.Cu")
		(hatch none 0.5)
		(connect_pads
			(clearance 0)
		)
		(min_thickness 0.25)
		(keepout
			(tracks not_allowed)
			(vias allowed)
			(pads allowed)
			(copperpour not_allowed)
			(footprints allowed)
		)
		(placement
			(enabled no)
			(sheetname "")
		)
		(fill yes
			(thermal_gap 0.5)
			(thermal_bridge_width 0.5)
			(island_removal_mode 0)
		)
		(polygon
			(pts
				(arc
					(start 112.436402 -225.203258)
					(mid 111.783622 -225.203258)
					(end 112.436402 -225.203258)
				)
			)
		)
	)
	(zone
		(layers "B.Cu" "In4.Cu" "In6.Cu" "In11.Cu" "In13.Cu" "In15.Cu")
		(hatch none 0.5)
		(connect_pads
			(clearance 0)
		)
		(min_thickness 0.25)
		(keepout
			(tracks not_allowed)
			(vias allowed)
			(pads allowed)
			(copperpour not_allowed)
			(footprints allowed)
		)
		(placement
			(enabled no)
			(sheetname "")
		)
		(fill yes
			(thermal_gap 0.5)
			(thermal_bridge_width 0.5)
			(island_removal_mode 0)
		)
		(polygon
			(pts
				(arc
					(start 87.300308 -407.00452)
					(mid 86.596728 -407.00452)
					(end 87.300308 -407.00452)
				)
			)
		)
	)
	(zone
		(layers "B.Cu" "In4.Cu" "In6.Cu" "In11.Cu" "In13.Cu" "In15.Cu")
		(hatch none 0.5)
		(connect_pads
			(clearance 0)
		)
		(min_thickness 0.25)
		(keepout
			(tracks not_allowed)
			(vias allowed)
			(pads allowed)
			(copperpour not_allowed)
			(footprints allowed)
		)
		(placement
			(enabled no)
			(sheetname "")
		)
		(fill yes
			(thermal_gap 0.5)
			(thermal_bridge_width 0.5)
			(island_removal_mode 0)
		)
		(polygon
			(pts
				(arc
					(start 295.230804 -211.766658)
					(mid 294.578024 -211.766658)
					(end 295.230804 -211.766658)
				)
			)
		)
	)
	(zone
		(layers "B.Cu" "In4.Cu" "In6.Cu" "In11.Cu" "In13.Cu" "In15.Cu")
		(hatch none 0.5)
		(connect_pads
			(clearance 0)
		)
		(min_thickness 0.25)
		(keepout
			(tracks not_allowed)
			(vias allowed)
			(pads allowed)
			(copperpour not_allowed)
			(footprints allowed)
		)
		(placement
			(enabled no)
			(sheetname "")
		)
		(fill yes
			(thermal_gap 0.5)
			(thermal_bridge_width 0.5)
			(island_removal_mode 0)
		)
		(polygon
			(pts
				(arc
					(start 135.571484 -263.686544)
					(mid 134.918704 -263.686544)
					(end 135.571484 -263.686544)
				)
			)
		)
	)
	(zone
		(layers "B.Cu" "In4.Cu" "In6.Cu" "In11.Cu" "In13.Cu" "In15.Cu")
		(hatch none 0.5)
		(connect_pads
			(clearance 0)
		)
		(min_thickness 0.25)
		(keepout
			(tracks not_allowed)
			(vias allowed)
			(pads allowed)
			(copperpour not_allowed)
			(footprints allowed)
		)
		(placement
			(enabled no)
			(sheetname "")
		)
		(fill yes
			(thermal_gap 0.5)
			(thermal_bridge_width 0.5)
			(island_removal_mode 0)
		)
		(polygon
			(pts
				(arc
					(start 421.062404 -289.966654)
					(mid 420.409624 -289.966654)
					(end 421.062404 -289.966654)
				)
			)
		)
	)
	(zone
		(layers "B.Cu" "In4.Cu" "In6.Cu" "In11.Cu" "In13.Cu" "In15.Cu")
		(hatch none 0.5)
		(connect_pads
			(clearance 0)
		)
		(min_thickness 0.25)
		(keepout
			(tracks not_allowed)
			(vias allowed)
			(pads allowed)
			(copperpour not_allowed)
			(footprints allowed)
		)
		(placement
			(enabled no)
			(sheetname "")
		)
		(fill yes
			(thermal_gap 0.5)
			(thermal_bridge_width 0.5)
			(island_removal_mode 0)
		)
		(polygon
			(pts
				(arc
					(start 425.162472 -240.666778)
					(mid 424.509692 -240.666778)
					(end 425.162472 -240.666778)
				)
			)
		)
	)
	(zone
		(layers "B.Cu" "In4.Cu" "In6.Cu" "In11.Cu" "In13.Cu" "In15.Cu")
		(hatch none 0.5)
		(connect_pads
			(clearance 0)
		)
		(min_thickness 0.25)
		(keepout
			(tracks not_allowed)
			(vias allowed)
			(pads allowed)
			(copperpour not_allowed)
			(footprints allowed)
		)
		(placement
			(enabled no)
			(sheetname "")
		)
		(fill yes
			(thermal_gap 0.5)
			(thermal_bridge_width 0.5)
			(island_removal_mode 0)
		)
		(polygon
			(pts
				(arc
					(start 134.161784 -256.361438)
					(mid 133.509004 -256.361438)
					(end 134.161784 -256.361438)
				)
			)
		)
	)
	(zone
		(layers "B.Cu" "In4.Cu" "In6.Cu" "In11.Cu" "In13.Cu" "In15.Cu")
		(hatch none 0.5)
		(connect_pads
			(clearance 0)
		)
		(min_thickness 0.25)
		(keepout
			(tracks not_allowed)
			(vias allowed)
			(pads allowed)
			(copperpour not_allowed)
			(footprints allowed)
		)
		(placement
			(enabled no)
			(sheetname "")
		)
		(fill yes
			(thermal_gap 0.5)
			(thermal_bridge_width 0.5)
			(island_removal_mode 0)
		)
		(polygon
			(pts
				(arc
					(start 314.418472 -227.066602)
					(mid 313.765692 -227.066602)
					(end 314.418472 -227.066602)
				)
			)
		)
	)
	(zone
		(layers "B.Cu" "In4.Cu" "In6.Cu" "In11.Cu" "In13.Cu" "In15.Cu")
		(hatch none 0.5)
		(connect_pads
			(clearance 0)
		)
		(min_thickness 0.25)
		(keepout
			(tracks not_allowed)
			(vias allowed)
			(pads allowed)
			(copperpour not_allowed)
			(footprints allowed)
		)
		(placement
			(enabled no)
			(sheetname "")
		)
		(fill yes
			(thermal_gap 0.5)
			(thermal_bridge_width 0.5)
			(island_removal_mode 0)
		)
		(polygon
			(pts
				(arc
					(start 425.162472 -210.916774)
					(mid 424.509692 -210.916774)
					(end 425.162472 -210.916774)
				)
			)
		)
	)
	(zone
		(layers "B.Cu" "In4.Cu" "In6.Cu" "In11.Cu" "In13.Cu" "In15.Cu")
		(hatch none 0.5)
		(connect_pads
			(clearance 0)
		)
		(min_thickness 0.25)
		(keepout
			(tracks not_allowed)
			(vias allowed)
			(pads allowed)
			(copperpour not_allowed)
			(footprints allowed)
		)
		(placement
			(enabled no)
			(sheetname "")
		)
		(fill yes
			(thermal_gap 0.5)
			(thermal_bridge_width 0.5)
			(island_removal_mode 0)
		)
		(polygon
			(pts
				(arc
					(start 88.581484 -275.08073)
					(mid 87.928704 -275.08073)
					(end 88.581484 -275.08073)
				)
			)
		)
	)
	(zone
		(layers "B.Cu" "In4.Cu" "In6.Cu" "In11.Cu" "In13.Cu" "In15.Cu")
		(hatch none 0.5)
		(connect_pads
			(clearance 0)
		)
		(min_thickness 0.25)
		(keepout
			(tracks not_allowed)
			(vias allowed)
			(pads allowed)
			(copperpour not_allowed)
			(footprints allowed)
		)
		(placement
			(enabled no)
			(sheetname "")
		)
		(fill yes
			(thermal_gap 0.5)
			(thermal_bridge_width 0.5)
			(island_removal_mode 0)
		)
		(polygon
			(pts
				(arc
					(start 295.230804 -239.81664)
					(mid 294.578024 -239.81664)
					(end 295.230804 -239.81664)
				)
			)
		)
	)
	(zone
		(layers "B.Cu" "In4.Cu" "In6.Cu" "In11.Cu" "In13.Cu" "In15.Cu")
		(hatch none 0.5)
		(connect_pads
			(clearance 0)
		)
		(min_thickness 0.25)
		(keepout
			(tracks not_allowed)
			(vias allowed)
			(pads allowed)
			(copperpour not_allowed)
			(footprints allowed)
		)
		(placement
			(enabled no)
			(sheetname "")
		)
		(fill yes
			(thermal_gap 0.5)
			(thermal_bridge_width 0.5)
			(island_removal_mode 0)
		)
		(polygon
			(pts
				(arc
					(start 144.159224 -407.00452)
					(mid 143.455644 -407.00452)
					(end 144.159224 -407.00452)
				)
			)
		)
	)
	(zone
		(layers "B.Cu" "In4.Cu" "In6.Cu" "In11.Cu" "In13.Cu" "In15.Cu")
		(hatch none 0.5)
		(connect_pads
			(clearance 0)
		)
		(min_thickness 0.25)
		(keepout
			(tracks not_allowed)
			(vias allowed)
			(pads allowed)
			(copperpour not_allowed)
			(footprints allowed)
		)
		(placement
			(enabled no)
			(sheetname "")
		)
		(fill yes
			(thermal_gap 0.5)
			(thermal_bridge_width 0.5)
			(island_removal_mode 0)
		)
		(polygon
			(pts
				(arc
					(start 130.872738 -255.547622)
					(mid 130.219958 -255.547622)
					(end 130.872738 -255.547622)
				)
			)
		)
	)
	(zone
		(layers "B.Cu" "In4.Cu" "In6.Cu" "In11.Cu" "In13.Cu" "In15.Cu")
		(hatch none 0.5)
		(connect_pads
			(clearance 0)
		)
		(min_thickness 0.25)
		(keepout
			(tracks not_allowed)
			(vias allowed)
			(pads allowed)
			(copperpour not_allowed)
			(footprints allowed)
		)
		(placement
			(enabled no)
			(sheetname "")
		)
		(fill yes
			(thermal_gap 0.5)
			(thermal_bridge_width 0.5)
			(island_removal_mode 0)
		)
		(polygon
			(pts
				(arc
					(start 383.981452 -267.755878)
					(mid 383.328672 -267.755878)
					(end 383.981452 -267.755878)
				)
			)
		)
	)
	(zone
		(layers "B.Cu" "In4.Cu" "In6.Cu" "In11.Cu" "In13.Cu" "In15.Cu")
		(hatch none 0.5)
		(connect_pads
			(clearance 0)
		)
		(min_thickness 0.25)
		(keepout
			(tracks not_allowed)
			(vias allowed)
			(pads allowed)
			(copperpour not_allowed)
			(footprints allowed)
		)
		(placement
			(enabled no)
			(sheetname "")
		)
		(fill yes
			(thermal_gap 0.5)
			(thermal_bridge_width 0.5)
			(island_removal_mode 0)
		)
		(polygon
			(pts
				(arc
					(start 299.330872 -244.916706)
					(mid 298.678092 -244.916706)
					(end 299.330872 -244.916706)
				)
			)
		)
	)
	(zone
		(layers "B.Cu" "In4.Cu" "In6.Cu" "In11.Cu" "In13.Cu" "In15.Cu")
		(hatch none 0.5)
		(connect_pads
			(clearance 0)
		)
		(min_thickness 0.25)
		(keepout
			(tracks not_allowed)
			(vias allowed)
			(pads allowed)
			(copperpour not_allowed)
			(footprints allowed)
		)
		(placement
			(enabled no)
			(sheetname "")
		)
		(fill yes
			(thermal_gap 0.5)
			(thermal_bridge_width 0.5)
			(island_removal_mode 0)
		)
		(polygon
			(pts
				(arc
					(start 379.2474 -407.00452)
					(mid 378.54382 -407.00452)
					(end 379.2474 -407.00452)
				)
			)
		)
	)
	(zone
		(layers "B.Cu" "In4.Cu" "In6.Cu" "In11.Cu" "In13.Cu" "In15.Cu")
		(hatch none 0.5)
		(connect_pads
			(clearance 0)
		)
		(min_thickness 0.25)
		(keepout
			(tracks not_allowed)
			(vias allowed)
			(pads allowed)
			(copperpour not_allowed)
			(footprints allowed)
		)
		(placement
			(enabled no)
			(sheetname "")
		)
		(fill yes
			(thermal_gap 0.5)
			(thermal_bridge_width 0.5)
			(island_removal_mode 0)
		)
		(polygon
			(pts
				(arc
					(start 421.062404 -316.316614)
					(mid 420.409624 -316.316614)
					(end 421.062404 -316.316614)
				)
			)
		)
	)
	(zone
		(layers "B.Cu" "In4.Cu" "In6.Cu" "In11.Cu" "In13.Cu" "In15.Cu")
		(hatch none 0.5)
		(connect_pads
			(clearance 0)
		)
		(min_thickness 0.25)
		(keepout
			(tracks not_allowed)
			(vias allowed)
			(pads allowed)
			(copperpour not_allowed)
			(footprints allowed)
		)
		(placement
			(enabled no)
			(sheetname "")
		)
		(fill yes
			(thermal_gap 0.5)
			(thermal_bridge_width 0.5)
			(island_removal_mode 0)
		)
		(polygon
			(pts
				(arc
					(start 184.766204 -244.916706)
					(mid 184.113424 -244.916706)
					(end 184.766204 -244.916706)
				)
			)
		)
	)
	(zone
		(layers "B.Cu" "In4.Cu" "In6.Cu" "In11.Cu" "In13.Cu" "In15.Cu")
		(hatch none 0.5)
		(connect_pads
			(clearance 0)
		)
		(min_thickness 0.25)
		(keepout
			(tracks not_allowed)
			(vias allowed)
			(pads allowed)
			(copperpour not_allowed)
			(footprints allowed)
		)
		(placement
			(enabled no)
			(sheetname "")
		)
		(fill yes
			(thermal_gap 0.5)
			(thermal_bridge_width 0.5)
			(island_removal_mode 0)
		)
		(polygon
			(pts
				(arc
					(start 90.461084 -273.453098)
					(mid 89.808304 -273.453098)
					(end 90.461084 -273.453098)
				)
			)
		)
	)
	(zone
		(layers "B.Cu" "In4.Cu" "In6.Cu" "In11.Cu" "In13.Cu" "In15.Cu")
		(hatch none 0.5)
		(connect_pads
			(clearance 0)
		)
		(min_thickness 0.25)
		(keepout
			(tracks not_allowed)
			(vias allowed)
			(pads allowed)
			(copperpour not_allowed)
			(footprints allowed)
		)
		(placement
			(enabled no)
			(sheetname "")
		)
		(fill yes
			(thermal_gap 0.5)
			(thermal_bridge_width 0.5)
			(island_removal_mode 0)
		)
		(polygon
			(pts
				(arc
					(start 150.285704 -407.00452)
					(mid 149.582124 -407.00452)
					(end 150.285704 -407.00452)
				)
			)
		)
	)
	(zone
		(layers "B.Cu" "In4.Cu" "In6.Cu" "In11.Cu" "In13.Cu" "In15.Cu")
		(hatch none 0.5)
		(connect_pads
			(clearance 0)
		)
		(min_thickness 0.25)
		(keepout
			(tracks not_allowed)
			(vias allowed)
			(pads allowed)
			(copperpour not_allowed)
			(footprints allowed)
		)
		(placement
			(enabled no)
			(sheetname "")
		)
		(fill yes
			(thermal_gap 0.5)
			(thermal_bridge_width 0.5)
			(island_removal_mode 0)
		)
		(polygon
			(pts
				(arc
					(start 177.222404 -278.066754)
					(mid 176.569624 -278.066754)
					(end 177.222404 -278.066754)
				)
			)
		)
	)
	(zone
		(layers "B.Cu" "In4.Cu" "In6.Cu" "In11.Cu" "In13.Cu" "In15.Cu")
		(hatch none 0.5)
		(connect_pads
			(clearance 0)
		)
		(min_thickness 0.25)
		(keepout
			(tracks not_allowed)
			(vias allowed)
			(pads allowed)
			(copperpour not_allowed)
			(footprints allowed)
		)
		(placement
			(enabled no)
			(sheetname "")
		)
		(fill yes
			(thermal_gap 0.5)
			(thermal_bridge_width 0.5)
			(island_removal_mode 0)
		)
		(polygon
			(pts
				(arc
					(start 310.318404 -226.216718)
					(mid 309.665624 -226.216718)
					(end 310.318404 -226.216718)
				)
			)
		)
	)
	(zone
		(layers "B.Cu" "In4.Cu" "In6.Cu" "In11.Cu" "In13.Cu" "In15.Cu")
		(hatch none 0.5)
		(connect_pads
			(clearance 0)
		)
		(min_thickness 0.25)
		(keepout
			(tracks not_allowed)
			(vias allowed)
			(pads allowed)
			(copperpour not_allowed)
			(footprints allowed)
		)
		(placement
			(enabled no)
			(sheetname "")
		)
		(fill yes
			(thermal_gap 0.5)
			(thermal_bridge_width 0.5)
			(island_removal_mode 0)
		)
		(polygon
			(pts
				(arc
					(start 158.009336 -299.316648)
					(mid 157.356556 -299.316648)
					(end 158.009336 -299.316648)
				)
			)
		)
	)
	(zone
		(layers "B.Cu" "In4.Cu" "In6.Cu" "In11.Cu" "In13.Cu" "In15.Cu")
		(hatch none 0.5)
		(connect_pads
			(clearance 0)
		)
		(min_thickness 0.25)
		(keepout
			(tracks not_allowed)
			(vias allowed)
			(pads allowed)
			(copperpour not_allowed)
			(footprints allowed)
		)
		(placement
			(enabled no)
			(sheetname "")
		)
		(fill yes
			(thermal_gap 0.5)
			(thermal_bridge_width 0.5)
			(island_removal_mode 0)
		)
		(polygon
			(pts
				(arc
					(start 89.411556 -243.922804)
					(mid 88.758776 -243.922804)
					(end 89.411556 -243.922804)
				)
			)
		)
	)
	(zone
		(layers "B.Cu" "In4.Cu" "In6.Cu" "In11.Cu" "In13.Cu" "In15.Cu")
		(hatch none 0.5)
		(connect_pads
			(clearance 0)
		)
		(min_thickness 0.25)
		(keepout
			(tracks not_allowed)
			(vias allowed)
			(pads allowed)
			(copperpour not_allowed)
			(footprints allowed)
		)
		(placement
			(enabled no)
			(sheetname "")
		)
		(fill yes
			(thermal_gap 0.5)
			(thermal_bridge_width 0.5)
			(island_removal_mode 0)
		)
		(polygon
			(pts
				(arc
					(start 381.632206 -278.336502)
					(mid 380.979426 -278.336502)
					(end 381.632206 -278.336502)
				)
			)
		)
	)
	(zone
		(layers "B.Cu" "In4.Cu" "In6.Cu" "In11.Cu" "In13.Cu" "In15.Cu")
		(hatch none 0.5)
		(connect_pads
			(clearance 0)
		)
		(min_thickness 0.25)
		(keepout
			(tracks not_allowed)
			(vias allowed)
			(pads allowed)
			(copperpour not_allowed)
			(footprints allowed)
		)
		(placement
			(enabled no)
			(sheetname "")
		)
		(fill yes
			(thermal_gap 0.5)
			(thermal_bridge_width 0.5)
			(island_removal_mode 0)
		)
		(polygon
			(pts
				(arc
					(start 90.821002 -236.597952)
					(mid 90.168222 -236.597952)
					(end 90.821002 -236.597952)
				)
			)
		)
	)
	(zone
		(layers "B.Cu" "In4.Cu" "In6.Cu" "In11.Cu" "In13.Cu" "In15.Cu")
		(hatch none 0.5)
		(connect_pads
			(clearance 0)
		)
		(min_thickness 0.25)
		(keepout
			(tracks not_allowed)
			(vias allowed)
			(pads allowed)
			(copperpour not_allowed)
			(footprints allowed)
		)
		(placement
			(enabled no)
			(sheetname "")
		)
		(fill yes
			(thermal_gap 0.5)
			(thermal_bridge_width 0.5)
			(island_removal_mode 0)
		)
		(polygon
			(pts
				(arc
					(start 56.667908 -407.00452)
					(mid 55.964328 -407.00452)
					(end 56.667908 -407.00452)
				)
			)
		)
	)
	(zone
		(layers "B.Cu" "In4.Cu" "In6.Cu" "In11.Cu" "In13.Cu" "In15.Cu")
		(hatch none 0.5)
		(connect_pads
			(clearance 0)
		)
		(min_thickness 0.25)
		(keepout
			(tracks not_allowed)
			(vias allowed)
			(pads allowed)
			(copperpour not_allowed)
			(footprints allowed)
		)
		(placement
			(enabled no)
			(sheetname "")
		)
		(fill yes
			(thermal_gap 0.5)
			(thermal_bridge_width 0.5)
			(island_removal_mode 0)
		)
		(polygon
			(pts
				(arc
					(start 135.461756 -243.922804)
					(mid 134.808976 -243.922804)
					(end 135.461756 -243.922804)
				)
			)
		)
	)
	(zone
		(layers "B.Cu" "In4.Cu" "In6.Cu" "In11.Cu" "In13.Cu" "In15.Cu")
		(hatch none 0.5)
		(connect_pads
			(clearance 0)
		)
		(min_thickness 0.25)
		(keepout
			(tracks not_allowed)
			(vias allowed)
			(pads allowed)
			(copperpour not_allowed)
			(footprints allowed)
		)
		(placement
			(enabled no)
			(sheetname "")
		)
		(fill yes
			(thermal_gap 0.5)
			(thermal_bridge_width 0.5)
			(island_removal_mode 0)
		)
		(polygon
			(pts
				(arc
					(start 383.401824 -239.0394)
					(mid 382.749044 -239.0394)
					(end 383.401824 -239.0394)
				)
			)
		)
	)
	(zone
		(layers "B.Cu" "In4.Cu" "In6.Cu" "In11.Cu" "In13.Cu" "In15.Cu")
		(hatch none 0.5)
		(connect_pads
			(clearance 0)
		)
		(min_thickness 0.25)
		(keepout
			(tracks not_allowed)
			(vias allowed)
			(pads allowed)
			(copperpour not_allowed)
			(footprints allowed)
		)
		(placement
			(enabled no)
			(sheetname "")
		)
		(fill yes
			(thermal_gap 0.5)
			(thermal_bridge_width 0.5)
			(island_removal_mode 0)
		)
		(polygon
			(pts
				(arc
					(start 134.052056 -234.970066)
					(mid 133.399276 -234.970066)
					(end 134.052056 -234.970066)
				)
			)
		)
	)
	(zone
		(layers "B.Cu" "In4.Cu" "In6.Cu" "In11.Cu" "In13.Cu" "In15.Cu")
		(hatch none 0.5)
		(connect_pads
			(clearance 0)
		)
		(min_thickness 0.25)
		(keepout
			(tracks not_allowed)
			(vias allowed)
			(pads allowed)
			(copperpour not_allowed)
			(footprints allowed)
		)
		(placement
			(enabled no)
			(sheetname "")
		)
		(fill yes
			(thermal_gap 0.5)
			(thermal_bridge_width 0.5)
			(island_removal_mode 0)
		)
		(polygon
			(pts
				(arc
					(start 295.230804 -277.216616)
					(mid 294.578024 -277.216616)
					(end 295.230804 -277.216616)
				)
			)
		)
	)
	(zone
		(layers "B.Cu" "In4.Cu" "In6.Cu" "In11.Cu" "In13.Cu" "In15.Cu")
		(hatch none 0.5)
		(connect_pads
			(clearance 0)
		)
		(min_thickness 0.25)
		(keepout
			(tracks not_allowed)
			(vias allowed)
			(pads allowed)
			(copperpour not_allowed)
			(footprints allowed)
		)
		(placement
			(enabled no)
			(sheetname "")
		)
		(fill yes
			(thermal_gap 0.5)
			(thermal_bridge_width 0.5)
			(island_removal_mode 0)
		)
		(polygon
			(pts
				(arc
					(start 89.411556 -230.900478)
					(mid 88.758776 -230.900478)
					(end 89.411556 -230.900478)
				)
			)
		)
	)
	(zone
		(layers "B.Cu" "In4.Cu" "In6.Cu" "In11.Cu" "In13.Cu" "In15.Cu")
		(hatch none 0.5)
		(connect_pads
			(clearance 0)
		)
		(min_thickness 0.25)
		(keepout
			(tracks not_allowed)
			(vias allowed)
			(pads allowed)
			(copperpour not_allowed)
			(footprints allowed)
		)
		(placement
			(enabled no)
			(sheetname "")
		)
		(fill yes
			(thermal_gap 0.5)
			(thermal_bridge_width 0.5)
			(island_removal_mode 0)
		)
		(polygon
			(pts
				(arc
					(start 51.390804 -238.966756)
					(mid 50.738024 -238.966756)
					(end 51.390804 -238.966756)
				)
			)
		)
	)
	(zone
		(layers "B.Cu" "In4.Cu" "In6.Cu" "In11.Cu" "In13.Cu" "In15.Cu")
		(hatch none 0.5)
		(connect_pads
			(clearance 0)
		)
		(min_thickness 0.25)
		(keepout
			(tracks not_allowed)
			(vias allowed)
			(pads allowed)
			(copperpour not_allowed)
			(footprints allowed)
		)
		(placement
			(enabled no)
			(sheetname "")
		)
		(fill yes
			(thermal_gap 0.5)
			(thermal_bridge_width 0.5)
			(island_removal_mode 0)
		)
		(polygon
			(pts
				(arc
					(start 47.290736 -312.91657)
					(mid 46.637956 -312.91657)
					(end 47.290736 -312.91657)
				)
			)
		)
	)
	(zone
		(layers "B.Cu" "In4.Cu" "In6.Cu" "In11.Cu" "In13.Cu" "In15.Cu")
		(hatch none 0.5)
		(connect_pads
			(clearance 0)
		)
		(min_thickness 0.25)
		(keepout
			(tracks not_allowed)
			(vias allowed)
			(pads allowed)
			(copperpour not_allowed)
			(footprints allowed)
		)
		(placement
			(enabled no)
			(sheetname "")
		)
		(fill yes
			(thermal_gap 0.5)
			(thermal_bridge_width 0.5)
			(island_removal_mode 0)
		)
		(polygon
			(pts
				(arc
					(start 143.295624 -407.00452)
					(mid 142.592044 -407.00452)
					(end 143.295624 -407.00452)
				)
			)
		)
	)
	(zone
		(layers "B.Cu" "In4.Cu" "In6.Cu" "In11.Cu" "In13.Cu" "In15.Cu")
		(hatch none 0.5)
		(connect_pads
			(clearance 0)
		)
		(min_thickness 0.25)
		(keepout
			(tracks not_allowed)
			(vias allowed)
			(pads allowed)
			(copperpour not_allowed)
			(footprints allowed)
		)
		(placement
			(enabled no)
			(sheetname "")
		)
		(fill yes
			(thermal_gap 0.5)
			(thermal_bridge_width 0.5)
			(island_removal_mode 0)
		)
		(polygon
			(pts
				(arc
					(start 356.20198 -61.195966)
					(mid 355.4984 -61.195966)
					(end 356.20198 -61.195966)
				)
			)
		)
	)
	(zone
		(layers "B.Cu" "In4.Cu" "In6.Cu" "In11.Cu" "In13.Cu" "In15.Cu")
		(hatch none 0.5)
		(connect_pads
			(clearance 0)
		)
		(min_thickness 0.25)
		(keepout
			(tracks not_allowed)
			(vias allowed)
			(pads allowed)
			(copperpour not_allowed)
			(footprints allowed)
		)
		(placement
			(enabled no)
			(sheetname "")
		)
		(fill yes
			(thermal_gap 0.5)
			(thermal_bridge_width 0.5)
			(island_removal_mode 0)
		)
		(polygon
			(pts
				(arc
					(start 47.290736 -297.616626)
					(mid 46.637956 -297.616626)
					(end 47.290736 -297.616626)
				)
			)
		)
	)
	(zone
		(layers "B.Cu" "In4.Cu" "In6.Cu" "In11.Cu" "In13.Cu" "In15.Cu")
		(hatch none 0.5)
		(connect_pads
			(clearance 0)
		)
		(min_thickness 0.25)
		(keepout
			(tracks not_allowed)
			(vias allowed)
			(pads allowed)
			(copperpour not_allowed)
			(footprints allowed)
		)
		(placement
			(enabled no)
			(sheetname "")
		)
		(fill yes
			(thermal_gap 0.5)
			(thermal_bridge_width 0.5)
			(island_removal_mode 0)
		)
		(polygon
			(pts
				(arc
					(start 383.981452 -257.98907)
					(mid 383.328672 -257.98907)
					(end 383.981452 -257.98907)
				)
			)
		)
	)
	(zone
		(layers "B.Cu" "In4.Cu" "In6.Cu" "In11.Cu" "In13.Cu" "In15.Cu")
		(hatch none 0.5)
		(connect_pads
			(clearance 0)
		)
		(min_thickness 0.25)
		(keepout
			(tracks not_allowed)
			(vias allowed)
			(pads allowed)
			(copperpour not_allowed)
			(footprints allowed)
		)
		(placement
			(enabled no)
			(sheetname "")
		)
		(fill yes
			(thermal_gap 0.5)
			(thermal_bridge_width 0.5)
			(island_removal_mode 0)
		)
		(polygon
			(pts
				(arc
					(start 134.161784 -259.616956)
					(mid 133.509004 -259.616956)
					(end 134.161784 -259.616956)
				)
			)
		)
	)
	(zone
		(layers "B.Cu" "In4.Cu" "In6.Cu" "In11.Cu" "In13.Cu" "In15.Cu")
		(hatch none 0.5)
		(connect_pads
			(clearance 0)
		)
		(min_thickness 0.25)
		(keepout
			(tracks not_allowed)
			(vias allowed)
			(pads allowed)
			(copperpour not_allowed)
			(footprints allowed)
		)
		(placement
			(enabled no)
			(sheetname "")
		)
		(fill yes
			(thermal_gap 0.5)
			(thermal_bridge_width 0.5)
			(island_removal_mode 0)
		)
		(polygon
			(pts
				(arc
					(start 90.461084 -263.686544)
					(mid 89.808304 -263.686544)
					(end 90.461084 -263.686544)
				)
			)
		)
	)
	(zone
		(layers "B.Cu" "In4.Cu" "In6.Cu" "In11.Cu" "In13.Cu" "In15.Cu")
		(hatch none 0.5)
		(connect_pads
			(clearance 0)
		)
		(min_thickness 0.25)
		(keepout
			(tracks not_allowed)
			(vias allowed)
			(pads allowed)
			(copperpour not_allowed)
			(footprints allowed)
		)
		(placement
			(enabled no)
			(sheetname "")
		)
		(fill yes
			(thermal_gap 0.5)
			(thermal_bridge_width 0.5)
			(island_removal_mode 0)
		)
		(polygon
			(pts
				(arc
					(start 351.144078 -400.858228)
					(mid 350.440498 -400.858228)
					(end 351.144078 -400.858228)
				)
			)
		)
	)
	(zone
		(layers "B.Cu" "In4.Cu" "In6.Cu" "In11.Cu" "In13.Cu" "In15.Cu")
		(hatch none 0.5)
		(connect_pads
			(clearance 0)
		)
		(min_thickness 0.25)
		(keepout
			(tracks not_allowed)
			(vias allowed)
			(pads allowed)
			(copperpour not_allowed)
			(footprints allowed)
		)
		(placement
			(enabled no)
			(sheetname "")
		)
		(fill yes
			(thermal_gap 0.5)
			(thermal_bridge_width 0.5)
			(island_removal_mode 0)
		)
		(polygon
			(pts
				(arc
					(start 421.062404 -314.616592)
					(mid 420.409624 -314.616592)
					(end 421.062404 -314.616592)
				)
			)
		)
	)
	(zone
		(layers "B.Cu" "In4.Cu" "In6.Cu" "In11.Cu" "In13.Cu" "In15.Cu")
		(hatch none 0.5)
		(connect_pads
			(clearance 0)
		)
		(min_thickness 0.25)
		(keepout
			(tracks not_allowed)
			(vias allowed)
			(pads allowed)
			(copperpour not_allowed)
			(footprints allowed)
		)
		(placement
			(enabled no)
			(sheetname "")
		)
		(fill yes
			(thermal_gap 0.5)
			(thermal_bridge_width 0.5)
			(island_removal_mode 0)
		)
		(polygon
			(pts
				(arc
					(start 125.703584 -285.661354)
					(mid 125.050804 -285.661354)
					(end 125.703584 -285.661354)
				)
			)
		)
	)
	(zone
		(layers "B.Cu" "In4.Cu" "In6.Cu" "In11.Cu" "In13.Cu" "In15.Cu")
		(hatch none 0.5)
		(connect_pads
			(clearance 0)
		)
		(min_thickness 0.25)
		(keepout
			(tracks not_allowed)
			(vias allowed)
			(pads allowed)
			(copperpour not_allowed)
			(footprints allowed)
		)
		(placement
			(enabled no)
			(sheetname "")
		)
		(fill yes
			(thermal_gap 0.5)
			(thermal_bridge_width 0.5)
			(island_removal_mode 0)
		)
		(polygon
			(pts
				(arc
					(start 47.290736 -259.366766)
					(mid 46.637956 -259.366766)
					(end 47.290736 -259.366766)
				)
			)
		)
	)
	(zone
		(layers "B.Cu" "In4.Cu" "In6.Cu" "In11.Cu" "In13.Cu" "In15.Cu")
		(hatch none 0.5)
		(connect_pads
			(clearance 0)
		)
		(min_thickness 0.25)
		(keepout
			(tracks not_allowed)
			(vias allowed)
			(pads allowed)
			(copperpour not_allowed)
			(footprints allowed)
		)
		(placement
			(enabled no)
			(sheetname "")
		)
		(fill yes
			(thermal_gap 0.5)
			(thermal_bridge_width 0.5)
			(island_removal_mode 0)
		)
		(polygon
			(pts
				(arc
					(start 334.964278 -400.858228)
					(mid 334.260698 -400.858228)
					(end 334.964278 -400.858228)
				)
			)
		)
	)
	(zone
		(layers "B.Cu" "In4.Cu" "In6.Cu" "In11.Cu" "In13.Cu" "In15.Cu")
		(hatch none 0.5)
		(connect_pads
			(clearance 0)
		)
		(min_thickness 0.25)
		(keepout
			(tracks not_allowed)
			(vias allowed)
			(pads allowed)
			(copperpour not_allowed)
			(footprints allowed)
		)
		(placement
			(enabled no)
			(sheetname "")
		)
		(fill yes
			(thermal_gap 0.5)
			(thermal_bridge_width 0.5)
			(island_removal_mode 0)
		)
		(polygon
			(pts
				(arc
					(start 371.294406 -284.847538)
					(mid 370.641626 -284.847538)
					(end 371.294406 -284.847538)
				)
			)
		)
	)
	(zone
		(layers "B.Cu" "In4.Cu" "In6.Cu" "In11.Cu" "In13.Cu" "In15.Cu")
		(hatch none 0.5)
		(connect_pads
			(clearance 0)
		)
		(min_thickness 0.25)
		(keepout
			(tracks not_allowed)
			(vias allowed)
			(pads allowed)
			(copperpour not_allowed)
			(footprints allowed)
		)
		(placement
			(enabled no)
			(sheetname "")
		)
		(fill yes
			(thermal_gap 0.5)
			(thermal_bridge_width 0.5)
			(island_removal_mode 0)
		)
		(polygon
			(pts
				(arc
					(start 328.085704 0.815594)
					(mid 327.382124 0.815594)
					(end 328.085704 0.815594)
				)
			)
		)
	)
	(zone
		(layers "B.Cu" "In4.Cu" "In6.Cu" "In11.Cu" "In13.Cu" "In15.Cu")
		(hatch none 0.5)
		(connect_pads
			(clearance 0)
		)
		(min_thickness 0.25)
		(keepout
			(tracks not_allowed)
			(vias allowed)
			(pads allowed)
			(copperpour not_allowed)
			(footprints allowed)
		)
		(placement
			(enabled no)
			(sheetname "")
		)
		(fill yes
			(thermal_gap 0.5)
			(thermal_bridge_width 0.5)
			(island_removal_mode 0)
		)
		(polygon
			(pts
				(arc
					(start 425.162472 -259.366766)
					(mid 424.509692 -259.366766)
					(end 425.162472 -259.366766)
				)
			)
		)
	)
	(zone
		(layers "B.Cu" "In4.Cu" "In6.Cu" "In11.Cu" "In13.Cu" "In15.Cu")
		(hatch none 0.5)
		(connect_pads
			(clearance 0)
		)
		(min_thickness 0.25)
		(keepout
			(tracks not_allowed)
			(vias allowed)
			(pads allowed)
			(copperpour not_allowed)
			(footprints allowed)
		)
		(placement
			(enabled no)
			(sheetname "")
		)
		(fill yes
			(thermal_gap 0.5)
			(thermal_bridge_width 0.5)
			(island_removal_mode 0)
		)
		(polygon
			(pts
				(arc
					(start 177.222404 -210.916774)
					(mid 176.569624 -210.916774)
					(end 177.222404 -210.916774)
				)
			)
		)
	)
	(zone
		(layers "B.Cu" "In4.Cu" "In6.Cu" "In11.Cu" "In13.Cu" "In15.Cu")
		(hatch none 0.5)
		(connect_pads
			(clearance 0)
		)
		(min_thickness 0.25)
		(keepout
			(tracks not_allowed)
			(vias allowed)
			(pads allowed)
			(copperpour not_allowed)
			(footprints allowed)
		)
		(placement
			(enabled no)
			(sheetname "")
		)
		(fill yes
			(thermal_gap 0.5)
			(thermal_bridge_width 0.5)
			(island_removal_mode 0)
		)
		(polygon
			(pts
				(arc
					(start 384.341624 -222.761556)
					(mid 383.688844 -222.761556)
					(end 384.341624 -222.761556)
				)
			)
		)
	)
	(zone
		(layers "B.Cu" "In4.Cu" "In6.Cu" "In11.Cu" "In13.Cu" "In15.Cu")
		(hatch none 0.5)
		(connect_pads
			(clearance 0)
		)
		(min_thickness 0.25)
		(keepout
			(tracks not_allowed)
			(vias allowed)
			(pads allowed)
			(copperpour not_allowed)
			(footprints allowed)
		)
		(placement
			(enabled no)
			(sheetname "")
		)
		(fill yes
			(thermal_gap 0.5)
			(thermal_bridge_width 0.5)
			(island_removal_mode 0)
		)
		(polygon
			(pts
				(arc
					(start 162.109404 -304.416714)
					(mid 161.456624 -304.416714)
					(end 162.109404 -304.416714)
				)
			)
		)
	)
	(zone
		(layers "B.Cu" "In4.Cu" "In6.Cu" "In11.Cu" "In13.Cu" "In15.Cu")
		(hatch none 0.5)
		(connect_pads
			(clearance 0)
		)
		(min_thickness 0.25)
		(keepout
			(tracks not_allowed)
			(vias allowed)
			(pads allowed)
			(copperpour not_allowed)
			(footprints allowed)
		)
		(placement
			(enabled no)
			(sheetname "")
		)
		(fill yes
			(thermal_gap 0.5)
			(thermal_bridge_width 0.5)
			(island_removal_mode 0)
		)
		(polygon
			(pts
				(arc
					(start 337.351624 -229.272846)
					(mid 336.698844 -229.272846)
					(end 337.351624 -229.272846)
				)
			)
		)
	)
	(zone
		(layers "B.Cu" "In4.Cu" "In6.Cu" "In11.Cu" "In13.Cu" "In15.Cu")
		(hatch none 0.5)
		(connect_pads
			(clearance 0)
		)
		(min_thickness 0.25)
		(keepout
			(tracks not_allowed)
			(vias allowed)
			(pads allowed)
			(copperpour not_allowed)
			(footprints allowed)
		)
		(placement
			(enabled no)
			(sheetname "")
		)
		(fill yes
			(thermal_gap 0.5)
			(thermal_bridge_width 0.5)
			(island_removal_mode 0)
		)
		(polygon
			(pts
				(arc
					(start 88.471756 -237.411514)
					(mid 87.818976 -237.411514)
					(end 88.471756 -237.411514)
				)
			)
		)
	)
	(zone
		(layers "B.Cu" "In4.Cu" "In6.Cu" "In11.Cu" "In13.Cu" "In15.Cu")
		(hatch none 0.5)
		(connect_pads
			(clearance 0)
		)
		(min_thickness 0.25)
		(keepout
			(tracks not_allowed)
			(vias allowed)
			(pads allowed)
			(copperpour not_allowed)
			(footprints allowed)
		)
		(placement
			(enabled no)
			(sheetname "")
		)
		(fill yes
			(thermal_gap 0.5)
			(thermal_bridge_width 0.5)
			(island_removal_mode 0)
		)
		(polygon
			(pts
				(arc
					(start 382.931924 -236.597952)
					(mid 382.279144 -236.597952)
					(end 382.931924 -236.597952)
				)
			)
		)
	)
	(zone
		(layers "B.Cu" "In4.Cu" "In6.Cu" "In11.Cu" "In13.Cu" "In15.Cu")
		(hatch none 0.5)
		(connect_pads
			(clearance 0)
		)
		(min_thickness 0.25)
		(keepout
			(tracks not_allowed)
			(vias allowed)
			(pads allowed)
			(copperpour not_allowed)
			(footprints allowed)
		)
		(placement
			(enabled no)
			(sheetname "")
		)
		(fill yes
			(thermal_gap 0.5)
			(thermal_bridge_width 0.5)
			(island_removal_mode 0)
		)
		(polygon
			(pts
				(arc
					(start 158.611824 -407.00452)
					(mid 157.908244 -407.00452)
					(end 158.611824 -407.00452)
				)
			)
		)
	)
	(zone
		(layers "B.Cu" "In4.Cu" "In6.Cu" "In11.Cu" "In13.Cu" "In15.Cu")
		(hatch none 0.5)
		(connect_pads
			(clearance 0)
		)
		(min_thickness 0.25)
		(keepout
			(tracks not_allowed)
			(vias allowed)
			(pads allowed)
			(copperpour not_allowed)
			(footprints allowed)
		)
		(placement
			(enabled no)
			(sheetname "")
		)
		(fill yes
			(thermal_gap 0.5)
			(thermal_bridge_width 0.5)
			(island_removal_mode 0)
		)
		(polygon
			(pts
				(arc
					(start 395.981174 -17.601438)
					(mid 395.277594 -17.601438)
					(end 395.981174 -17.601438)
				)
			)
		)
	)
	(zone
		(layers "B.Cu" "In4.Cu" "In6.Cu" "In11.Cu" "In13.Cu" "In15.Cu")
		(hatch none 0.5)
		(connect_pads
			(clearance 0)
		)
		(min_thickness 0.25)
		(keepout
			(tracks not_allowed)
			(vias allowed)
			(pads allowed)
			(copperpour not_allowed)
			(footprints allowed)
		)
		(placement
			(enabled no)
			(sheetname "")
		)
		(fill yes
			(thermal_gap 0.5)
			(thermal_bridge_width 0.5)
			(island_removal_mode 0)
		)
		(polygon
			(pts
				(arc
					(start 375.523252 -285.661354)
					(mid 374.870472 -285.661354)
					(end 375.523252 -285.661354)
				)
			)
		)
	)
	(zone
		(layers "B.Cu" "In4.Cu" "In6.Cu" "In11.Cu" "In13.Cu" "In15.Cu")
		(hatch none 0.5)
		(connect_pads
			(clearance 0)
		)
		(min_thickness 0.25)
		(keepout
			(tracks not_allowed)
			(vias allowed)
			(pads allowed)
			(copperpour not_allowed)
			(footprints allowed)
		)
		(placement
			(enabled no)
			(sheetname "")
		)
		(fill yes
			(thermal_gap 0.5)
			(thermal_bridge_width 0.5)
			(island_removal_mode 0)
		)
		(polygon
			(pts
				(arc
					(start 51.416204 -315.46673)
					(mid 50.763424 -315.46673)
					(end 51.416204 -315.46673)
				)
			)
		)
	)
	(zone
		(layers "B.Cu" "In4.Cu" "In6.Cu" "In11.Cu" "In13.Cu" "In15.Cu")
		(hatch none 0.5)
		(connect_pads
			(clearance 0)
		)
		(min_thickness 0.25)
		(keepout
			(tracks not_allowed)
			(vias allowed)
			(pads allowed)
			(copperpour not_allowed)
			(footprints allowed)
		)
		(placement
			(enabled no)
			(sheetname "")
		)
		(fill yes
			(thermal_gap 0.5)
			(thermal_bridge_width 0.5)
			(island_removal_mode 0)
		)
		(polygon
			(pts
				(arc
					(start 134.161784 -285.661354)
					(mid 133.509004 -285.661354)
					(end 134.161784 -285.661354)
				)
			)
		)
	)
	(zone
		(layers "B.Cu" "In4.Cu" "In6.Cu" "In11.Cu" "In13.Cu" "In15.Cu")
		(hatch none 0.5)
		(connect_pads
			(clearance 0)
		)
		(min_thickness 0.25)
		(keepout
			(tracks not_allowed)
			(vias allowed)
			(pads allowed)
			(copperpour not_allowed)
			(footprints allowed)
		)
		(placement
			(enabled no)
			(sheetname "")
		)
		(fill yes
			(thermal_gap 0.5)
			(thermal_bridge_width 0.5)
			(island_removal_mode 0)
		)
		(polygon
			(pts
				(arc
					(start 338.891118 -400.858228)
					(mid 338.187538 -400.858228)
					(end 338.891118 -400.858228)
				)
			)
		)
	)
	(zone
		(layers "B.Cu" "In4.Cu" "In6.Cu" "In11.Cu" "In13.Cu" "In15.Cu")
		(hatch none 0.5)
		(connect_pads
			(clearance 0)
		)
		(min_thickness 0.25)
		(keepout
			(tracks not_allowed)
			(vias allowed)
			(pads allowed)
			(copperpour not_allowed)
			(footprints allowed)
		)
		(placement
			(enabled no)
			(sheetname "")
		)
		(fill yes
			(thermal_gap 0.5)
			(thermal_bridge_width 0.5)
			(island_removal_mode 0)
		)
		(polygon
			(pts
				(arc
					(start 135.571738 -273.453098)
					(mid 134.918958 -273.453098)
					(end 135.571738 -273.453098)
				)
			)
		)
	)
	(zone
		(layers "B.Cu" "In4.Cu" "In6.Cu" "In11.Cu" "In13.Cu" "In15.Cu")
		(hatch none 0.5)
		(connect_pads
			(clearance 0)
		)
		(min_thickness 0.25)
		(keepout
			(tracks not_allowed)
			(vias allowed)
			(pads allowed)
			(copperpour not_allowed)
			(footprints allowed)
		)
		(placement
			(enabled no)
			(sheetname "")
		)
		(fill yes
			(thermal_gap 0.5)
			(thermal_bridge_width 0.5)
			(island_removal_mode 0)
		)
		(polygon
			(pts
				(arc
					(start 299.356272 -309.51678)
					(mid 298.703492 -309.51678)
					(end 299.356272 -309.51678)
				)
			)
		)
	)
	(zone
		(layers "B.Cu" "In4.Cu" "In6.Cu" "In11.Cu" "In13.Cu" "In15.Cu")
		(hatch none 0.5)
		(connect_pads
			(clearance 0)
		)
		(min_thickness 0.25)
		(keepout
			(tracks not_allowed)
			(vias allowed)
			(pads allowed)
			(copperpour not_allowed)
			(footprints allowed)
		)
		(placement
			(enabled no)
			(sheetname "")
		)
		(fill yes
			(thermal_gap 0.5)
			(thermal_bridge_width 0.5)
			(island_removal_mode 0)
		)
		(polygon
			(pts
				(arc
					(start 338.401152 -271.825212)
					(mid 337.748372 -271.825212)
					(end 338.401152 -271.825212)
				)
			)
		)
	)
	(zone
		(layers "B.Cu" "In4.Cu" "In6.Cu" "In11.Cu" "In13.Cu" "In15.Cu")
		(hatch none 0.5)
		(connect_pads
			(clearance 0)
		)
		(min_thickness 0.25)
		(keepout
			(tracks not_allowed)
			(vias allowed)
			(pads allowed)
			(copperpour not_allowed)
			(footprints allowed)
		)
		(placement
			(enabled no)
			(sheetname "")
		)
		(fill yes
			(thermal_gap 0.5)
			(thermal_bridge_width 0.5)
			(island_removal_mode 0)
		)
		(polygon
			(pts
				(arc
					(start 310.318404 -230.466646)
					(mid 309.665624 -230.466646)
					(end 310.318404 -230.466646)
				)
			)
		)
	)
	(zone
		(layers "B.Cu" "In4.Cu" "In6.Cu" "In11.Cu" "In13.Cu" "In15.Cu")
		(hatch none 0.5)
		(connect_pads
			(clearance 0)
		)
		(min_thickness 0.25)
		(keepout
			(tracks not_allowed)
			(vias allowed)
			(pads allowed)
			(copperpour not_allowed)
			(footprints allowed)
		)
		(placement
			(enabled no)
			(sheetname "")
		)
		(fill yes
			(thermal_gap 0.5)
			(thermal_bridge_width 0.5)
			(island_removal_mode 0)
		)
		(polygon
			(pts
				(arc
					(start 410.049472 -223.666558)
					(mid 409.396692 -223.666558)
					(end 410.049472 -223.666558)
				)
			)
		)
	)
	(zone
		(layers "B.Cu" "In4.Cu" "In6.Cu" "In11.Cu" "In13.Cu" "In15.Cu")
		(hatch none 0.5)
		(connect_pads
			(clearance 0)
		)
		(min_thickness 0.25)
		(keepout
			(tracks not_allowed)
			(vias allowed)
			(pads allowed)
			(copperpour not_allowed)
			(footprints allowed)
		)
		(placement
			(enabled no)
			(sheetname "")
		)
		(fill yes
			(thermal_gap 0.5)
			(thermal_bridge_width 0.5)
			(island_removal_mode 0)
		)
		(polygon
			(pts
				(arc
					(start 134.052056 -246.364506)
					(mid 133.399276 -246.364506)
					(end 134.052056 -246.364506)
				)
			)
		)
	)
	(zone
		(layers "B.Cu" "In4.Cu" "In6.Cu" "In11.Cu" "In13.Cu" "In15.Cu")
		(hatch none 0.5)
		(connect_pads
			(clearance 0)
		)
		(min_thickness 0.25)
		(keepout
			(tracks not_allowed)
			(vias allowed)
			(pads allowed)
			(copperpour not_allowed)
			(footprints allowed)
		)
		(placement
			(enabled no)
			(sheetname "")
		)
		(fill yes
			(thermal_gap 0.5)
			(thermal_bridge_width 0.5)
			(island_removal_mode 0)
		)
		(polygon
			(pts
				(arc
					(start 62.378336 -228.766624)
					(mid 61.725556 -228.766624)
					(end 62.378336 -228.766624)
				)
			)
		)
	)
	(zone
		(layers "B.Cu" "In4.Cu" "In6.Cu" "In11.Cu" "In13.Cu" "In15.Cu")
		(hatch none 0.5)
		(connect_pads
			(clearance 0)
		)
		(min_thickness 0.25)
		(keepout
			(tracks not_allowed)
			(vias allowed)
			(pads allowed)
			(copperpour not_allowed)
			(footprints allowed)
		)
		(placement
			(enabled no)
			(sheetname "")
		)
		(fill yes
			(thermal_gap 0.5)
			(thermal_bridge_width 0.5)
			(island_removal_mode 0)
		)
		(polygon
			(pts
				(arc
					(start 88.941402 -226.831144)
					(mid 88.288622 -226.831144)
					(end 88.941402 -226.831144)
				)
			)
		)
	)
	(zone
		(layers "B.Cu" "In4.Cu" "In6.Cu" "In11.Cu" "In13.Cu" "In15.Cu")
		(hatch none 0.5)
		(connect_pads
			(clearance 0)
		)
		(min_thickness 0.25)
		(keepout
			(tracks not_allowed)
			(vias allowed)
			(pads allowed)
			(copperpour not_allowed)
			(footprints allowed)
		)
		(placement
			(enabled no)
			(sheetname "")
		)
		(fill yes
			(thermal_gap 0.5)
			(thermal_bridge_width 0.5)
			(island_removal_mode 0)
		)
		(polygon
			(pts
				(arc
					(start 375.993406 -286.475424)
					(mid 375.340626 -286.475424)
					(end 375.993406 -286.475424)
				)
			)
		)
	)
	(zone
		(layers "B.Cu" "In4.Cu" "In6.Cu" "In11.Cu" "In13.Cu" "In15.Cu")
		(hatch none 0.5)
		(connect_pads
			(clearance 0)
		)
		(min_thickness 0.25)
		(keepout
			(tracks not_allowed)
			(vias allowed)
			(pads allowed)
			(copperpour not_allowed)
			(footprints allowed)
		)
		(placement
			(enabled no)
			(sheetname "")
		)
		(fill yes
			(thermal_gap 0.5)
			(thermal_bridge_width 0.5)
			(island_removal_mode 0)
		)
		(polygon
			(pts
				(arc
					(start 122.884184 -285.661354)
					(mid 122.231404 -285.661354)
					(end 122.884184 -285.661354)
				)
			)
		)
	)
	(zone
		(layers "B.Cu" "In4.Cu" "In6.Cu" "In11.Cu" "In13.Cu" "In15.Cu")
		(hatch none 0.5)
		(connect_pads
			(clearance 0)
		)
		(min_thickness 0.25)
		(keepout
			(tracks not_allowed)
			(vias allowed)
			(pads allowed)
			(copperpour not_allowed)
			(footprints allowed)
		)
		(placement
			(enabled no)
			(sheetname "")
		)
		(fill yes
			(thermal_gap 0.5)
			(thermal_bridge_width 0.5)
			(island_removal_mode 0)
		)
		(polygon
			(pts
				(arc
					(start 94.110556 -248.806208)
					(mid 93.457776 -248.806208)
					(end 94.110556 -248.806208)
				)
			)
		)
	)
	(zone
		(layers "B.Cu" "In4.Cu" "In6.Cu" "In11.Cu" "In13.Cu" "In15.Cu")
		(hatch none 0.5)
		(connect_pads
			(clearance 0)
		)
		(min_thickness 0.25)
		(keepout
			(tracks not_allowed)
			(vias allowed)
			(pads allowed)
			(copperpour not_allowed)
			(footprints allowed)
		)
		(placement
			(enabled no)
			(sheetname "")
		)
		(fill yes
			(thermal_gap 0.5)
			(thermal_bridge_width 0.5)
			(island_removal_mode 0)
		)
		(polygon
			(pts
				(arc
					(start 177.222404 -209.216752)
					(mid 176.569624 -209.216752)
					(end 177.222404 -209.216752)
				)
			)
		)
	)
	(zone
		(layers "B.Cu" "In4.Cu" "In6.Cu" "In11.Cu" "In13.Cu" "In15.Cu")
		(hatch none 0.5)
		(connect_pads
			(clearance 0)
		)
		(min_thickness 0.25)
		(keepout
			(tracks not_allowed)
			(vias allowed)
			(pads allowed)
			(copperpour not_allowed)
			(footprints allowed)
		)
		(placement
			(enabled no)
			(sheetname "")
		)
		(fill yes
			(thermal_gap 0.5)
			(thermal_bridge_width 0.5)
			(island_removal_mode 0)
		)
		(polygon
			(pts
				(arc
					(start 68.920868 -407.00452)
					(mid 68.217288 -407.00452)
					(end 68.920868 -407.00452)
				)
			)
		)
	)
	(zone
		(layers "B.Cu" "In4.Cu" "In6.Cu" "In11.Cu" "In13.Cu" "In15.Cu")
		(hatch none 0.5)
		(connect_pads
			(clearance 0)
		)
		(min_thickness 0.25)
		(keepout
			(tracks not_allowed)
			(vias allowed)
			(pads allowed)
			(copperpour not_allowed)
			(footprints allowed)
		)
		(placement
			(enabled no)
			(sheetname "")
		)
		(fill yes
			(thermal_gap 0.5)
			(thermal_bridge_width 0.5)
			(island_removal_mode 0)
		)
		(polygon
			(pts
				(arc
					(start 421.062404 -219.41663)
					(mid 420.409624 -219.41663)
					(end 421.062404 -219.41663)
				)
			)
		)
	)
	(zone
		(layers "B.Cu" "In4.Cu" "In6.Cu" "In11.Cu" "In13.Cu" "In15.Cu")
		(hatch none 0.5)
		(connect_pads
			(clearance 0)
		)
		(min_thickness 0.25)
		(keepout
			(tracks not_allowed)
			(vias allowed)
			(pads allowed)
			(copperpour not_allowed)
			(footprints allowed)
		)
		(placement
			(enabled no)
			(sheetname "")
		)
		(fill yes
			(thermal_gap 0.5)
			(thermal_bridge_width 0.5)
			(island_removal_mode 0)
		)
		(polygon
			(pts
				(arc
					(start 381.631952 -266.941808)
					(mid 380.979172 -266.941808)
					(end 381.631952 -266.941808)
				)
			)
		)
	)
	(zone
		(layers "B.Cu" "In4.Cu" "In6.Cu" "In11.Cu" "In13.Cu" "In15.Cu")
		(hatch none 0.5)
		(connect_pads
			(clearance 0)
		)
		(min_thickness 0.25)
		(keepout
			(tracks not_allowed)
			(vias allowed)
			(pads allowed)
			(copperpour not_allowed)
			(footprints allowed)
		)
		(placement
			(enabled no)
			(sheetname "")
		)
		(fill yes
			(thermal_gap 0.5)
			(thermal_bridge_width 0.5)
			(island_removal_mode 0)
		)
		(polygon
			(pts
				(arc
					(start 299.330872 -214.316564)
					(mid 298.678092 -214.316564)
					(end 299.330872 -214.316564)
				)
			)
		)
	)
	(zone
		(layers "B.Cu" "In4.Cu" "In6.Cu" "In11.Cu" "In13.Cu" "In15.Cu")
		(hatch none 0.5)
		(connect_pads
			(clearance 0)
		)
		(min_thickness 0.25)
		(keepout
			(tracks not_allowed)
			(vias allowed)
			(pads allowed)
			(copperpour not_allowed)
			(footprints allowed)
		)
		(placement
			(enabled no)
			(sheetname "")
		)
		(fill yes
			(thermal_gap 0.5)
			(thermal_bridge_width 0.5)
			(island_removal_mode 0)
		)
		(polygon
			(pts
				(arc
					(start 386.23748 -407.00452)
					(mid 385.5339 -407.00452)
					(end 386.23748 -407.00452)
				)
			)
		)
	)
	(zone
		(layers "B.Cu" "In4.Cu" "In6.Cu" "In11.Cu" "In13.Cu" "In15.Cu")
		(hatch none 0.5)
		(connect_pads
			(clearance 0)
		)
		(min_thickness 0.25)
		(keepout
			(tracks not_allowed)
			(vias allowed)
			(pads allowed)
			(copperpour not_allowed)
			(footprints allowed)
		)
		(placement
			(enabled no)
			(sheetname "")
		)
		(fill yes
			(thermal_gap 0.5)
			(thermal_bridge_width 0.5)
			(island_removal_mode 0)
		)
		(polygon
			(pts
				(arc
					(start 90.930984 -264.50036)
					(mid 90.278204 -264.50036)
					(end 90.930984 -264.50036)
				)
			)
		)
	)
	(zone
		(layers "B.Cu" "In4.Cu" "In6.Cu" "In11.Cu" "In13.Cu" "In15.Cu")
		(hatch none 0.5)
		(connect_pads
			(clearance 0)
		)
		(min_thickness 0.25)
		(keepout
			(tracks not_allowed)
			(vias allowed)
			(pads allowed)
			(copperpour not_allowed)
			(footprints allowed)
		)
		(placement
			(enabled no)
			(sheetname "")
		)
		(fill yes
			(thermal_gap 0.5)
			(thermal_bridge_width 0.5)
			(island_removal_mode 0)
		)
		(polygon
			(pts
				(arc
					(start 296.32783 -163.096448)
					(mid 295.62425 -163.096448)
					(end 296.32783 -163.096448)
				)
			)
		)
	)
	(zone
		(layers "B.Cu" "In4.Cu" "In6.Cu" "In11.Cu" "In13.Cu" "In15.Cu")
		(hatch none 0.5)
		(connect_pads
			(clearance 0)
		)
		(min_thickness 0.25)
		(keepout
			(tracks not_allowed)
			(vias allowed)
			(pads allowed)
			(copperpour not_allowed)
			(footprints allowed)
		)
		(placement
			(enabled no)
			(sheetname "")
		)
		(fill yes
			(thermal_gap 0.5)
			(thermal_bridge_width 0.5)
			(island_removal_mode 0)
		)
		(polygon
			(pts
				(arc
					(start 351.558606 -286.475424)
					(mid 350.905826 -286.475424)
					(end 351.558606 -286.475424)
				)
			)
		)
	)
	(zone
		(layers "B.Cu" "In4.Cu" "In6.Cu" "In11.Cu" "In13.Cu" "In15.Cu")
		(hatch none 0.5)
		(connect_pads
			(clearance 0)
		)
		(min_thickness 0.25)
		(keepout
			(tracks not_allowed)
			(vias allowed)
			(pads allowed)
			(copperpour not_allowed)
			(footprints allowed)
		)
		(placement
			(enabled no)
			(sheetname "")
		)
		(fill yes
			(thermal_gap 0.5)
			(thermal_bridge_width 0.5)
			(island_removal_mode 0)
		)
		(polygon
			(pts
				(arc
					(start 425.162472 -234.716574)
					(mid 424.509692 -234.716574)
					(end 425.162472 -234.716574)
				)
			)
		)
	)
	(zone
		(layers "B.Cu" "In4.Cu" "In6.Cu" "In11.Cu" "In13.Cu" "In15.Cu")
		(hatch none 0.5)
		(connect_pads
			(clearance 0)
		)
		(min_thickness 0.25)
		(keepout
			(tracks not_allowed)
			(vias allowed)
			(pads allowed)
			(copperpour not_allowed)
			(footprints allowed)
		)
		(placement
			(enabled no)
			(sheetname "")
		)
		(fill yes
			(thermal_gap 0.5)
			(thermal_bridge_width 0.5)
			(island_removal_mode 0)
		)
		(polygon
			(pts
				(arc
					(start 376.933206 -284.847538)
					(mid 376.280426 -284.847538)
					(end 376.933206 -284.847538)
				)
			)
		)
	)
	(zone
		(layers "B.Cu" "In4.Cu" "In6.Cu" "In11.Cu" "In13.Cu" "In15.Cu")
		(hatch none 0.5)
		(connect_pads
			(clearance 0)
		)
		(min_thickness 0.25)
		(keepout
			(tracks not_allowed)
			(vias allowed)
			(pads allowed)
			(copperpour not_allowed)
			(footprints allowed)
		)
		(placement
			(enabled no)
			(sheetname "")
		)
		(fill yes
			(thermal_gap 0.5)
			(thermal_bridge_width 0.5)
			(island_removal_mode 0)
		)
		(polygon
			(pts
				(arc
					(start 29.855668 -19.13636)
					(mid 29.152088 -19.13636)
					(end 29.855668 -19.13636)
				)
			)
		)
	)
	(zone
		(layers "B.Cu" "In4.Cu" "In6.Cu" "In11.Cu" "In13.Cu" "In15.Cu")
		(hatch none 0.5)
		(connect_pads
			(clearance 0)
		)
		(min_thickness 0.25)
		(keepout
			(tracks not_allowed)
			(vias allowed)
			(pads allowed)
			(copperpour not_allowed)
			(footprints allowed)
		)
		(placement
			(enabled no)
			(sheetname "")
		)
		(fill yes
			(thermal_gap 0.5)
			(thermal_bridge_width 0.5)
			(island_removal_mode 0)
		)
		(polygon
			(pts
				(arc
					(start 338.401152 -270.19758)
					(mid 337.748372 -270.19758)
					(end 338.401152 -270.19758)
				)
			)
		)
	)
	(zone
		(layers "B.Cu" "In4.Cu" "In6.Cu" "In11.Cu" "In13.Cu" "In15.Cu")
		(hatch none 0.5)
		(connect_pads
			(clearance 0)
		)
		(min_thickness 0.25)
		(keepout
			(tracks not_allowed)
			(vias allowed)
			(pads allowed)
			(copperpour not_allowed)
			(footprints allowed)
		)
		(placement
			(enabled no)
			(sheetname "")
		)
		(fill yes
			(thermal_gap 0.5)
			(thermal_bridge_width 0.5)
			(island_removal_mode 0)
		)
		(polygon
			(pts
				(arc
					(start 173.122336 -297.616626)
					(mid 172.469556 -297.616626)
					(end 173.122336 -297.616626)
				)
			)
		)
	)
	(zone
		(layers "B.Cu" "In4.Cu" "In6.Cu" "In11.Cu" "In13.Cu" "In15.Cu")
		(hatch none 0.5)
		(connect_pads
			(clearance 0)
		)
		(min_thickness 0.25)
		(keepout
			(tracks not_allowed)
			(vias allowed)
			(pads allowed)
			(copperpour not_allowed)
			(footprints allowed)
		)
		(placement
			(enabled no)
			(sheetname "")
		)
		(fill yes
			(thermal_gap 0.5)
			(thermal_bridge_width 0.5)
			(island_removal_mode 0)
		)
		(polygon
			(pts
				(arc
					(start 135.571484 -257.175254)
					(mid 134.918704 -257.175254)
					(end 135.571484 -257.175254)
				)
			)
		)
	)
	(zone
		(layers "B.Cu" "In4.Cu" "In6.Cu" "In11.Cu" "In13.Cu" "In15.Cu")
		(hatch none 0.5)
		(connect_pads
			(clearance 0)
		)
		(min_thickness 0.25)
		(keepout
			(tracks not_allowed)
			(vias allowed)
			(pads allowed)
			(copperpour not_allowed)
			(footprints allowed)
		)
		(placement
			(enabled no)
			(sheetname "")
		)
		(fill yes
			(thermal_gap 0.5)
			(thermal_bridge_width 0.5)
			(island_removal_mode 0)
		)
		(polygon
			(pts
				(arc
					(start 363.666024 -224.389442)
					(mid 363.013244 -224.389442)
					(end 363.666024 -224.389442)
				)
			)
		)
	)
	(zone
		(layers "B.Cu" "In4.Cu" "In6.Cu" "In11.Cu" "In13.Cu" "In15.Cu")
		(hatch none 0.5)
		(connect_pads
			(clearance 0)
		)
		(min_thickness 0.25)
		(keepout
			(tracks not_allowed)
			(vias allowed)
			(pads allowed)
			(copperpour not_allowed)
			(footprints allowed)
		)
		(placement
			(enabled no)
			(sheetname "")
		)
		(fill yes
			(thermal_gap 0.5)
			(thermal_bridge_width 0.5)
			(island_removal_mode 0)
		)
		(polygon
			(pts
				(arc
					(start 80.310228 -407.00452)
					(mid 79.606648 -407.00452)
					(end 80.310228 -407.00452)
				)
			)
		)
	)
	(zone
		(layers "B.Cu" "In4.Cu" "In6.Cu" "In11.Cu" "In13.Cu" "In15.Cu")
		(hatch none 0.5)
		(connect_pads
			(clearance 0)
		)
		(min_thickness 0.25)
		(keepout
			(tracks not_allowed)
			(vias allowed)
			(pads allowed)
			(copperpour not_allowed)
			(footprints allowed)
		)
		(placement
			(enabled no)
			(sheetname "")
		)
		(fill yes
			(thermal_gap 0.5)
			(thermal_bridge_width 0.5)
			(island_removal_mode 0)
		)
		(polygon
			(pts
				(arc
					(start 27.061668 -17.61236)
					(mid 26.358088 -17.61236)
					(end 27.061668 -17.61236)
				)
			)
		)
	)
	(zone
		(layers "B.Cu" "In4.Cu" "In6.Cu" "In11.Cu" "In13.Cu" "In15.Cu")
		(hatch none 0.5)
		(connect_pads
			(clearance 0)
		)
		(min_thickness 0.25)
		(keepout
			(tracks not_allowed)
			(vias allowed)
			(pads allowed)
			(copperpour not_allowed)
			(footprints allowed)
		)
		(placement
			(enabled no)
			(sheetname "")
		)
		(fill yes
			(thermal_gap 0.5)
			(thermal_bridge_width 0.5)
			(island_removal_mode 0)
		)
		(polygon
			(pts
				(arc
					(start 88.471756 -232.528364)
					(mid 87.818976 -232.528364)
					(end 88.471756 -232.528364)
				)
			)
		)
	)
	(zone
		(layers "B.Cu" "In4.Cu" "In6.Cu" "In11.Cu" "In13.Cu" "In15.Cu")
		(hatch none 0.5)
		(connect_pads
			(clearance 0)
		)
		(min_thickness 0.25)
		(keepout
			(tracks not_allowed)
			(vias allowed)
			(pads allowed)
			(copperpour not_allowed)
			(footprints allowed)
		)
		(placement
			(enabled no)
			(sheetname "")
		)
		(fill yes
			(thermal_gap 0.5)
			(thermal_bridge_width 0.5)
			(island_removal_mode 0)
		)
		(polygon
			(pts
				(arc
					(start 381.992124 -243.108988)
					(mid 381.339344 -243.108988)
					(end 381.992124 -243.108988)
				)
			)
		)
	)
	(zone
		(layers "B.Cu" "In4.Cu" "In6.Cu" "In11.Cu" "In13.Cu" "In15.Cu")
		(hatch none 0.5)
		(connect_pads
			(clearance 0)
		)
		(min_thickness 0.25)
		(keepout
			(tracks not_allowed)
			(vias allowed)
			(pads allowed)
			(copperpour not_allowed)
			(footprints allowed)
		)
		(placement
			(enabled no)
			(sheetname "")
		)
		(fill yes
			(thermal_gap 0.5)
			(thermal_bridge_width 0.5)
			(island_removal_mode 0)
		)
		(polygon
			(pts
				(arc
					(start 381.522224 -229.272846)
					(mid 380.869444 -229.272846)
					(end 381.522224 -229.272846)
				)
			)
		)
	)
	(zone
		(layers "B.Cu" "In4.Cu" "In6.Cu" "In11.Cu" "In13.Cu" "In15.Cu")
		(hatch none 0.5)
		(connect_pads
			(clearance 0)
		)
		(min_thickness 0.25)
		(keepout
			(tracks not_allowed)
			(vias allowed)
			(pads allowed)
			(copperpour not_allowed)
			(footprints allowed)
		)
		(placement
			(enabled no)
			(sheetname "")
		)
		(fill yes
			(thermal_gap 0.5)
			(thermal_bridge_width 0.5)
			(island_removal_mode 0)
		)
		(polygon
			(pts
				(arc
					(start 96.490028 -407.00452)
					(mid 95.786448 -407.00452)
					(end 96.490028 -407.00452)
				)
			)
		)
	)
	(zone
		(layers "B.Cu" "In4.Cu" "In6.Cu" "In11.Cu" "In13.Cu" "In15.Cu")
		(hatch none 0.5)
		(connect_pads
			(clearance 0)
		)
		(min_thickness 0.25)
		(keepout
			(tracks not_allowed)
			(vias allowed)
			(pads allowed)
			(copperpour not_allowed)
			(footprints allowed)
		)
		(placement
			(enabled no)
			(sheetname "")
		)
		(fill yes
			(thermal_gap 0.5)
			(thermal_bridge_width 0.5)
			(island_removal_mode 0)
		)
		(polygon
			(pts
				(arc
					(start 173.122336 -205.816708)
					(mid 172.469556 -205.816708)
					(end 173.122336 -205.816708)
				)
			)
		)
	)
	(zone
		(layers "B.Cu" "In4.Cu" "In6.Cu" "In11.Cu" "In13.Cu" "In15.Cu")
		(hatch none 0.5)
		(connect_pads
			(clearance 0)
		)
		(min_thickness 0.25)
		(keepout
			(tracks not_allowed)
			(vias allowed)
			(pads allowed)
			(copperpour not_allowed)
			(footprints allowed)
		)
		(placement
			(enabled no)
			(sheetname "")
		)
		(fill yes
			(thermal_gap 0.5)
			(thermal_bridge_width 0.5)
			(island_removal_mode 0)
		)
		(polygon
			(pts
				(arc
					(start 380.692406 -278.336502)
					(mid 380.039626 -278.336502)
					(end 380.692406 -278.336502)
				)
			)
		)
	)
	(zone
		(layers "B.Cu" "In4.Cu" "In6.Cu" "In11.Cu" "In13.Cu" "In15.Cu")
		(hatch none 0.5)
		(connect_pads
			(clearance 0)
		)
		(min_thickness 0.25)
		(keepout
			(tracks not_allowed)
			(vias allowed)
			(pads allowed)
			(copperpour not_allowed)
			(footprints allowed)
		)
		(placement
			(enabled no)
			(sheetname "")
		)
		(fill yes
			(thermal_gap 0.5)
			(thermal_bridge_width 0.5)
			(island_removal_mode 0)
		)
		(polygon
			(pts
				(arc
					(start 336.991452 -254.733552)
					(mid 336.338672 -254.733552)
					(end 336.991452 -254.733552)
				)
			)
		)
	)
	(zone
		(layers "B.Cu" "In4.Cu" "In6.Cu" "In11.Cu" "In13.Cu" "In15.Cu")
		(hatch none 0.5)
		(connect_pads
			(clearance 0)
		)
		(min_thickness 0.25)
		(keepout
			(tracks not_allowed)
			(vias allowed)
			(pads allowed)
			(copperpour not_allowed)
			(footprints allowed)
		)
		(placement
			(enabled no)
			(sheetname "")
		)
		(fill yes
			(thermal_gap 0.5)
			(thermal_bridge_width 0.5)
			(island_removal_mode 0)
		)
		(polygon
			(pts
				(arc
					(start 89.411556 -232.528364)
					(mid 88.758776 -232.528364)
					(end 89.411556 -232.528364)
				)
			)
		)
	)
	(zone
		(layers "B.Cu" "In4.Cu" "In6.Cu" "In11.Cu" "In13.Cu" "In15.Cu")
		(hatch none 0.5)
		(connect_pads
			(clearance 0)
		)
		(min_thickness 0.25)
		(keepout
			(tracks not_allowed)
			(vias allowed)
			(pads allowed)
			(copperpour not_allowed)
			(footprints allowed)
		)
		(placement
			(enabled no)
			(sheetname "")
		)
		(fill yes
			(thermal_gap 0.5)
			(thermal_bridge_width 0.5)
			(island_removal_mode 0)
		)
		(polygon
			(pts
				(arc
					(start 376.94489 0.815594)
					(mid 376.24131 0.815594)
					(end 376.94489 0.815594)
				)
			)
		)
	)
	(zone
		(layers "B.Cu" "In4.Cu" "In6.Cu" "In11.Cu" "In13.Cu" "In15.Cu")
		(hatch none 0.5)
		(connect_pads
			(clearance 0)
		)
		(min_thickness 0.25)
		(keepout
			(tracks not_allowed)
			(vias allowed)
			(pads allowed)
			(copperpour not_allowed)
			(footprints allowed)
		)
		(placement
			(enabled no)
			(sheetname "")
		)
		(fill yes
			(thermal_gap 0.5)
			(thermal_bridge_width 0.5)
			(island_removal_mode 0)
		)
		(polygon
			(pts
				(arc
					(start 357.55707 -223.575626)
					(mid 356.90429 -223.575626)
					(end 357.55707 -223.575626)
				)
			)
		)
	)
	(zone
		(layers "B.Cu" "In4.Cu" "In6.Cu" "In11.Cu" "In13.Cu" "In15.Cu")
		(hatch none 0.5)
		(connect_pads
			(clearance 0)
		)
		(min_thickness 0.25)
		(keepout
			(tracks not_allowed)
			(vias allowed)
			(pads allowed)
			(copperpour not_allowed)
			(footprints allowed)
		)
		(placement
			(enabled no)
			(sheetname "")
		)
		(fill yes
			(thermal_gap 0.5)
			(thermal_bridge_width 0.5)
			(island_removal_mode 0)
		)
		(polygon
			(pts
				(arc
					(start 381.992124 -233.34218)
					(mid 381.339344 -233.34218)
					(end 381.992124 -233.34218)
				)
			)
		)
	)
	(zone
		(layers "B.Cu" "In4.Cu" "In6.Cu" "In11.Cu" "In13.Cu" "In15.Cu")
		(hatch none 0.5)
		(connect_pads
			(clearance 0)
		)
		(min_thickness 0.25)
		(keepout
			(tracks not_allowed)
			(vias allowed)
			(pads allowed)
			(copperpour not_allowed)
			(footprints allowed)
		)
		(placement
			(enabled no)
			(sheetname "")
		)
		(fill yes
			(thermal_gap 0.5)
			(thermal_bridge_width 0.5)
			(island_removal_mode 0)
		)
		(polygon
			(pts
				(arc
					(start 158.009336 -303.566576)
					(mid 157.356556 -303.566576)
					(end 158.009336 -303.566576)
				)
			)
		)
	)
	(zone
		(layers "B.Cu" "In4.Cu" "In6.Cu" "In11.Cu" "In13.Cu" "In15.Cu")
		(hatch none 0.5)
		(connect_pads
			(clearance 0)
		)
		(min_thickness 0.25)
		(keepout
			(tracks not_allowed)
			(vias allowed)
			(pads allowed)
			(copperpour not_allowed)
			(footprints allowed)
		)
		(placement
			(enabled no)
			(sheetname "")
		)
		(fill yes
			(thermal_gap 0.5)
			(thermal_bridge_width 0.5)
			(island_removal_mode 0)
		)
		(polygon
			(pts
				(arc
					(start 381.162052 -285.661354)
					(mid 380.509272 -285.661354)
					(end 381.162052 -285.661354)
				)
			)
		)
	)
	(zone
		(layers "B.Cu" "In4.Cu" "In6.Cu" "In11.Cu" "In13.Cu" "In15.Cu")
		(hatch none 0.5)
		(connect_pads
			(clearance 0)
		)
		(min_thickness 0.25)
		(keepout
			(tracks not_allowed)
			(vias allowed)
			(pads allowed)
			(copperpour not_allowed)
			(footprints allowed)
		)
		(placement
			(enabled no)
			(sheetname "")
		)
		(fill yes
			(thermal_gap 0.5)
			(thermal_bridge_width 0.5)
			(island_removal_mode 0)
		)
		(polygon
			(pts
				(arc
					(start 51.390804 -221.96679)
					(mid 50.738024 -221.96679)
					(end 51.390804 -221.96679)
				)
			)
		)
	)
	(zone
		(layers "B.Cu" "In4.Cu" "In6.Cu" "In11.Cu" "In13.Cu" "In15.Cu")
		(hatch none 0.5)
		(connect_pads
			(clearance 0)
		)
		(min_thickness 0.25)
		(keepout
			(tracks not_allowed)
			(vias allowed)
			(pads allowed)
			(copperpour not_allowed)
			(footprints allowed)
		)
		(placement
			(enabled no)
			(sheetname "")
		)
		(fill yes
			(thermal_gap 0.5)
			(thermal_bridge_width 0.5)
			(island_removal_mode 0)
		)
		(polygon
			(pts
				(arc
					(start 90.821002 -241.481102)
					(mid 90.168222 -241.481102)
					(end 90.821002 -241.481102)
				)
			)
		)
	)
	(zone
		(layers "B.Cu" "In4.Cu" "In6.Cu" "In11.Cu" "In13.Cu" "In15.Cu")
		(hatch none 0.5)
		(connect_pads
			(clearance 0)
		)
		(min_thickness 0.25)
		(keepout
			(tracks not_allowed)
			(vias allowed)
			(pads allowed)
			(copperpour not_allowed)
			(footprints allowed)
		)
		(placement
			(enabled no)
			(sheetname "")
		)
		(fill yes
			(thermal_gap 0.5)
			(thermal_bridge_width 0.5)
			(island_removal_mode 0)
		)
		(polygon
			(pts
				(arc
					(start 295.230804 -238.116618)
					(mid 294.578024 -238.116618)
					(end 295.230804 -238.116618)
				)
			)
		)
	)
	(zone
		(layers "B.Cu" "In4.Cu" "In6.Cu" "In11.Cu" "In13.Cu" "In15.Cu")
		(hatch none 0.5)
		(connect_pads
			(clearance 0)
		)
		(min_thickness 0.25)
		(keepout
			(tracks not_allowed)
			(vias allowed)
			(pads allowed)
			(copperpour not_allowed)
			(footprints allowed)
		)
		(placement
			(enabled no)
			(sheetname "")
		)
		(fill yes
			(thermal_gap 0.5)
			(thermal_bridge_width 0.5)
			(island_removal_mode 0)
		)
		(polygon
			(pts
				(arc
					(start 382.101852 -277.522432)
					(mid 381.449072 -277.522432)
					(end 382.101852 -277.522432)
				)
			)
		)
	)
	(zone
		(layers "B.Cu" "In4.Cu" "In6.Cu" "In11.Cu" "In13.Cu" "In15.Cu")
		(hatch none 0.5)
		(connect_pads
			(clearance 0)
		)
		(min_thickness 0.25)
		(keepout
			(tracks not_allowed)
			(vias allowed)
			(pads allowed)
			(copperpour not_allowed)
			(footprints allowed)
		)
		(placement
			(enabled no)
			(sheetname "")
		)
		(fill yes
			(thermal_gap 0.5)
			(thermal_bridge_width 0.5)
			(island_removal_mode 0)
		)
		(polygon
			(pts
				(arc
					(start 51.390804 -217.716608)
					(mid 50.738024 -217.716608)
					(end 51.390804 -217.716608)
				)
			)
		)
	)
	(zone
		(layers "B.Cu" "In4.Cu" "In6.Cu" "In11.Cu" "In13.Cu" "In15.Cu")
		(hatch none 0.5)
		(connect_pads
			(clearance 0)
		)
		(min_thickness 0.25)
		(keepout
			(tracks not_allowed)
			(vias allowed)
			(pads allowed)
			(copperpour not_allowed)
			(footprints allowed)
		)
		(placement
			(enabled no)
			(sheetname "")
		)
		(fill yes
			(thermal_gap 0.5)
			(thermal_bridge_width 0.5)
			(island_removal_mode 0)
		)
		(polygon
			(pts
				(arc
					(start 92.700602 -247.992138)
					(mid 92.047822 -247.992138)
					(end 92.700602 -247.992138)
				)
			)
		)
	)
	(zone
		(layers "B.Cu" "In4.Cu" "In6.Cu" "In11.Cu" "In13.Cu" "In15.Cu")
		(hatch none 0.5)
		(connect_pads
			(clearance 0)
		)
		(min_thickness 0.25)
		(keepout
			(tracks not_allowed)
			(vias allowed)
			(pads allowed)
			(copperpour not_allowed)
			(footprints allowed)
		)
		(placement
			(enabled no)
			(sheetname "")
		)
		(fill yes
			(thermal_gap 0.5)
			(thermal_bridge_width 0.5)
			(island_removal_mode 0)
		)
		(polygon
			(pts
				(arc
					(start 129.932938 -255.547622)
					(mid 129.280158 -255.547622)
					(end 129.932938 -255.547622)
				)
			)
		)
	)
	(zone
		(layers "B.Cu" "In4.Cu" "In6.Cu" "In11.Cu" "In13.Cu" "In15.Cu")
		(hatch none 0.5)
		(connect_pads
			(clearance 0)
		)
		(min_thickness 0.25)
		(keepout
			(tracks not_allowed)
			(vias allowed)
			(pads allowed)
			(copperpour not_allowed)
			(footprints allowed)
		)
		(placement
			(enabled no)
			(sheetname "")
		)
		(fill yes
			(thermal_gap 0.5)
			(thermal_bridge_width 0.5)
			(island_removal_mode 0)
		)
		(polygon
			(pts
				(arc
					(start 90.461084 -262.058658)
					(mid 89.808304 -262.058658)
					(end 90.461084 -262.058658)
				)
			)
		)
	)
	(zone
		(layers "B.Cu" "In4.Cu" "In6.Cu" "In11.Cu" "In13.Cu" "In15.Cu")
		(hatch none 0.5)
		(connect_pads
			(clearance 0)
		)
		(min_thickness 0.25)
		(keepout
			(tracks not_allowed)
			(vias allowed)
			(pads allowed)
			(copperpour not_allowed)
			(footprints allowed)
		)
		(placement
			(enabled no)
			(sheetname "")
		)
		(fill yes
			(thermal_gap 0.5)
			(thermal_bridge_width 0.5)
			(island_removal_mode 0)
		)
		(polygon
			(pts
				(arc
					(start 173.122336 -237.266734)
					(mid 172.469556 -237.266734)
					(end 173.122336 -237.266734)
				)
			)
		)
	)
	(zone
		(layers "B.Cu" "In4.Cu" "In6.Cu" "In11.Cu" "In13.Cu" "In15.Cu")
		(hatch none 0.5)
		(connect_pads
			(clearance 0)
		)
		(min_thickness 0.25)
		(keepout
			(tracks not_allowed)
			(vias allowed)
			(pads allowed)
			(copperpour not_allowed)
			(footprints allowed)
		)
		(placement
			(enabled no)
			(sheetname "")
		)
		(fill yes
			(thermal_gap 0.5)
			(thermal_bridge_width 0.5)
			(island_removal_mode 0)
		)
		(polygon
			(pts
				(arc
					(start 89.051384 -266.128246)
					(mid 88.398604 -266.128246)
					(end 89.051384 -266.128246)
				)
			)
		)
	)
	(zone
		(layers "B.Cu" "In4.Cu" "In6.Cu" "In11.Cu" "In13.Cu" "In15.Cu")
		(hatch none 0.5)
		(connect_pads
			(clearance 0)
		)
		(min_thickness 0.25)
		(keepout
			(tracks not_allowed)
			(vias allowed)
			(pads allowed)
			(copperpour not_allowed)
			(footprints allowed)
		)
		(placement
			(enabled no)
			(sheetname "")
		)
		(fill yes
			(thermal_gap 0.5)
			(thermal_bridge_width 0.5)
			(island_removal_mode 0)
		)
		(polygon
			(pts
				(arc
					(start 383.041652 -267.755878)
					(mid 382.388872 -267.755878)
					(end 383.041652 -267.755878)
				)
			)
		)
	)
	(zone
		(layers "B.Cu" "In4.Cu" "In6.Cu" "In11.Cu" "In13.Cu" "In15.Cu")
		(hatch none 0.5)
		(connect_pads
			(clearance 0)
		)
		(min_thickness 0.25)
		(keepout
			(tracks not_allowed)
			(vias allowed)
			(pads allowed)
			(copperpour not_allowed)
			(footprints allowed)
		)
		(placement
			(enabled no)
			(sheetname "")
		)
		(fill yes
			(thermal_gap 0.5)
			(thermal_bridge_width 0.5)
			(island_removal_mode 0)
		)
		(polygon
			(pts
				(arc
					(start 364.13567 -225.203258)
					(mid 363.48289 -225.203258)
					(end 364.13567 -225.203258)
				)
			)
		)
	)
	(zone
		(layers "B.Cu" "In4.Cu" "In6.Cu" "In11.Cu" "In13.Cu" "In15.Cu")
		(hatch none 0.5)
		(connect_pads
			(clearance 0)
		)
		(min_thickness 0.25)
		(keepout
			(tracks not_allowed)
			(vias allowed)
			(pads allowed)
			(copperpour not_allowed)
			(footprints allowed)
		)
		(placement
			(enabled no)
			(sheetname "")
		)
		(fill yes
			(thermal_gap 0.5)
			(thermal_bridge_width 0.5)
			(island_removal_mode 0)
		)
		(polygon
			(pts
				(arc
					(start 305.195478 -400.858228)
					(mid 304.491898 -400.858228)
					(end 305.195478 -400.858228)
				)
			)
		)
	)
	(zone
		(layers "B.Cu" "In4.Cu" "In6.Cu" "In11.Cu" "In13.Cu" "In15.Cu")
		(hatch none 0.5)
		(connect_pads
			(clearance 0)
		)
		(min_thickness 0.25)
		(keepout
			(tracks not_allowed)
			(vias allowed)
			(pads allowed)
			(copperpour not_allowed)
			(footprints allowed)
		)
		(placement
			(enabled no)
			(sheetname "")
		)
		(fill yes
			(thermal_gap 0.5)
			(thermal_bridge_width 0.5)
			(island_removal_mode 0)
		)
		(polygon
			(pts
				(arc
					(start 89.991184 -285.661354)
					(mid 89.338404 -285.661354)
					(end 89.991184 -285.661354)
				)
			)
		)
	)
	(zone
		(layers "B.Cu" "In4.Cu" "In6.Cu" "In11.Cu" "In13.Cu" "In15.Cu")
		(hatch none 0.5)
		(connect_pads
			(clearance 0)
		)
		(min_thickness 0.25)
		(keepout
			(tracks not_allowed)
			(vias allowed)
			(pads allowed)
			(copperpour not_allowed)
			(footprints allowed)
		)
		(placement
			(enabled no)
			(sheetname "")
		)
		(fill yes
			(thermal_gap 0.5)
			(thermal_bridge_width 0.5)
			(island_removal_mode 0)
		)
		(polygon
			(pts
				(arc
					(start 337.461606 -271.825212)
					(mid 336.808826 -271.825212)
					(end 337.461606 -271.825212)
				)
			)
		)
	)
	(zone
		(layers "B.Cu" "In4.Cu" "In6.Cu" "In11.Cu" "In13.Cu" "In15.Cu")
		(hatch none 0.5)
		(connect_pads
			(clearance 0)
		)
		(min_thickness 0.25)
		(keepout
			(tracks not_allowed)
			(vias allowed)
			(pads allowed)
			(copperpour not_allowed)
			(footprints allowed)
		)
		(placement
			(enabled no)
			(sheetname "")
		)
		(fill yes
			(thermal_gap 0.5)
			(thermal_bridge_width 0.5)
			(island_removal_mode 0)
		)
		(polygon
			(pts
				(arc
					(start 299.356272 -259.366766)
					(mid 298.703492 -259.366766)
					(end 299.356272 -259.366766)
				)
			)
		)
	)
	(zone
		(layers "B.Cu" "In4.Cu" "In6.Cu" "In11.Cu" "In13.Cu" "In15.Cu")
		(hatch none 0.5)
		(connect_pads
			(clearance 0)
		)
		(min_thickness 0.25)
		(keepout
			(tracks not_allowed)
			(vias allowed)
			(pads allowed)
			(copperpour not_allowed)
			(footprints allowed)
		)
		(placement
			(enabled no)
			(sheetname "")
		)
		(fill yes
			(thermal_gap 0.5)
			(thermal_bridge_width 0.5)
			(island_removal_mode 0)
		)
		(polygon
			(pts
				(arc
					(start 382.93167 -243.108988)
					(mid 382.27889 -243.108988)
					(end 382.93167 -243.108988)
				)
			)
		)
	)
	(zone
		(layers "B.Cu" "In4.Cu" "In6.Cu" "In11.Cu" "In13.Cu" "In15.Cu")
		(hatch none 0.5)
		(connect_pads
			(clearance 0)
		)
		(min_thickness 0.25)
		(keepout
			(tracks not_allowed)
			(vias allowed)
			(pads allowed)
			(copperpour not_allowed)
			(footprints allowed)
		)
		(placement
			(enabled no)
			(sheetname "")
		)
		(fill yes
			(thermal_gap 0.5)
			(thermal_bridge_width 0.5)
			(island_removal_mode 0)
		)
		(polygon
			(pts
				(arc
					(start 419.06952 -407.00452)
					(mid 418.36594 -407.00452)
					(end 419.06952 -407.00452)
				)
			)
		)
	)
	(zone
		(layers "B.Cu" "In4.Cu" "In6.Cu" "In11.Cu" "In13.Cu" "In15.Cu")
		(hatch none 0.5)
		(connect_pads
			(clearance 0)
		)
		(min_thickness 0.25)
		(keepout
			(tracks not_allowed)
			(vias allowed)
			(pads allowed)
			(copperpour not_allowed)
			(footprints allowed)
		)
		(placement
			(enabled no)
			(sheetname "")
		)
		(fill yes
			(thermal_gap 0.5)
			(thermal_bridge_width 0.5)
			(island_removal_mode 0)
		)
		(polygon
			(pts
				(arc
					(start 135.461756 -245.55069)
					(mid 134.808976 -245.55069)
					(end 135.461756 -245.55069)
				)
			)
		)
	)
	(zone
		(layers "B.Cu" "In4.Cu" "In6.Cu" "In11.Cu" "In13.Cu" "In15.Cu")
		(hatch none 0.5)
		(connect_pads
			(clearance 0)
		)
		(min_thickness 0.25)
		(keepout
			(tracks not_allowed)
			(vias allowed)
			(pads allowed)
			(copperpour not_allowed)
			(footprints allowed)
		)
		(placement
			(enabled no)
			(sheetname "")
		)
		(fill yes
			(thermal_gap 0.5)
			(thermal_bridge_width 0.5)
			(island_removal_mode 0)
		)
		(polygon
			(pts
				(arc
					(start 81.173828 -407.00452)
					(mid 80.470248 -407.00452)
					(end 81.173828 -407.00452)
				)
			)
		)
	)
	(zone
		(layers "B.Cu" "In4.Cu" "In6.Cu" "In11.Cu" "In13.Cu" "In15.Cu")
		(hatch none 0.5)
		(connect_pads
			(clearance 0)
		)
		(min_thickness 0.25)
		(keepout
			(tracks not_allowed)
			(vias allowed)
			(pads allowed)
			(copperpour not_allowed)
			(footprints allowed)
		)
		(placement
			(enabled no)
			(sheetname "")
		)
		(fill yes
			(thermal_gap 0.5)
			(thermal_bridge_width 0.5)
			(island_removal_mode 0)
		)
		(polygon
			(pts
				(arc
					(start 322.711318 -400.858228)
					(mid 322.007738 -400.858228)
					(end 322.711318 -400.858228)
				)
			)
		)
	)
	(zone
		(layers "B.Cu" "In4.Cu" "In6.Cu" "In11.Cu" "In13.Cu" "In15.Cu")
		(hatch none 0.5)
		(connect_pads
			(clearance 0)
		)
		(min_thickness 0.25)
		(keepout
			(tracks not_allowed)
			(vias allowed)
			(pads allowed)
			(copperpour not_allowed)
			(footprints allowed)
		)
		(placement
			(enabled no)
			(sheetname "")
		)
		(fill yes
			(thermal_gap 0.5)
			(thermal_bridge_width 0.5)
			(island_removal_mode 0)
		)
		(polygon
			(pts
				(arc
					(start 381.522224 -243.922804)
					(mid 380.869444 -243.922804)
					(end 381.522224 -243.922804)
				)
			)
		)
	)
	(zone
		(layers "B.Cu" "In4.Cu" "In6.Cu" "In11.Cu" "In13.Cu" "In15.Cu")
		(hatch none 0.5)
		(connect_pads
			(clearance 0)
		)
		(min_thickness 0.25)
		(keepout
			(tracks not_allowed)
			(vias allowed)
			(pads allowed)
			(copperpour not_allowed)
			(footprints allowed)
		)
		(placement
			(enabled no)
			(sheetname "")
		)
		(fill yes
			(thermal_gap 0.5)
			(thermal_bridge_width 0.5)
			(island_removal_mode 0)
		)
		(polygon
			(pts
				(arc
					(start 344.040206 -286.475424)
					(mid 343.387426 -286.475424)
					(end 344.040206 -286.475424)
				)
			)
		)
	)
	(zone
		(layers "B.Cu" "In4.Cu" "In6.Cu" "In11.Cu" "In13.Cu" "In15.Cu")
		(hatch none 0.5)
		(connect_pads
			(clearance 0)
		)
		(min_thickness 0.25)
		(keepout
			(tracks not_allowed)
			(vias allowed)
			(pads allowed)
			(copperpour not_allowed)
			(footprints allowed)
		)
		(placement
			(enabled no)
			(sheetname "")
		)
		(fill yes
			(thermal_gap 0.5)
			(thermal_bridge_width 0.5)
			(island_removal_mode 0)
		)
		(polygon
			(pts
				(arc
					(start 428.606204 -267.866622)
					(mid 427.953424 -267.866622)
					(end 428.606204 -267.866622)
				)
			)
		)
	)
	(zone
		(layers "B.Cu" "In4.Cu" "In6.Cu" "In11.Cu" "In13.Cu" "In15.Cu")
		(hatch none 0.5)
		(connect_pads
			(clearance 0)
		)
		(min_thickness 0.25)
		(keepout
			(tracks not_allowed)
			(vias allowed)
			(pads allowed)
			(copperpour not_allowed)
			(footprints allowed)
		)
		(placement
			(enabled no)
			(sheetname "")
		)
		(fill yes
			(thermal_gap 0.5)
			(thermal_bridge_width 0.5)
			(island_removal_mode 0)
		)
		(polygon
			(pts
				(arc
					(start 399.638774 -19.125438)
					(mid 398.935194 -19.125438)
					(end 399.638774 -19.125438)
				)
			)
		)
	)
	(zone
		(layers "B.Cu" "In4.Cu" "In6.Cu" "In11.Cu" "In13.Cu" "In15.Cu")
		(hatch none 0.5)
		(connect_pads
			(clearance 0)
		)
		(min_thickness 0.25)
		(keepout
			(tracks not_allowed)
			(vias allowed)
			(pads allowed)
			(copperpour not_allowed)
			(footprints allowed)
		)
		(placement
			(enabled no)
			(sheetname "")
		)
		(fill yes
			(thermal_gap 0.5)
			(thermal_bridge_width 0.5)
			(island_removal_mode 0)
		)
		(polygon
			(pts
				(arc
					(start 59.731148 -407.00452)
					(mid 59.027568 -407.00452)
					(end 59.731148 -407.00452)
				)
			)
		)
	)
	(zone
		(layers "B.Cu" "In4.Cu" "In6.Cu" "In11.Cu" "In13.Cu" "In15.Cu")
		(hatch none 0.5)
		(connect_pads
			(clearance 0)
		)
		(min_thickness 0.25)
		(keepout
			(tracks not_allowed)
			(vias allowed)
			(pads allowed)
			(copperpour not_allowed)
			(footprints allowed)
		)
		(placement
			(enabled no)
			(sheetname "")
		)
		(fill yes
			(thermal_gap 0.5)
			(thermal_bridge_width 0.5)
			(island_removal_mode 0)
		)
		(polygon
			(pts
				(arc
					(start 421.062404 -310.366664)
					(mid 420.409624 -310.366664)
					(end 421.062404 -310.366664)
				)
			)
		)
	)
	(zone
		(layers "B.Cu" "In4.Cu" "In6.Cu" "In11.Cu" "In13.Cu" "In15.Cu")
		(hatch none 0.5)
		(connect_pads
			(clearance 0)
		)
		(min_thickness 0.25)
		(keepout
			(tracks not_allowed)
			(vias allowed)
			(pads allowed)
			(copperpour not_allowed)
			(footprints allowed)
		)
		(placement
			(enabled no)
			(sheetname "")
		)
		(fill yes
			(thermal_gap 0.5)
			(thermal_bridge_width 0.5)
			(island_removal_mode 0)
		)
		(polygon
			(pts
				(arc
					(start 33.513268 -17.61236)
					(mid 32.809688 -17.61236)
					(end 33.513268 -17.61236)
				)
			)
		)
	)
	(zone
		(layers "B.Cu" "In4.Cu" "In6.Cu" "In11.Cu" "In13.Cu" "In15.Cu")
		(hatch none 0.5)
		(connect_pads
			(clearance 0)
		)
		(min_thickness 0.25)
		(keepout
			(tracks not_allowed)
			(vias allowed)
			(pads allowed)
			(copperpour not_allowed)
			(footprints allowed)
		)
		(placement
			(enabled no)
			(sheetname "")
		)
		(fill yes
			(thermal_gap 0.5)
			(thermal_bridge_width 0.5)
			(island_removal_mode 0)
		)
		(polygon
			(pts
				(arc
					(start 295.230804 -247.466612)
					(mid 294.578024 -247.466612)
					(end 295.230804 -247.466612)
				)
			)
		)
	)
	(zone
		(layers "B.Cu" "In4.Cu" "In6.Cu" "In11.Cu" "In13.Cu" "In15.Cu")
		(hatch none 0.5)
		(connect_pads
			(clearance 0)
		)
		(min_thickness 0.25)
		(keepout
			(tracks not_allowed)
			(vias allowed)
			(pads allowed)
			(copperpour not_allowed)
			(footprints allowed)
		)
		(placement
			(enabled no)
			(sheetname "")
		)
		(fill yes
			(thermal_gap 0.5)
			(thermal_bridge_width 0.5)
			(island_removal_mode 0)
		)
		(polygon
			(pts
				(arc
					(start 47.290736 -274.66671)
					(mid 46.637956 -274.66671)
					(end 47.290736 -274.66671)
				)
			)
		)
	)
	(zone
		(layers "B.Cu" "In4.Cu" "In6.Cu" "In11.Cu" "In13.Cu" "In15.Cu")
		(hatch none 0.5)
		(connect_pads
			(clearance 0)
		)
		(min_thickness 0.25)
		(keepout
			(tracks not_allowed)
			(vias allowed)
			(pads allowed)
			(copperpour not_allowed)
			(footprints allowed)
		)
		(placement
			(enabled no)
			(sheetname "")
		)
		(fill yes
			(thermal_gap 0.5)
			(thermal_bridge_width 0.5)
			(island_removal_mode 0)
		)
		(polygon
			(pts
				(arc
					(start 338.76107 -241.481102)
					(mid 338.10829 -241.481102)
					(end 338.76107 -241.481102)
				)
			)
		)
	)
	(zone
		(layers "B.Cu" "In4.Cu" "In6.Cu" "In11.Cu" "In13.Cu" "In15.Cu")
		(hatch none 0.5)
		(connect_pads
			(clearance 0)
		)
		(min_thickness 0.25)
		(keepout
			(tracks not_allowed)
			(vias allowed)
			(pads allowed)
			(copperpour not_allowed)
			(footprints allowed)
		)
		(placement
			(enabled no)
			(sheetname "")
		)
		(fill yes
			(thermal_gap 0.5)
			(thermal_bridge_width 0.5)
			(island_removal_mode 0)
		)
		(polygon
			(pts
				(arc
					(start 338.401152 -253.919736)
					(mid 337.748372 -253.919736)
					(end 338.401152 -253.919736)
				)
			)
		)
	)
	(zone
		(layers "B.Cu" "In4.Cu" "In6.Cu" "In11.Cu" "In13.Cu" "In15.Cu")
		(hatch none 0.5)
		(connect_pads
			(clearance 0)
		)
		(min_thickness 0.25)
		(keepout
			(tracks not_allowed)
			(vias allowed)
			(pads allowed)
			(copperpour not_allowed)
			(footprints allowed)
		)
		(placement
			(enabled no)
			(sheetname "")
		)
		(fill yes
			(thermal_gap 0.5)
			(thermal_bridge_width 0.5)
			(island_removal_mode 0)
		)
		(polygon
			(pts
				(arc
					(start 91.401138 -270.19758)
					(mid 90.748358 -270.19758)
					(end 91.401138 -270.19758)
				)
			)
		)
	)
	(zone
		(layers "B.Cu" "In4.Cu" "In6.Cu" "In11.Cu" "In13.Cu" "In15.Cu")
		(hatch none 0.5)
		(connect_pads
			(clearance 0)
		)
		(min_thickness 0.25)
		(keepout
			(tracks not_allowed)
			(vias allowed)
			(pads allowed)
			(copperpour not_allowed)
			(footprints allowed)
		)
		(placement
			(enabled no)
			(sheetname "")
		)
		(fill yes
			(thermal_gap 0.5)
			(thermal_bridge_width 0.5)
			(island_removal_mode 0)
		)
		(polygon
			(pts
				(arc
					(start 425.162472 -212.616796)
					(mid 424.509692 -212.616796)
					(end 425.162472 -212.616796)
				)
			)
		)
	)
	(zone
		(layers "B.Cu" "In4.Cu" "In6.Cu" "In11.Cu" "In13.Cu" "In15.Cu")
		(hatch none 0.5)
		(connect_pads
			(clearance 0)
		)
		(min_thickness 0.25)
		(keepout
			(tracks not_allowed)
			(vias allowed)
			(pads allowed)
			(copperpour not_allowed)
			(footprints allowed)
		)
		(placement
			(enabled no)
			(sheetname "")
		)
		(fill yes
			(thermal_gap 0.5)
			(thermal_bridge_width 0.5)
			(island_removal_mode 0)
		)
		(polygon
			(pts
				(arc
					(start 340.750652 -285.661354)
					(mid 340.097872 -285.661354)
					(end 340.750652 -285.661354)
				)
			)
		)
	)
	(zone
		(layers "B.Cu" "In4.Cu" "In6.Cu" "In11.Cu" "In13.Cu" "In15.Cu")
		(hatch none 0.5)
		(connect_pads
			(clearance 0)
		)
		(min_thickness 0.25)
		(keepout
			(tracks not_allowed)
			(vias allowed)
			(pads allowed)
			(copperpour not_allowed)
			(footprints allowed)
		)
		(placement
			(enabled no)
			(sheetname "")
		)
		(fill yes
			(thermal_gap 0.5)
			(thermal_bridge_width 0.5)
			(island_removal_mode 0)
		)
		(polygon
			(pts
				(arc
					(start 89.521284 -258.80314)
					(mid 88.868504 -258.80314)
					(end 89.521284 -258.80314)
				)
			)
		)
	)
	(zone
		(layers "B.Cu" "In4.Cu" "In6.Cu" "In11.Cu" "In13.Cu" "In15.Cu")
		(hatch none 0.5)
		(connect_pads
			(clearance 0)
		)
		(min_thickness 0.25)
		(keepout
			(tracks not_allowed)
			(vias allowed)
			(pads allowed)
			(copperpour not_allowed)
			(footprints allowed)
		)
		(placement
			(enabled no)
			(sheetname "")
		)
		(fill yes
			(thermal_gap 0.5)
			(thermal_bridge_width 0.5)
			(island_removal_mode 0)
		)
		(polygon
			(pts
				(arc
					(start 373.174006 -284.847538)
					(mid 372.521226 -284.847538)
					(end 373.174006 -284.847538)
				)
			)
		)
	)
	(zone
		(layers "B.Cu" "In4.Cu" "In6.Cu" "In11.Cu" "In13.Cu" "In15.Cu")
		(hatch none 0.5)
		(connect_pads
			(clearance 0)
		)
		(min_thickness 0.25)
		(keepout
			(tracks not_allowed)
			(vias allowed)
			(pads allowed)
			(copperpour not_allowed)
			(footprints allowed)
		)
		(placement
			(enabled no)
			(sheetname "")
		)
		(fill yes
			(thermal_gap 0.5)
			(thermal_bridge_width 0.5)
			(island_removal_mode 0)
		)
		(polygon
			(pts
				(arc
					(start 338.76107 -247.992138)
					(mid 338.10829 -247.992138)
					(end 338.76107 -247.992138)
				)
			)
		)
	)
	(zone
		(layers "B.Cu" "In4.Cu" "In6.Cu" "In11.Cu" "In13.Cu" "In15.Cu")
		(hatch none 0.5)
		(connect_pads
			(clearance 0)
		)
		(min_thickness 0.25)
		(keepout
			(tracks not_allowed)
			(vias allowed)
			(pads allowed)
			(copperpour not_allowed)
			(footprints allowed)
		)
		(placement
			(enabled no)
			(sheetname "")
		)
		(fill yes
			(thermal_gap 0.5)
			(thermal_bridge_width 0.5)
			(island_removal_mode 0)
		)
		(polygon
			(pts
				(arc
					(start 133.692138 -262.058658)
					(mid 133.039358 -262.058658)
					(end 133.692138 -262.058658)
				)
			)
		)
	)
	(zone
		(layers "B.Cu" "In4.Cu" "In6.Cu" "In11.Cu" "In13.Cu" "In15.Cu")
		(hatch none 0.5)
		(connect_pads
			(clearance 0)
		)
		(min_thickness 0.25)
		(keepout
			(tracks not_allowed)
			(vias allowed)
			(pads allowed)
			(copperpour not_allowed)
			(footprints allowed)
		)
		(placement
			(enabled no)
			(sheetname "")
		)
		(fill yes
			(thermal_gap 0.5)
			(thermal_bridge_width 0.5)
			(island_removal_mode 0)
		)
		(polygon
			(pts
				(arc
					(start 127.583184 -285.661354)
					(mid 126.930404 -285.661354)
					(end 127.583184 -285.661354)
				)
			)
		)
	)
	(zone
		(layers "B.Cu" "In4.Cu" "In6.Cu" "In11.Cu" "In13.Cu" "In15.Cu")
		(hatch none 0.5)
		(connect_pads
			(clearance 0)
		)
		(min_thickness 0.25)
		(keepout
			(tracks not_allowed)
			(vias allowed)
			(pads allowed)
			(copperpour not_allowed)
			(footprints allowed)
		)
		(placement
			(enabled no)
			(sheetname "")
		)
		(fill yes
			(thermal_gap 0.5)
			(thermal_bridge_width 0.5)
			(island_removal_mode 0)
		)
		(polygon
			(pts
				(arc
					(start 338.401152 -275.08073)
					(mid 337.748372 -275.08073)
					(end 338.401152 -275.08073)
				)
			)
		)
	)
	(zone
		(layers "B.Cu" "In4.Cu" "In6.Cu" "In11.Cu" "In13.Cu" "In15.Cu")
		(hatch none 0.5)
		(connect_pads
			(clearance 0)
		)
		(min_thickness 0.25)
		(keepout
			(tracks not_allowed)
			(vias allowed)
			(pads allowed)
			(copperpour not_allowed)
			(footprints allowed)
		)
		(placement
			(enabled no)
			(sheetname "")
		)
		(fill yes
			(thermal_gap 0.5)
			(thermal_bridge_width 0.5)
			(island_removal_mode 0)
		)
		(polygon
			(pts
				(arc
					(start 117.135402 -223.575626)
					(mid 116.482622 -223.575626)
					(end 117.135402 -223.575626)
				)
			)
		)
	)
	(zone
		(layers "B.Cu" "In4.Cu" "In6.Cu" "In11.Cu" "In13.Cu" "In15.Cu")
		(hatch none 0.5)
		(connect_pads
			(clearance 0)
		)
		(min_thickness 0.25)
		(keepout
			(tracks not_allowed)
			(vias allowed)
			(pads allowed)
			(copperpour not_allowed)
			(footprints allowed)
		)
		(placement
			(enabled no)
			(sheetname "")
		)
		(fill yes
			(thermal_gap 0.5)
			(thermal_bridge_width 0.5)
			(island_removal_mode 0)
		)
		(polygon
			(pts
				(arc
					(start 339.231224 -242.294918)
					(mid 338.578444 -242.294918)
					(end 339.231224 -242.294918)
				)
			)
		)
	)
	(zone
		(layers "B.Cu" "In4.Cu" "In6.Cu" "In11.Cu" "In13.Cu" "In15.Cu")
		(hatch none 0.5)
		(connect_pads
			(clearance 0)
		)
		(min_thickness 0.25)
		(keepout
			(tracks not_allowed)
			(vias allowed)
			(pads allowed)
			(copperpour not_allowed)
			(footprints allowed)
		)
		(placement
			(enabled no)
			(sheetname "")
		)
		(fill yes
			(thermal_gap 0.5)
			(thermal_bridge_width 0.5)
			(island_removal_mode 0)
		)
		(polygon
			(pts
				(arc
					(start 51.416204 -278.067008)
					(mid 50.763424 -278.067008)
					(end 51.416204 -278.067008)
				)
			)
		)
	)
	(zone
		(layers "B.Cu" "In4.Cu" "In6.Cu" "In11.Cu" "In13.Cu" "In15.Cu")
		(hatch none 0.5)
		(connect_pads
			(clearance 0)
		)
		(min_thickness 0.25)
		(keepout
			(tracks not_allowed)
			(vias allowed)
			(pads allowed)
			(copperpour not_allowed)
			(footprints allowed)
		)
		(placement
			(enabled no)
			(sheetname "")
		)
		(fill yes
			(thermal_gap 0.5)
			(thermal_bridge_width 0.5)
			(island_removal_mode 0)
		)
		(polygon
			(pts
				(arc
					(start 382.931924 -238.225584)
					(mid 382.279144 -238.225584)
					(end 382.931924 -238.225584)
				)
			)
		)
	)
	(zone
		(layers "B.Cu" "In4.Cu" "In6.Cu" "In11.Cu" "In13.Cu" "In15.Cu")
		(hatch none 0.5)
		(connect_pads
			(clearance 0)
		)
		(min_thickness 0.25)
		(keepout
			(tracks not_allowed)
			(vias allowed)
			(pads allowed)
			(copperpour not_allowed)
			(footprints allowed)
		)
		(placement
			(enabled no)
			(sheetname "")
		)
		(fill yes
			(thermal_gap 0.5)
			(thermal_bridge_width 0.5)
			(island_removal_mode 0)
		)
		(polygon
			(pts
				(arc
					(start 339.231224 -247.178322)
					(mid 338.578444 -247.178322)
					(end 339.231224 -247.178322)
				)
			)
		)
	)
	(zone
		(layers "B.Cu" "In4.Cu" "In6.Cu" "In11.Cu" "In13.Cu" "In15.Cu")
		(hatch none 0.5)
		(connect_pads
			(clearance 0)
		)
		(min_thickness 0.25)
		(keepout
			(tracks not_allowed)
			(vias allowed)
			(pads allowed)
			(copperpour not_allowed)
			(footprints allowed)
		)
		(placement
			(enabled no)
			(sheetname "")
		)
		(fill yes
			(thermal_gap 0.5)
			(thermal_bridge_width 0.5)
			(island_removal_mode 0)
		)
		(polygon
			(pts
				(arc
					(start 427.918626 -19.125438)
					(mid 427.215046 -19.125438)
					(end 427.918626 -19.125438)
				)
			)
		)
	)
	(zone
		(layers "B.Cu" "In4.Cu" "In6.Cu" "In11.Cu" "In13.Cu" "In15.Cu")
		(hatch none 0.5)
		(connect_pads
			(clearance 0)
		)
		(min_thickness 0.25)
		(keepout
			(tracks not_allowed)
			(vias allowed)
			(pads allowed)
			(copperpour not_allowed)
			(footprints allowed)
		)
		(placement
			(enabled no)
			(sheetname "")
		)
		(fill yes
			(thermal_gap 0.5)
			(thermal_bridge_width 0.5)
			(island_removal_mode 0)
		)
		(polygon
			(pts
				(arc
					(start 381.05207 -230.086662)
					(mid 380.39929 -230.086662)
					(end 381.05207 -230.086662)
				)
			)
		)
	)
	(zone
		(layers "B.Cu" "In4.Cu" "In6.Cu" "In11.Cu" "In13.Cu" "In15.Cu")
		(hatch none 0.5)
		(connect_pads
			(clearance 0)
		)
		(min_thickness 0.25)
		(keepout
			(tracks not_allowed)
			(vias allowed)
			(pads allowed)
			(copperpour not_allowed)
			(footprints allowed)
		)
		(placement
			(enabled no)
			(sheetname "")
		)
		(fill yes
			(thermal_gap 0.5)
			(thermal_bridge_width 0.5)
			(island_removal_mode 0)
		)
		(polygon
			(pts
				(arc
					(start 422.29659 -19.125438)
					(mid 421.59301 -19.125438)
					(end 422.29659 -19.125438)
				)
			)
		)
	)
	(zone
		(layers "B.Cu" "In4.Cu" "In6.Cu" "In11.Cu" "In13.Cu" "In15.Cu")
		(hatch none 0.5)
		(connect_pads
			(clearance 0)
		)
		(min_thickness 0.25)
		(keepout
			(tracks not_allowed)
			(vias allowed)
			(pads allowed)
			(copperpour not_allowed)
			(footprints allowed)
		)
		(placement
			(enabled no)
			(sheetname "")
		)
		(fill yes
			(thermal_gap 0.5)
			(thermal_bridge_width 0.5)
			(island_removal_mode 0)
		)
		(polygon
			(pts
				(arc
					(start 345.017598 -400.858228)
					(mid 344.314018 -400.858228)
					(end 345.017598 -400.858228)
				)
			)
		)
	)
	(zone
		(layers "B.Cu" "In4.Cu" "In6.Cu" "In11.Cu" "In13.Cu" "In15.Cu")
		(hatch none 0.5)
		(connect_pads
			(clearance 0)
		)
		(min_thickness 0.25)
		(keepout
			(tracks not_allowed)
			(vias allowed)
			(pads allowed)
			(copperpour not_allowed)
			(footprints allowed)
		)
		(placement
			(enabled no)
			(sheetname "")
		)
		(fill yes
			(thermal_gap 0.5)
			(thermal_bridge_width 0.5)
			(island_removal_mode 0)
		)
		(polygon
			(pts
				(arc
					(start 381.522224 -234.15625)
					(mid 380.869444 -234.15625)
					(end 381.522224 -234.15625)
				)
			)
		)
	)
	(zone
		(layers "B.Cu" "In4.Cu" "In6.Cu" "In11.Cu" "In13.Cu" "In15.Cu")
		(hatch none 0.5)
		(connect_pads
			(clearance 0)
		)
		(min_thickness 0.25)
		(keepout
			(tracks not_allowed)
			(vias allowed)
			(pads allowed)
			(copperpour not_allowed)
			(footprints allowed)
		)
		(placement
			(enabled no)
			(sheetname "")
		)
		(fill yes
			(thermal_gap 0.5)
			(thermal_bridge_width 0.5)
			(island_removal_mode 0)
		)
		(polygon
			(pts
				(arc
					(start 338.871052 -254.733552)
					(mid 338.218272 -254.733552)
					(end 338.871052 -254.733552)
				)
			)
		)
	)
	(zone
		(layers "B.Cu" "In4.Cu" "In6.Cu" "In11.Cu" "In13.Cu" "In15.Cu")
		(hatch none 0.5)
		(connect_pads
			(clearance 0)
		)
		(min_thickness 0.25)
		(keepout
			(tracks not_allowed)
			(vias allowed)
			(pads allowed)
			(copperpour not_allowed)
			(footprints allowed)
		)
		(placement
			(enabled no)
			(sheetname "")
		)
		(fill yes
			(thermal_gap 0.5)
			(thermal_bridge_width 0.5)
			(island_removal_mode 0)
		)
		(polygon
			(pts
				(arc
					(start 360.846624 -224.389442)
					(mid 360.193844 -224.389442)
					(end 360.846624 -224.389442)
				)
			)
		)
	)
	(zone
		(layers "B.Cu" "In4.Cu" "In6.Cu" "In11.Cu" "In13.Cu" "In15.Cu")
		(hatch none 0.5)
		(connect_pads
			(clearance 0)
		)
		(min_thickness 0.25)
		(keepout
			(tracks not_allowed)
			(vias allowed)
			(pads allowed)
			(copperpour not_allowed)
			(footprints allowed)
		)
		(placement
			(enabled no)
			(sheetname "")
		)
		(fill yes
			(thermal_gap 0.5)
			(thermal_bridge_width 0.5)
			(island_removal_mode 0)
		)
		(polygon
			(pts
				(arc
					(start 134.052056 -236.597952)
					(mid 133.399276 -236.597952)
					(end 134.052056 -236.597952)
				)
			)
		)
	)
	(zone
		(layers "B.Cu" "In4.Cu" "In6.Cu" "In11.Cu" "In13.Cu" "In15.Cu")
		(hatch none 0.5)
		(connect_pads
			(clearance 0)
		)
		(min_thickness 0.25)
		(keepout
			(tracks not_allowed)
			(vias allowed)
			(pads allowed)
			(copperpour not_allowed)
			(footprints allowed)
		)
		(placement
			(enabled no)
			(sheetname "")
		)
		(fill yes
			(thermal_gap 0.5)
			(thermal_bridge_width 0.5)
			(island_removal_mode 0)
		)
		(polygon
			(pts
				(arc
					(start 68.057268 -407.00452)
					(mid 67.353688 -407.00452)
					(end 68.057268 -407.00452)
				)
			)
		)
	)
	(zone
		(layers "B.Cu" "In4.Cu" "In6.Cu" "In11.Cu" "In13.Cu" "In15.Cu")
		(hatch none 0.5)
		(connect_pads
			(clearance 0)
		)
		(min_thickness 0.25)
		(keepout
			(tracks not_allowed)
			(vias allowed)
			(pads allowed)
			(copperpour not_allowed)
			(footprints allowed)
		)
		(placement
			(enabled no)
			(sheetname "")
		)
		(fill yes
			(thermal_gap 0.5)
			(thermal_bridge_width 0.5)
			(island_removal_mode 0)
		)
		(polygon
			(pts
				(arc
					(start 336.991452 -271.011396)
					(mid 336.338672 -271.011396)
					(end 336.991452 -271.011396)
				)
			)
		)
	)
	(zone
		(layers "B.Cu" "In4.Cu" "In6.Cu" "In11.Cu" "In13.Cu" "In15.Cu")
		(hatch none 0.5)
		(connect_pads
			(clearance 0)
		)
		(min_thickness 0.25)
		(keepout
			(tracks not_allowed)
			(vias allowed)
			(pads allowed)
			(copperpour not_allowed)
			(footprints allowed)
		)
		(placement
			(enabled no)
			(sheetname "")
		)
		(fill yes
			(thermal_gap 0.5)
			(thermal_bridge_width 0.5)
			(island_removal_mode 0)
		)
		(polygon
			(pts
				(arc
					(start 136.041384 -272.639282)
					(mid 135.388604 -272.639282)
					(end 136.041384 -272.639282)
				)
			)
		)
	)
	(zone
		(layers "B.Cu" "In4.Cu" "In6.Cu" "In11.Cu" "In13.Cu" "In15.Cu")
		(hatch none 0.5)
		(connect_pads
			(clearance 0)
		)
		(min_thickness 0.25)
		(keepout
			(tracks not_allowed)
			(vias allowed)
			(pads allowed)
			(copperpour not_allowed)
			(footprints allowed)
		)
		(placement
			(enabled no)
			(sheetname "")
		)
		(fill yes
			(thermal_gap 0.5)
			(thermal_bridge_width 0.5)
			(island_removal_mode 0)
		)
		(polygon
			(pts
				(arc
					(start 133.112002 -230.086662)
					(mid 132.459222 -230.086662)
					(end 133.112002 -230.086662)
				)
			)
		)
	)
	(zone
		(layers "B.Cu" "In4.Cu" "In6.Cu" "In11.Cu" "In13.Cu" "In15.Cu")
		(hatch none 0.5)
		(connect_pads
			(clearance 0)
		)
		(min_thickness 0.25)
		(keepout
			(tracks not_allowed)
			(vias allowed)
			(pads allowed)
			(copperpour not_allowed)
			(footprints allowed)
		)
		(placement
			(enabled no)
			(sheetname "")
		)
		(fill yes
			(thermal_gap 0.5)
			(thermal_bridge_width 0.5)
			(island_removal_mode 0)
		)
		(polygon
			(pts
				(arc
					(start 89.411556 -226.017328)
					(mid 88.758776 -226.017328)
					(end 89.411556 -226.017328)
				)
			)
		)
	)
	(zone
		(layers "B.Cu" "In4.Cu" "In6.Cu" "In11.Cu" "In13.Cu" "In15.Cu")
		(hatch none 0.5)
		(connect_pads
			(clearance 0)
		)
		(min_thickness 0.25)
		(keepout
			(tracks not_allowed)
			(vias allowed)
			(pads allowed)
			(copperpour not_allowed)
			(footprints allowed)
		)
		(placement
			(enabled no)
			(sheetname "")
		)
		(fill yes
			(thermal_gap 0.5)
			(thermal_bridge_width 0.5)
			(island_removal_mode 0)
		)
		(polygon
			(pts
				(arc
					(start 51.390804 -212.616796)
					(mid 50.738024 -212.616796)
					(end 51.390804 -212.616796)
				)
			)
		)
	)
	(zone
		(layers "B.Cu" "In4.Cu" "In6.Cu" "In11.Cu" "In13.Cu" "In15.Cu")
		(hatch none 0.5)
		(connect_pads
			(clearance 0)
		)
		(min_thickness 0.25)
		(keepout
			(tracks not_allowed)
			(vias allowed)
			(pads allowed)
			(copperpour not_allowed)
			(footprints allowed)
		)
		(placement
			(enabled no)
			(sheetname "")
		)
		(fill yes
			(thermal_gap 0.5)
			(thermal_bridge_width 0.5)
			(island_removal_mode 0)
		)
		(polygon
			(pts
				(arc
					(start 336.88147 -243.108988)
					(mid 336.22869 -243.108988)
					(end 336.88147 -243.108988)
				)
			)
		)
	)
	(zone
		(layers "B.Cu" "In4.Cu" "In6.Cu" "In11.Cu" "In13.Cu" "In15.Cu")
		(hatch none 0.5)
		(connect_pads
			(clearance 0)
		)
		(min_thickness 0.25)
		(keepout
			(tracks not_allowed)
			(vias allowed)
			(pads allowed)
			(copperpour not_allowed)
			(footprints allowed)
		)
		(placement
			(enabled no)
			(sheetname "")
		)
		(fill yes
			(thermal_gap 0.5)
			(thermal_bridge_width 0.5)
			(island_removal_mode 0)
		)
		(polygon
			(pts
				(arc
					(start 173.122336 -213.46668)
					(mid 172.469556 -213.46668)
					(end 173.122336 -213.46668)
				)
			)
		)
	)
	(zone
		(layers "B.Cu" "In4.Cu" "In6.Cu" "In11.Cu" "In13.Cu" "In15.Cu")
		(hatch none 0.5)
		(connect_pads
			(clearance 0)
		)
		(min_thickness 0.25)
		(keepout
			(tracks not_allowed)
			(vias allowed)
			(pads allowed)
			(copperpour not_allowed)
			(footprints allowed)
		)
		(placement
			(enabled no)
			(sheetname "")
		)
		(fill yes
			(thermal_gap 0.5)
			(thermal_bridge_width 0.5)
			(island_removal_mode 0)
		)
		(polygon
			(pts
				(arc
					(start 152.485344 -407.00452)
					(mid 151.781764 -407.00452)
					(end 152.485344 -407.00452)
				)
			)
		)
	)
	(zone
		(layers "B.Cu" "In4.Cu" "In6.Cu" "In11.Cu" "In13.Cu" "In15.Cu")
		(hatch none 0.5)
		(connect_pads
			(clearance 0)
		)
		(min_thickness 0.25)
		(keepout
			(tracks not_allowed)
			(vias allowed)
			(pads allowed)
			(copperpour not_allowed)
			(footprints allowed)
		)
		(placement
			(enabled no)
			(sheetname "")
		)
		(fill yes
			(thermal_gap 0.5)
			(thermal_bridge_width 0.5)
			(island_removal_mode 0)
		)
		(polygon
			(pts
				(arc
					(start 116.195602 -225.203258)
					(mid 115.542822 -225.203258)
					(end 116.195602 -225.203258)
				)
			)
		)
	)
	(zone
		(layers "B.Cu" "In4.Cu" "In6.Cu" "In11.Cu" "In13.Cu" "In15.Cu")
		(hatch none 0.5)
		(connect_pads
			(clearance 0)
		)
		(min_thickness 0.25)
		(keepout
			(tracks not_allowed)
			(vias allowed)
			(pads allowed)
			(copperpour not_allowed)
			(footprints allowed)
		)
		(placement
			(enabled no)
			(sheetname "")
		)
		(fill yes
			(thermal_gap 0.5)
			(thermal_bridge_width 0.5)
			(island_removal_mode 0)
		)
		(polygon
			(pts
				(arc
					(start 92.340938 -286.475424)
					(mid 91.688158 -286.475424)
					(end 92.340938 -286.475424)
				)
			)
		)
	)
	(zone
		(layers "B.Cu" "In4.Cu" "In6.Cu" "In11.Cu" "In13.Cu" "In15.Cu")
		(hatch none 0.5)
		(connect_pads
			(clearance 0)
		)
		(min_thickness 0.25)
		(keepout
			(tracks not_allowed)
			(vias allowed)
			(pads allowed)
			(copperpour not_allowed)
			(footprints allowed)
		)
		(placement
			(enabled no)
			(sheetname "")
		)
		(fill yes
			(thermal_gap 0.5)
			(thermal_bridge_width 0.5)
			(island_removal_mode 0)
		)
		(polygon
			(pts
				(arc
					(start 108.677202 -225.203258)
					(mid 108.024422 -225.203258)
					(end 108.677202 -225.203258)
				)
			)
		)
	)
	(zone
		(layers "B.Cu" "In4.Cu" "In6.Cu" "In11.Cu" "In13.Cu" "In15.Cu")
		(hatch none 0.5)
		(connect_pads
			(clearance 0)
		)
		(min_thickness 0.25)
		(keepout
			(tracks not_allowed)
			(vias allowed)
			(pads allowed)
			(copperpour not_allowed)
			(footprints allowed)
		)
		(placement
			(enabled no)
			(sheetname "")
		)
		(fill yes
			(thermal_gap 0.5)
			(thermal_bridge_width 0.5)
			(island_removal_mode 0)
		)
		(polygon
			(pts
				(arc
					(start 90.930984 -271.011396)
					(mid 90.278204 -271.011396)
					(end 90.930984 -271.011396)
				)
			)
		)
	)
	(zone
		(layers "B.Cu" "In4.Cu" "In6.Cu" "In11.Cu" "In13.Cu" "In15.Cu")
		(hatch none 0.5)
		(connect_pads
			(clearance 0)
		)
		(min_thickness 0.25)
		(keepout
			(tracks not_allowed)
			(vias allowed)
			(pads allowed)
			(copperpour not_allowed)
			(footprints allowed)
		)
		(placement
			(enabled no)
			(sheetname "")
		)
		(fill yes
			(thermal_gap 0.5)
			(thermal_bridge_width 0.5)
			(island_removal_mode 0)
		)
		(polygon
			(pts
				(arc
					(start 425.162472 -293.366698)
					(mid 424.509692 -293.366698)
					(end 425.162472 -293.366698)
				)
			)
		)
	)
	(zone
		(layers "B.Cu" "In4.Cu" "In6.Cu" "In11.Cu" "In13.Cu" "In15.Cu")
		(hatch none 0.5)
		(connect_pads
			(clearance 0)
		)
		(min_thickness 0.25)
		(keepout
			(tracks not_allowed)
			(vias allowed)
			(pads allowed)
			(copperpour not_allowed)
			(footprints allowed)
		)
		(placement
			(enabled no)
			(sheetname "")
		)
		(fill yes
			(thermal_gap 0.5)
			(thermal_bridge_width 0.5)
			(island_removal_mode 0)
		)
		(polygon
			(pts
				(arc
					(start 16.749268 -17.61236)
					(mid 16.045688 -17.61236)
					(end 16.749268 -17.61236)
				)
			)
		)
	)
	(zone
		(layers "B.Cu" "In4.Cu" "In6.Cu" "In11.Cu" "In13.Cu" "In15.Cu")
		(hatch none 0.5)
		(connect_pads
			(clearance 0)
		)
		(min_thickness 0.25)
		(keepout
			(tracks not_allowed)
			(vias allowed)
			(pads allowed)
			(copperpour not_allowed)
			(footprints allowed)
		)
		(placement
			(enabled no)
			(sheetname "")
		)
		(fill yes
			(thermal_gap 0.5)
			(thermal_bridge_width 0.5)
			(island_removal_mode 0)
		)
		(polygon
			(pts
				(arc
					(start 404.61692 -407.00452)
					(mid 403.91334 -407.00452)
					(end 404.61692 -407.00452)
				)
			)
		)
	)
	(zone
		(layers "B.Cu" "In4.Cu" "In6.Cu" "In11.Cu" "In13.Cu" "In15.Cu")
		(hatch none 0.5)
		(connect_pads
			(clearance 0)
		)
		(min_thickness 0.25)
		(keepout
			(tracks not_allowed)
			(vias allowed)
			(pads allowed)
			(copperpour not_allowed)
			(footprints allowed)
		)
		(placement
			(enabled no)
			(sheetname "")
		)
		(fill yes
			(thermal_gap 0.5)
			(thermal_bridge_width 0.5)
			(island_removal_mode 0)
		)
		(polygon
			(pts
				(arc
					(start 90.351356 -242.294918)
					(mid 89.698576 -242.294918)
					(end 90.351356 -242.294918)
				)
			)
		)
	)
	(zone
		(layers "B.Cu" "In4.Cu" "In6.Cu" "In11.Cu" "In13.Cu" "In15.Cu")
		(hatch none 0.5)
		(connect_pads
			(clearance 0)
		)
		(min_thickness 0.25)
		(keepout
			(tracks not_allowed)
			(vias allowed)
			(pads allowed)
			(copperpour not_allowed)
			(footprints allowed)
		)
		(placement
			(enabled no)
			(sheetname "")
		)
		(fill yes
			(thermal_gap 0.5)
			(thermal_bridge_width 0.5)
			(island_removal_mode 0)
		)
		(polygon
			(pts
				(arc
					(start 74.183748 -407.00452)
					(mid 73.480168 -407.00452)
					(end 74.183748 -407.00452)
				)
			)
		)
	)
	(zone
		(layers "B.Cu" "In4.Cu" "In6.Cu" "In11.Cu" "In13.Cu" "In15.Cu")
		(hatch none 0.5)
		(connect_pads
			(clearance 0)
		)
		(min_thickness 0.25)
		(keepout
			(tracks not_allowed)
			(vias allowed)
			(pads allowed)
			(copperpour not_allowed)
			(footprints allowed)
		)
		(placement
			(enabled no)
			(sheetname "")
		)
		(fill yes
			(thermal_gap 0.5)
			(thermal_bridge_width 0.5)
			(island_removal_mode 0)
		)
		(polygon
			(pts
				(arc
					(start 337.351624 -230.900478)
					(mid 336.698844 -230.900478)
					(end 337.351624 -230.900478)
				)
			)
		)
	)
	(zone
		(layers "B.Cu" "In4.Cu" "In6.Cu" "In11.Cu" "In13.Cu" "In15.Cu")
		(hatch none 0.5)
		(connect_pads
			(clearance 0)
		)
		(min_thickness 0.25)
		(keepout
			(tracks not_allowed)
			(vias allowed)
			(pads allowed)
			(copperpour not_allowed)
			(footprints allowed)
		)
		(placement
			(enabled no)
			(sheetname "")
		)
		(fill yes
			(thermal_gap 0.5)
			(thermal_bridge_width 0.5)
			(island_removal_mode 0)
		)
		(polygon
			(pts
				(arc
					(start 47.290736 -272.966688)
					(mid 46.637956 -272.966688)
					(end 47.290736 -272.966688)
				)
			)
		)
	)
	(zone
		(layers "B.Cu" "In4.Cu" "In6.Cu" "In11.Cu" "In13.Cu" "In15.Cu")
		(hatch none 0.5)
		(connect_pads
			(clearance 0)
		)
		(min_thickness 0.25)
		(keepout
			(tracks not_allowed)
			(vias allowed)
			(pads allowed)
			(copperpour not_allowed)
			(footprints allowed)
		)
		(placement
			(enabled no)
			(sheetname "")
		)
		(fill yes
			(thermal_gap 0.5)
			(thermal_bridge_width 0.5)
			(island_removal_mode 0)
		)
		(polygon
			(pts
				(arc
					(start 310.318404 -232.166668)
					(mid 309.665624 -232.166668)
					(end 310.318404 -232.166668)
				)
			)
		)
	)
	(zone
		(layers "B.Cu" "In4.Cu" "In6.Cu" "In11.Cu" "In13.Cu" "In15.Cu")
		(hatch none 0.5)
		(connect_pads
			(clearance 0)
		)
		(min_thickness 0.25)
		(keepout
			(tracks not_allowed)
			(vias allowed)
			(pads allowed)
			(copperpour not_allowed)
			(footprints allowed)
		)
		(placement
			(enabled no)
			(sheetname "")
		)
		(fill yes
			(thermal_gap 0.5)
			(thermal_bridge_width 0.5)
			(island_removal_mode 0)
		)
		(polygon
			(pts
				(arc
					(start 421.062404 -278.916638)
					(mid 420.409624 -278.916638)
					(end 421.062404 -278.916638)
				)
			)
		)
	)
	(zone
		(layers "B.Cu" "In4.Cu" "In6.Cu" "In11.Cu" "In13.Cu" "In15.Cu")
		(hatch none 0.5)
		(connect_pads
			(clearance 0)
		)
		(min_thickness 0.25)
		(keepout
			(tracks not_allowed)
			(vias allowed)
			(pads allowed)
			(copperpour not_allowed)
			(footprints allowed)
		)
		(placement
			(enabled no)
			(sheetname "")
		)
		(fill yes
			(thermal_gap 0.5)
			(thermal_bridge_width 0.5)
			(island_removal_mode 0)
		)
		(polygon
			(pts
				(arc
					(start 106.327956 -224.389442)
					(mid 105.675176 -224.389442)
					(end 106.327956 -224.389442)
				)
			)
		)
	)
	(zone
		(layers "B.Cu" "In4.Cu" "In6.Cu" "In11.Cu" "In13.Cu" "In15.Cu")
		(hatch none 0.5)
		(connect_pads
			(clearance 0)
		)
		(min_thickness 0.25)
		(keepout
			(tracks not_allowed)
			(vias allowed)
			(pads allowed)
			(copperpour not_allowed)
			(footprints allowed)
		)
		(placement
			(enabled no)
			(sheetname "")
		)
		(fill yes
			(thermal_gap 0.5)
			(thermal_bridge_width 0.5)
			(island_removal_mode 0)
		)
		(polygon
			(pts
				(arc
					(start 129.932938 -286.475424)
					(mid 129.280158 -286.475424)
					(end 129.932938 -286.475424)
				)
			)
		)
	)
	(zone
		(layers "B.Cu" "In4.Cu" "In6.Cu" "In11.Cu" "In13.Cu" "In15.Cu")
		(hatch none 0.5)
		(connect_pads
			(clearance 0)
		)
		(min_thickness 0.25)
		(keepout
			(tracks not_allowed)
			(vias allowed)
			(pads allowed)
			(copperpour not_allowed)
			(footprints allowed)
		)
		(placement
			(enabled no)
			(sheetname "")
		)
		(fill yes
			(thermal_gap 0.5)
			(thermal_bridge_width 0.5)
			(island_removal_mode 0)
		)
		(polygon
			(pts
				(arc
					(start 66.478404 -231.316784)
					(mid 65.825624 -231.316784)
					(end 66.478404 -231.316784)
				)
			)
		)
	)
	(zone
		(layers "B.Cu" "In4.Cu" "In6.Cu" "In11.Cu" "In13.Cu" "In15.Cu")
		(hatch none 0.5)
		(connect_pads
			(clearance 0)
		)
		(min_thickness 0.25)
		(keepout
			(tracks not_allowed)
			(vias allowed)
			(pads allowed)
			(copperpour not_allowed)
			(footprints allowed)
		)
		(placement
			(enabled no)
			(sheetname "")
		)
		(fill yes
			(thermal_gap 0.5)
			(thermal_bridge_width 0.5)
			(island_removal_mode 0)
		)
		(polygon
			(pts
				(arc
					(start 421.062404 -207.51673)
					(mid 420.409624 -207.51673)
					(end 421.062404 -207.51673)
				)
			)
		)
	)
	(zone
		(layers "B.Cu" "In4.Cu" "In6.Cu" "In11.Cu" "In13.Cu" "In15.Cu")
		(hatch none 0.5)
		(connect_pads
			(clearance 0)
		)
		(min_thickness 0.25)
		(keepout
			(tracks not_allowed)
			(vias allowed)
			(pads allowed)
			(copperpour not_allowed)
			(footprints allowed)
		)
		(placement
			(enabled no)
			(sheetname "")
		)
		(fill yes
			(thermal_gap 0.5)
			(thermal_bridge_width 0.5)
			(island_removal_mode 0)
		)
		(polygon
			(pts
				(arc
					(start 90.821002 -228.45903)
					(mid 90.168222 -228.45903)
					(end 90.821002 -228.45903)
				)
			)
		)
	)
	(zone
		(layers "B.Cu" "In4.Cu" "In6.Cu" "In11.Cu" "In13.Cu" "In15.Cu")
		(hatch none 0.5)
		(connect_pads
			(clearance 0)
		)
		(min_thickness 0.25)
		(keepout
			(tracks not_allowed)
			(vias allowed)
			(pads allowed)
			(copperpour not_allowed)
			(footprints allowed)
		)
		(placement
			(enabled no)
			(sheetname "")
		)
		(fill yes
			(thermal_gap 0.5)
			(thermal_bridge_width 0.5)
			(island_removal_mode 0)
		)
		(polygon
			(pts
				(arc
					(start 345.919806 -286.475424)
					(mid 345.267026 -286.475424)
					(end 345.919806 -286.475424)
				)
			)
		)
	)
	(zone
		(layers "B.Cu" "In4.Cu" "In6.Cu" "In11.Cu" "In13.Cu" "In15.Cu")
		(hatch none 0.5)
		(connect_pads
			(clearance 0)
		)
		(min_thickness 0.25)
		(keepout
			(tracks not_allowed)
			(vias allowed)
			(pads allowed)
			(copperpour not_allowed)
			(footprints allowed)
		)
		(placement
			(enabled no)
			(sheetname "")
		)
		(fill yes
			(thermal_gap 0.5)
			(thermal_bridge_width 0.5)
			(island_removal_mode 0)
		)
		(polygon
			(pts
				(arc
					(start 295.230804 -218.566746)
					(mid 294.578024 -218.566746)
					(end 295.230804 -218.566746)
				)
			)
		)
	)
	(zone
		(layers "B.Cu" "In4.Cu" "In6.Cu" "In11.Cu" "In13.Cu" "In15.Cu")
		(hatch none 0.5)
		(connect_pads
			(clearance 0)
		)
		(min_thickness 0.25)
		(keepout
			(tracks not_allowed)
			(vias allowed)
			(pads allowed)
			(copperpour not_allowed)
			(footprints allowed)
		)
		(placement
			(enabled no)
			(sheetname "")
		)
		(fill yes
			(thermal_gap 0.5)
			(thermal_bridge_width 0.5)
			(island_removal_mode 0)
		)
		(polygon
			(pts
				(arc
					(start 310.318404 -302.716692)
					(mid 309.665624 -302.716692)
					(end 310.318404 -302.716692)
				)
			)
		)
	)
	(zone
		(layers "B.Cu" "In4.Cu" "In6.Cu" "In11.Cu" "In13.Cu" "In15.Cu")
		(hatch none 0.5)
		(connect_pads
			(clearance 0)
		)
		(min_thickness 0.25)
		(keepout
			(tracks not_allowed)
			(vias allowed)
			(pads allowed)
			(copperpour not_allowed)
			(footprints allowed)
		)
		(placement
			(enabled no)
			(sheetname "")
		)
		(fill yes
			(thermal_gap 0.5)
			(thermal_bridge_width 0.5)
			(island_removal_mode 0)
		)
		(polygon
			(pts
				(arc
					(start 89.521284 -257.175254)
					(mid 88.868504 -257.175254)
					(end 89.521284 -257.175254)
				)
			)
		)
	)
	(zone
		(layers "B.Cu" "In4.Cu" "In6.Cu" "In11.Cu" "In13.Cu" "In15.Cu")
		(hatch none 0.5)
		(connect_pads
			(clearance 0)
		)
		(min_thickness 0.25)
		(keepout
			(tracks not_allowed)
			(vias allowed)
			(pads allowed)
			(copperpour not_allowed)
			(footprints allowed)
		)
		(placement
			(enabled no)
			(sheetname "")
		)
		(fill yes
			(thermal_gap 0.5)
			(thermal_bridge_width 0.5)
			(island_removal_mode 0)
		)
		(polygon
			(pts
				(arc
					(start 297.48607 -161.557208)
					(mid 296.78249 -161.557208)
					(end 297.48607 -161.557208)
				)
			)
		)
	)
	(zone
		(layers "B.Cu" "In4.Cu" "In6.Cu" "In11.Cu" "In13.Cu" "In15.Cu")
		(hatch none 0.5)
		(connect_pads
			(clearance 0)
		)
		(min_thickness 0.25)
		(keepout
			(tracks not_allowed)
			(vias allowed)
			(pads allowed)
			(copperpour not_allowed)
			(footprints allowed)
		)
		(placement
			(enabled no)
			(sheetname "")
		)
		(fill yes
			(thermal_gap 0.5)
			(thermal_bridge_width 0.5)
			(island_removal_mode 0)
		)
		(polygon
			(pts
				(arc
					(start 295.230804 -241.516662)
					(mid 294.578024 -241.516662)
					(end 295.230804 -241.516662)
				)
			)
		)
	)
	(zone
		(layers "B.Cu" "In4.Cu" "In6.Cu" "In11.Cu" "In13.Cu" "In15.Cu")
		(hatch none 0.5)
		(connect_pads
			(clearance 0)
		)
		(min_thickness 0.25)
		(keepout
			(tracks not_allowed)
			(vias allowed)
			(pads allowed)
			(copperpour not_allowed)
			(footprints allowed)
		)
		(placement
			(enabled no)
			(sheetname "")
		)
		(fill yes
			(thermal_gap 0.5)
			(thermal_bridge_width 0.5)
			(island_removal_mode 0)
		)
		(polygon
			(pts
				(arc
					(start 62.794388 -407.00452)
					(mid 62.090808 -407.00452)
					(end 62.794388 -407.00452)
				)
			)
		)
	)
	(zone
		(layers "B.Cu" "In4.Cu" "In6.Cu" "In11.Cu" "In13.Cu" "In15.Cu")
		(hatch none 0.5)
		(connect_pads
			(clearance 0)
		)
		(min_thickness 0.25)
		(keepout
			(tracks not_allowed)
			(vias allowed)
			(pads allowed)
			(copperpour not_allowed)
			(footprints allowed)
		)
		(placement
			(enabled no)
			(sheetname "")
		)
		(fill yes
			(thermal_gap 0.5)
			(thermal_bridge_width 0.5)
			(island_removal_mode 0)
		)
		(polygon
			(pts
				(arc
					(start 56.20512 -17.61236)
					(mid 55.50154 -17.61236)
					(end 56.20512 -17.61236)
				)
			)
		)
	)
	(zone
		(layers "B.Cu" "In4.Cu" "In6.Cu" "In11.Cu" "In13.Cu" "In15.Cu")
		(hatch none 0.5)
		(connect_pads
			(clearance 0)
		)
		(min_thickness 0.25)
		(keepout
			(tracks not_allowed)
			(vias allowed)
			(pads allowed)
			(copperpour not_allowed)
			(footprints allowed)
		)
		(placement
			(enabled no)
			(sheetname "")
		)
		(fill yes
			(thermal_gap 0.5)
			(thermal_bridge_width 0.5)
			(island_removal_mode 0)
		)
		(polygon
			(pts
				(arc
					(start 91.291156 -237.411514)
					(mid 90.638376 -237.411514)
					(end 91.291156 -237.411514)
				)
			)
		)
	)
	(zone
		(layers "B.Cu" "In4.Cu" "In6.Cu" "In11.Cu" "In13.Cu" "In15.Cu")
		(hatch none 0.5)
		(connect_pads
			(clearance 0)
		)
		(min_thickness 0.25)
		(keepout
			(tracks not_allowed)
			(vias allowed)
			(pads allowed)
			(copperpour not_allowed)
			(footprints allowed)
		)
		(placement
			(enabled no)
			(sheetname "")
		)
		(fill yes
			(thermal_gap 0.5)
			(thermal_bridge_width 0.5)
			(island_removal_mode 0)
		)
		(polygon
			(pts
				(arc
					(start 432.706272 -267.016738)
					(mid 432.053492 -267.016738)
					(end 432.706272 -267.016738)
				)
			)
		)
	)
	(zone
		(layers "B.Cu" "In4.Cu" "In6.Cu" "In11.Cu" "In13.Cu" "In15.Cu")
		(hatch none 0.5)
		(connect_pads
			(clearance 0)
		)
		(min_thickness 0.25)
		(keepout
			(tracks not_allowed)
			(vias allowed)
			(pads allowed)
			(copperpour not_allowed)
			(footprints allowed)
		)
		(placement
			(enabled no)
			(sheetname "")
		)
		(fill yes
			(thermal_gap 0.5)
			(thermal_bridge_width 0.5)
			(island_removal_mode 0)
		)
		(polygon
			(pts
				(arc
					(start 149.422104 -407.00452)
					(mid 148.718524 -407.00452)
					(end 149.422104 -407.00452)
				)
			)
		)
	)
	(zone
		(layers "B.Cu" "In4.Cu" "In6.Cu" "In11.Cu" "In13.Cu" "In15.Cu")
		(hatch none 0.5)
		(connect_pads
			(clearance 0)
		)
		(min_thickness 0.25)
		(keepout
			(tracks not_allowed)
			(vias allowed)
			(pads allowed)
			(copperpour not_allowed)
			(footprints allowed)
		)
		(placement
			(enabled no)
			(sheetname "")
		)
		(fill yes
			(thermal_gap 0.5)
			(thermal_bridge_width 0.5)
			(island_removal_mode 0)
		)
		(polygon
			(pts
				(arc
					(start 420.986204 -266.1666)
					(mid 420.333424 -266.1666)
					(end 420.986204 -266.1666)
				)
			)
		)
	)
	(zone
		(layers "B.Cu" "In4.Cu" "In6.Cu" "In11.Cu" "In13.Cu" "In15.Cu")
		(hatch none 0.5)
		(connect_pads
			(clearance 0)
		)
		(min_thickness 0.25)
		(keepout
			(tracks not_allowed)
			(vias allowed)
			(pads allowed)
			(copperpour not_allowed)
			(footprints allowed)
		)
		(placement
			(enabled no)
			(sheetname "")
		)
		(fill yes
			(thermal_gap 0.5)
			(thermal_bridge_width 0.5)
			(island_removal_mode 0)
		)
		(polygon
			(pts
				(arc
					(start 177.222404 -273.816572)
					(mid 176.569624 -273.816572)
					(end 177.222404 -273.816572)
				)
			)
		)
	)
	(zone
		(layers "B.Cu" "In4.Cu" "In6.Cu" "In11.Cu" "In13.Cu" "In15.Cu")
		(hatch none 0.5)
		(connect_pads
			(clearance 0)
		)
		(min_thickness 0.25)
		(keepout
			(tracks not_allowed)
			(vias allowed)
			(pads allowed)
			(copperpour not_allowed)
			(footprints allowed)
		)
		(placement
			(enabled no)
			(sheetname "")
		)
		(fill yes
			(thermal_gap 0.5)
			(thermal_bridge_width 0.5)
			(island_removal_mode 0)
		)
		(polygon
			(pts
				(arc
					(start 47.290736 -308.666642)
					(mid 46.637956 -308.666642)
					(end 47.290736 -308.666642)
				)
			)
		)
	)
	(zone
		(layers "B.Cu" "In4.Cu" "In6.Cu" "In11.Cu" "In13.Cu" "In15.Cu")
		(hatch none 0.5)
		(connect_pads
			(clearance 0)
		)
		(min_thickness 0.25)
		(keepout
			(tracks not_allowed)
			(vias allowed)
			(pads allowed)
			(copperpour not_allowed)
			(footprints allowed)
		)
		(placement
			(enabled no)
			(sheetname "")
		)
		(fill yes
			(thermal_gap 0.5)
			(thermal_bridge_width 0.5)
			(island_removal_mode 0)
		)
		(polygon
			(pts
				(arc
					(start 134.991856 -234.970066)
					(mid 134.339076 -234.970066)
					(end 134.991856 -234.970066)
				)
			)
		)
	)
	(zone
		(layers "B.Cu" "In4.Cu" "In6.Cu" "In11.Cu" "In13.Cu" "In15.Cu")
		(hatch none 0.5)
		(connect_pads
			(clearance 0)
		)
		(min_thickness 0.25)
		(keepout
			(tracks not_allowed)
			(vias allowed)
			(pads allowed)
			(copperpour not_allowed)
			(footprints allowed)
		)
		(placement
			(enabled no)
			(sheetname "")
		)
		(fill yes
			(thermal_gap 0.5)
			(thermal_bridge_width 0.5)
			(island_removal_mode 0)
		)
		(polygon
			(pts
				(arc
					(start 91.401138 -275.08073)
					(mid 90.748358 -275.08073)
					(end 91.401138 -275.08073)
				)
			)
		)
	)
	(zone
		(layers "B.Cu" "In4.Cu" "In6.Cu" "In11.Cu" "In13.Cu" "In15.Cu")
		(hatch none 0.5)
		(connect_pads
			(clearance 0)
		)
		(min_thickness 0.25)
		(keepout
			(tracks not_allowed)
			(vias allowed)
			(pads allowed)
			(copperpour not_allowed)
			(footprints allowed)
		)
		(placement
			(enabled no)
			(sheetname "")
		)
		(fill yes
			(thermal_gap 0.5)
			(thermal_bridge_width 0.5)
			(island_removal_mode 0)
		)
		(polygon
			(pts
				(arc
					(start 137.169144 -407.00452)
					(mid 136.465564 -407.00452)
					(end 137.169144 -407.00452)
				)
			)
		)
	)
	(zone
		(layers "B.Cu" "In4.Cu" "In6.Cu" "In11.Cu" "In13.Cu" "In15.Cu")
		(hatch none 0.5)
		(connect_pads
			(clearance 0)
		)
		(min_thickness 0.25)
		(keepout
			(tracks not_allowed)
			(vias allowed)
			(pads allowed)
			(copperpour not_allowed)
			(footprints allowed)
		)
		(placement
			(enabled no)
			(sheetname "")
		)
		(fill yes
			(thermal_gap 0.5)
			(thermal_bridge_width 0.5)
			(island_removal_mode 0)
		)
		(polygon
			(pts
				(arc
					(start 337.461352 -258.80314)
					(mid 336.808572 -258.80314)
					(end 337.461352 -258.80314)
				)
			)
		)
	)
	(zone
		(layers "B.Cu" "In4.Cu" "In6.Cu" "In11.Cu" "In13.Cu" "In15.Cu")
		(hatch none 0.5)
		(connect_pads
			(clearance 0)
		)
		(min_thickness 0.25)
		(keepout
			(tracks not_allowed)
			(vias allowed)
			(pads allowed)
			(copperpour not_allowed)
			(footprints allowed)
		)
		(placement
			(enabled no)
			(sheetname "")
		)
		(fill yes
			(thermal_gap 0.5)
			(thermal_bridge_width 0.5)
			(island_removal_mode 0)
		)
		(polygon
			(pts
				(arc
					(start 124.294138 -286.475424)
					(mid 123.641358 -286.475424)
					(end 124.294138 -286.475424)
				)
			)
		)
	)
	(zone
		(layers "B.Cu" "In4.Cu" "In6.Cu" "In11.Cu" "In13.Cu" "In15.Cu")
		(hatch none 0.5)
		(connect_pads
			(clearance 0)
		)
		(min_thickness 0.25)
		(keepout
			(tracks not_allowed)
			(vias allowed)
			(pads allowed)
			(copperpour not_allowed)
			(footprints allowed)
		)
		(placement
			(enabled no)
			(sheetname "")
		)
		(fill yes
			(thermal_gap 0.5)
			(thermal_bridge_width 0.5)
			(island_removal_mode 0)
		)
		(polygon
			(pts
				(arc
					(start 314.418472 -301.866808)
					(mid 313.765692 -301.866808)
					(end 314.418472 -301.866808)
				)
			)
		)
	)
	(zone
		(layers "B.Cu" "In4.Cu" "In6.Cu" "In11.Cu" "In13.Cu" "In15.Cu")
		(hatch none 0.5)
		(connect_pads
			(clearance 0)
		)
		(min_thickness 0.25)
		(keepout
			(tracks not_allowed)
			(vias allowed)
			(pads allowed)
			(copperpour not_allowed)
			(footprints allowed)
		)
		(placement
			(enabled no)
			(sheetname "")
		)
		(fill yes
			(thermal_gap 0.5)
			(thermal_bridge_width 0.5)
			(island_removal_mode 0)
		)
		(polygon
			(pts
				(arc
					(start 338.291424 -237.411514)
					(mid 337.638644 -237.411514)
					(end 338.291424 -237.411514)
				)
			)
		)
	)
	(zone
		(layers "B.Cu" "In4.Cu" "In6.Cu" "In11.Cu" "In13.Cu" "In15.Cu")
		(hatch none 0.5)
		(connect_pads
			(clearance 0)
		)
		(min_thickness 0.25)
		(keepout
			(tracks not_allowed)
			(vias allowed)
			(pads allowed)
			(copperpour not_allowed)
			(footprints allowed)
		)
		(placement
			(enabled no)
			(sheetname "")
		)
		(fill yes
			(thermal_gap 0.5)
			(thermal_bridge_width 0.5)
			(island_removal_mode 0)
		)
		(polygon
			(pts
				(arc
					(start 349.208852 -285.661354)
					(mid 348.556072 -285.661354)
					(end 349.208852 -285.661354)
				)
			)
		)
	)
	(zone
		(layers "B.Cu" "In4.Cu" "In6.Cu" "In11.Cu" "In13.Cu" "In15.Cu")
		(hatch none 0.5)
		(connect_pads
			(clearance 0)
		)
		(min_thickness 0.25)
		(keepout
			(tracks not_allowed)
			(vias allowed)
			(pads allowed)
			(copperpour not_allowed)
			(footprints allowed)
		)
		(placement
			(enabled no)
			(sheetname "")
		)
		(fill yes
			(thermal_gap 0.5)
			(thermal_bridge_width 0.5)
			(island_removal_mode 0)
		)
		(polygon
			(pts
				(arc
					(start 336.88147 -228.45903)
					(mid 336.22869 -228.45903)
					(end 336.88147 -228.45903)
				)
			)
		)
	)
	(zone
		(layers "B.Cu" "In4.Cu" "In6.Cu" "In11.Cu" "In13.Cu" "In15.Cu")
		(hatch none 0.5)
		(connect_pads
			(clearance 0)
		)
		(min_thickness 0.25)
		(keepout
			(tracks not_allowed)
			(vias allowed)
			(pads allowed)
			(copperpour not_allowed)
			(footprints allowed)
		)
		(placement
			(enabled no)
			(sheetname "")
		)
		(fill yes
			(thermal_gap 0.5)
			(thermal_bridge_width 0.5)
			(island_removal_mode 0)
		)
		(polygon
			(pts
				(arc
					(start 134.991602 -239.853216)
					(mid 134.338822 -239.853216)
					(end 134.991602 -239.853216)
				)
			)
		)
	)
	(zone
		(layers "B.Cu" "In4.Cu" "In6.Cu" "In11.Cu" "In13.Cu" "In15.Cu")
		(hatch none 0.5)
		(connect_pads
			(clearance 0)
		)
		(min_thickness 0.25)
		(keepout
			(tracks not_allowed)
			(vias allowed)
			(pads allowed)
			(copperpour not_allowed)
			(footprints allowed)
		)
		(placement
			(enabled no)
			(sheetname "")
		)
		(fill yes
			(thermal_gap 0.5)
			(thermal_bridge_width 0.5)
			(island_removal_mode 0)
		)
		(polygon
			(pts
				(arc
					(start 421.062404 -291.666676)
					(mid 420.409624 -291.666676)
					(end 421.062404 -291.666676)
				)
			)
		)
	)
	(zone
		(layers "B.Cu" "In4.Cu" "In6.Cu" "In11.Cu" "In13.Cu" "In15.Cu")
		(hatch none 0.5)
		(connect_pads
			(clearance 0)
		)
		(min_thickness 0.25)
		(keepout
			(tracks not_allowed)
			(vias allowed)
			(pads allowed)
			(copperpour not_allowed)
			(footprints allowed)
		)
		(placement
			(enabled no)
			(sheetname "")
		)
		(fill yes
			(thermal_gap 0.5)
			(thermal_bridge_width 0.5)
			(island_removal_mode 0)
		)
		(polygon
			(pts
				(arc
					(start 412.94304 -407.00452)
					(mid 412.23946 -407.00452)
					(end 412.94304 -407.00452)
				)
			)
		)
	)
	(zone
		(layers "B.Cu" "In4.Cu" "In6.Cu" "In11.Cu" "In13.Cu" "In15.Cu")
		(hatch none 0.5)
		(connect_pads
			(clearance 0)
		)
		(min_thickness 0.25)
		(keepout
			(tracks not_allowed)
			(vias allowed)
			(pads allowed)
			(copperpour not_allowed)
			(footprints allowed)
		)
		(placement
			(enabled no)
			(sheetname "")
		)
		(fill yes
			(thermal_gap 0.5)
			(thermal_bridge_width 0.5)
			(island_removal_mode 0)
		)
		(polygon
			(pts
				(arc
					(start 90.930984 -256.361438)
					(mid 90.278204 -256.361438)
					(end 90.930984 -256.361438)
				)
			)
		)
	)
	(zone
		(layers "B.Cu" "In4.Cu" "In6.Cu" "In11.Cu" "In13.Cu" "In15.Cu")
		(hatch none 0.5)
		(connect_pads
			(clearance 0)
		)
		(min_thickness 0.25)
		(keepout
			(tracks not_allowed)
			(vias allowed)
			(pads allowed)
			(copperpour not_allowed)
			(footprints allowed)
		)
		(placement
			(enabled no)
			(sheetname "")
		)
		(fill yes
			(thermal_gap 0.5)
			(thermal_bridge_width 0.5)
			(island_removal_mode 0)
		)
		(polygon
			(pts
				(arc
					(start 47.290736 -219.41663)
					(mid 46.637956 -219.41663)
					(end 47.290736 -219.41663)
				)
			)
		)
	)
	(zone
		(layers "B.Cu" "In4.Cu" "In6.Cu" "In11.Cu" "In13.Cu" "In15.Cu")
		(hatch none 0.5)
		(connect_pads
			(clearance 0)
		)
		(min_thickness 0.25)
		(keepout
			(tracks not_allowed)
			(vias allowed)
			(pads allowed)
			(copperpour not_allowed)
			(footprints allowed)
		)
		(placement
			(enabled no)
			(sheetname "")
		)
		(fill yes
			(thermal_gap 0.5)
			(thermal_bridge_width 0.5)
			(island_removal_mode 0)
		)
		(polygon
			(pts
				(arc
					(start 177.222404 -237.266734)
					(mid 176.569624 -237.266734)
					(end 177.222404 -237.266734)
				)
			)
		)
	)
	(zone
		(layers "B.Cu" "In4.Cu" "In6.Cu" "In11.Cu" "In13.Cu" "In15.Cu")
		(hatch none 0.5)
		(connect_pads
			(clearance 0)
		)
		(min_thickness 0.25)
		(keepout
			(tracks not_allowed)
			(vias allowed)
			(pads allowed)
			(copperpour not_allowed)
			(footprints allowed)
		)
		(placement
			(enabled no)
			(sheetname "")
		)
		(fill yes
			(thermal_gap 0.5)
			(thermal_bridge_width 0.5)
			(island_removal_mode 0)
		)
		(polygon
			(pts
				(arc
					(start 413.80664 -407.00452)
					(mid 413.10306 -407.00452)
					(end 413.80664 -407.00452)
				)
			)
		)
	)
	(zone
		(layers "B.Cu" "In4.Cu" "In6.Cu" "In11.Cu" "In13.Cu" "In15.Cu")
		(hatch none 0.5)
		(connect_pads
			(clearance 0)
		)
		(min_thickness 0.25)
		(keepout
			(tracks not_allowed)
			(vias allowed)
			(pads allowed)
			(copperpour not_allowed)
			(footprints allowed)
		)
		(placement
			(enabled no)
			(sheetname "")
		)
		(fill yes
			(thermal_gap 0.5)
			(thermal_bridge_width 0.5)
			(island_removal_mode 0)
		)
		(polygon
			(pts
				(arc
					(start 336.991452 -266.128246)
					(mid 336.338672 -266.128246)
					(end 336.991452 -266.128246)
				)
			)
		)
	)
	(zone
		(layers "B.Cu" "In4.Cu" "In6.Cu" "In11.Cu" "In13.Cu" "In15.Cu")
		(hatch none 0.5)
		(connect_pads
			(clearance 0)
		)
		(min_thickness 0.25)
		(keepout
			(tracks not_allowed)
			(vias allowed)
			(pads allowed)
			(copperpour not_allowed)
			(footprints allowed)
		)
		(placement
			(enabled no)
			(sheetname "")
		)
		(fill yes
			(thermal_gap 0.5)
			(thermal_bridge_width 0.5)
			(island_removal_mode 0)
		)
		(polygon
			(pts
				(arc
					(start 131.812538 -286.475424)
					(mid 131.159758 -286.475424)
					(end 131.812538 -286.475424)
				)
			)
		)
	)
	(zone
		(layers "B.Cu" "In4.Cu" "In6.Cu" "In11.Cu" "In13.Cu" "In15.Cu")
		(hatch none 0.5)
		(connect_pads
			(clearance 0)
		)
		(min_thickness 0.25)
		(keepout
			(tracks not_allowed)
			(vias allowed)
			(pads allowed)
			(copperpour not_allowed)
			(footprints allowed)
		)
		(placement
			(enabled no)
			(sheetname "")
		)
		(fill yes
			(thermal_gap 0.5)
			(thermal_bridge_width 0.5)
			(island_removal_mode 0)
		)
		(polygon
			(pts
				(arc
					(start 32.649668 -17.61236)
					(mid 31.946088 -17.61236)
					(end 32.649668 -17.61236)
				)
			)
		)
	)
	(zone
		(layers "B.Cu" "In4.Cu" "In6.Cu" "In11.Cu" "In13.Cu" "In15.Cu")
		(hatch none 0.5)
		(connect_pads
			(clearance 0)
		)
		(min_thickness 0.25)
		(keepout
			(tracks not_allowed)
			(vias allowed)
			(pads allowed)
			(copperpour not_allowed)
			(footprints allowed)
		)
		(placement
			(enabled no)
			(sheetname "")
		)
		(fill yes
			(thermal_gap 0.5)
			(thermal_bridge_width 0.5)
			(island_removal_mode 0)
		)
		(polygon
			(pts
				(arc
					(start 89.411556 -237.411514)
					(mid 88.758776 -237.411514)
					(end 89.411556 -237.411514)
				)
			)
		)
	)
	(zone
		(layers "B.Cu" "In4.Cu" "In6.Cu" "In11.Cu" "In13.Cu" "In15.Cu")
		(hatch none 0.5)
		(connect_pads
			(clearance 0)
		)
		(min_thickness 0.25)
		(keepout
			(tracks not_allowed)
			(vias allowed)
			(pads allowed)
			(copperpour not_allowed)
			(footprints allowed)
		)
		(placement
			(enabled no)
			(sheetname "")
		)
		(fill yes
			(thermal_gap 0.5)
			(thermal_bridge_width 0.5)
			(island_removal_mode 0)
		)
		(polygon
			(pts
				(arc
					(start 421.062404 -215.166702)
					(mid 420.409624 -215.166702)
					(end 421.062404 -215.166702)
				)
			)
		)
	)
	(zone
		(layers "B.Cu" "In4.Cu" "In6.Cu" "In11.Cu" "In13.Cu" "In15.Cu")
		(hatch none 0.5)
		(connect_pads
			(clearance 0)
		)
		(min_thickness 0.25)
		(keepout
			(tracks not_allowed)
			(vias allowed)
			(pads allowed)
			(copperpour not_allowed)
			(footprints allowed)
		)
		(placement
			(enabled no)
			(sheetname "")
		)
		(fill yes
			(thermal_gap 0.5)
			(thermal_bridge_width 0.5)
			(island_removal_mode 0)
		)
		(polygon
			(pts
				(arc
					(start 381.992124 -241.481102)
					(mid 381.339344 -241.481102)
					(end 381.992124 -241.481102)
				)
			)
		)
	)
	(zone
		(layers "B.Cu" "In4.Cu" "In6.Cu" "In11.Cu" "In13.Cu" "In15.Cu")
		(hatch none 0.5)
		(connect_pads
			(clearance 0)
		)
		(min_thickness 0.25)
		(keepout
			(tracks not_allowed)
			(vias allowed)
			(pads allowed)
			(copperpour not_allowed)
			(footprints allowed)
		)
		(placement
			(enabled no)
			(sheetname "")
		)
		(fill yes
			(thermal_gap 0.5)
			(thermal_bridge_width 0.5)
			(island_removal_mode 0)
		)
		(polygon
			(pts
				(arc
					(start 135.101584 -256.361438)
					(mid 134.448804 -256.361438)
					(end 135.101584 -256.361438)
				)
			)
		)
	)
	(zone
		(layers "B.Cu" "In4.Cu" "In6.Cu" "In11.Cu" "In13.Cu" "In15.Cu")
		(hatch none 0.5)
		(connect_pads
			(clearance 0)
		)
		(min_thickness 0.25)
		(keepout
			(tracks not_allowed)
			(vias allowed)
			(pads allowed)
			(copperpour not_allowed)
			(footprints allowed)
		)
		(placement
			(enabled no)
			(sheetname "")
		)
		(fill yes
			(thermal_gap 0.5)
			(thermal_bridge_width 0.5)
			(island_removal_mode 0)
		)
		(polygon
			(pts
				(arc
					(start 101.268784 -285.661354)
					(mid 100.616004 -285.661354)
					(end 101.268784 -285.661354)
				)
			)
		)
	)
	(zone
		(layers "B.Cu" "In4.Cu" "In6.Cu" "In11.Cu" "In13.Cu" "In15.Cu")
		(hatch none 0.5)
		(connect_pads
			(clearance 0)
		)
		(min_thickness 0.25)
		(keepout
			(tracks not_allowed)
			(vias allowed)
			(pads allowed)
			(copperpour not_allowed)
			(footprints allowed)
		)
		(placement
			(enabled no)
			(sheetname "")
		)
		(fill yes
			(thermal_gap 0.5)
			(thermal_bridge_width 0.5)
			(island_removal_mode 0)
		)
		(polygon
			(pts
				(arc
					(start 177.222404 -293.366698)
					(mid 176.569624 -293.366698)
					(end 177.222404 -293.366698)
				)
			)
		)
	)
	(zone
		(layers "B.Cu" "In4.Cu" "In6.Cu" "In11.Cu" "In13.Cu" "In15.Cu")
		(hatch none 0.5)
		(connect_pads
			(clearance 0)
		)
		(min_thickness 0.25)
		(keepout
			(tracks not_allowed)
			(vias allowed)
			(pads allowed)
			(copperpour not_allowed)
			(footprints allowed)
		)
		(placement
			(enabled no)
			(sheetname "")
		)
		(fill yes
			(thermal_gap 0.5)
			(thermal_bridge_width 0.5)
			(island_removal_mode 0)
		)
		(polygon
			(pts
				(arc
					(start 413.608774 -17.601438)
					(mid 412.905194 -17.601438)
					(end 413.608774 -17.601438)
				)
			)
		)
	)
	(zone
		(layers "B.Cu" "In4.Cu" "In6.Cu" "In11.Cu" "In13.Cu" "In15.Cu")
		(hatch none 0.5)
		(connect_pads
			(clearance 0)
		)
		(min_thickness 0.25)
		(keepout
			(tracks not_allowed)
			(vias allowed)
			(pads allowed)
			(copperpour not_allowed)
			(footprints allowed)
		)
		(placement
			(enabled no)
			(sheetname "")
		)
		(fill yes
			(thermal_gap 0.5)
			(thermal_bridge_width 0.5)
			(island_removal_mode 0)
		)
		(polygon
			(pts
				(arc
					(start 337.461352 -265.314176)
					(mid 336.808572 -265.314176)
					(end 337.461352 -265.314176)
				)
			)
		)
	)
	(zone
		(layers "B.Cu" "In4.Cu" "In6.Cu" "In11.Cu" "In13.Cu" "In15.Cu")
		(hatch none 0.5)
		(connect_pads
			(clearance 0)
		)
		(min_thickness 0.25)
		(keepout
			(tracks not_allowed)
			(vias allowed)
			(pads allowed)
			(copperpour not_allowed)
			(footprints allowed)
		)
		(placement
			(enabled no)
			(sheetname "")
		)
		(fill yes
			(thermal_gap 0.5)
			(thermal_bridge_width 0.5)
			(island_removal_mode 0)
		)
		(polygon
			(pts
				(arc
					(start 94.690184 -285.661354)
					(mid 94.037404 -285.661354)
					(end 94.690184 -285.661354)
				)
			)
		)
	)
	(zone
		(layers "B.Cu" "In4.Cu" "In6.Cu" "In11.Cu" "In13.Cu" "In15.Cu")
		(hatch none 0.5)
		(connect_pads
			(clearance 0)
		)
		(min_thickness 0.25)
		(keepout
			(tracks not_allowed)
			(vias allowed)
			(pads allowed)
			(copperpour not_allowed)
			(footprints allowed)
		)
		(placement
			(enabled no)
			(sheetname "")
		)
		(fill yes
			(thermal_gap 0.5)
			(thermal_bridge_width 0.5)
			(island_removal_mode 0)
		)
		(polygon
			(pts
				(arc
					(start 184.766204 -259.366766)
					(mid 184.113424 -259.366766)
					(end 184.766204 -259.366766)
				)
			)
		)
	)
	(zone
		(layers "B.Cu" "In4.Cu" "In6.Cu" "In11.Cu" "In13.Cu" "In15.Cu")
		(hatch none 0.5)
		(connect_pads
			(clearance 0)
		)
		(min_thickness 0.25)
		(keepout
			(tracks not_allowed)
			(vias allowed)
			(pads allowed)
			(copperpour not_allowed)
			(footprints allowed)
		)
		(placement
			(enabled no)
			(sheetname "")
		)
		(fill yes
			(thermal_gap 0.5)
			(thermal_bridge_width 0.5)
			(island_removal_mode 0)
		)
		(polygon
			(pts
				(arc
					(start 299.34789 -315.46673)
					(mid 298.69511 -315.46673)
					(end 299.34789 -315.46673)
				)
			)
		)
	)
	(zone
		(layers "B.Cu" "In4.Cu" "In6.Cu" "In11.Cu" "In13.Cu" "In15.Cu")
		(hatch none 0.5)
		(connect_pads
			(clearance 0)
		)
		(min_thickness 0.25)
		(keepout
			(tracks not_allowed)
			(vias allowed)
			(pads allowed)
			(copperpour not_allowed)
			(footprints allowed)
		)
		(placement
			(enabled no)
			(sheetname "")
		)
		(fill yes
			(thermal_gap 0.5)
			(thermal_bridge_width 0.5)
			(island_removal_mode 0)
		)
		(polygon
			(pts
				(arc
					(start 173.122336 -277.216616)
					(mid 172.469556 -277.216616)
					(end 173.122336 -277.216616)
				)
			)
		)
	)
	(zone
		(layers "B.Cu" "In4.Cu" "In6.Cu" "In11.Cu" "In13.Cu" "In15.Cu")
		(hatch none 0.5)
		(connect_pads
			(clearance 0)
		)
		(min_thickness 0.25)
		(keepout
			(tracks not_allowed)
			(vias allowed)
			(pads allowed)
			(copperpour not_allowed)
			(footprints allowed)
		)
		(placement
			(enabled no)
			(sheetname "")
		)
		(fill yes
			(thermal_gap 0.5)
			(thermal_bridge_width 0.5)
			(island_removal_mode 0)
		)
		(polygon
			(pts
				(arc
					(start 338.76107 -236.597952)
					(mid 338.10829 -236.597952)
					(end 338.76107 -236.597952)
				)
			)
		)
	)
	(zone
		(layers "B.Cu" "In4.Cu" "In6.Cu" "In11.Cu" "In13.Cu" "In15.Cu")
		(hatch none 0.5)
		(connect_pads
			(clearance 0)
		)
		(min_thickness 0.25)
		(keepout
			(tracks not_allowed)
			(vias allowed)
			(pads allowed)
			(copperpour not_allowed)
			(footprints allowed)
		)
		(placement
			(enabled no)
			(sheetname "")
		)
		(fill yes
			(thermal_gap 0.5)
			(thermal_bridge_width 0.5)
			(island_removal_mode 0)
		)
		(polygon
			(pts
				(arc
					(start 391.50036 -407.00452)
					(mid 390.79678 -407.00452)
					(end 391.50036 -407.00452)
				)
			)
		)
	)
	(zone
		(layers "B.Cu" "In4.Cu" "In6.Cu" "In11.Cu" "In13.Cu" "In15.Cu")
		(hatch none 0.5)
		(connect_pads
			(clearance 0)
		)
		(min_thickness 0.25)
		(keepout
			(tracks not_allowed)
			(vias allowed)
			(pads allowed)
			(copperpour not_allowed)
			(footprints allowed)
		)
		(placement
			(enabled no)
			(sheetname "")
		)
		(fill yes
			(thermal_gap 0.5)
			(thermal_bridge_width 0.5)
			(island_removal_mode 0)
		)
		(polygon
			(pts
				(arc
					(start 136.041384 -267.755878)
					(mid 135.388604 -267.755878)
					(end 136.041384 -267.755878)
				)
			)
		)
	)
	(zone
		(layers "B.Cu" "In4.Cu" "In6.Cu" "In11.Cu" "In13.Cu" "In15.Cu")
		(hatch none 0.5)
		(connect_pads
			(clearance 0)
		)
		(min_thickness 0.25)
		(keepout
			(tracks not_allowed)
			(vias allowed)
			(pads allowed)
			(copperpour not_allowed)
			(footprints allowed)
		)
		(placement
			(enabled no)
			(sheetname "")
		)
		(fill yes
			(thermal_gap 0.5)
			(thermal_bridge_width 0.5)
			(island_removal_mode 0)
		)
		(polygon
			(pts
				(arc
					(start 383.041652 -259.616956)
					(mid 382.388872 -259.616956)
					(end 383.041652 -259.616956)
				)
			)
		)
	)
	(zone
		(layers "B.Cu" "In4.Cu" "In6.Cu" "In11.Cu" "In13.Cu" "In15.Cu")
		(hatch none 0.5)
		(connect_pads
			(clearance 0)
		)
		(min_thickness 0.25)
		(keepout
			(tracks not_allowed)
			(vias allowed)
			(pads allowed)
			(copperpour not_allowed)
			(footprints allowed)
		)
		(placement
			(enabled no)
			(sheetname "")
		)
		(fill yes
			(thermal_gap 0.5)
			(thermal_bridge_width 0.5)
			(island_removal_mode 0)
		)
		(polygon
			(pts
				(arc
					(start 137.341102 -222.761556)
					(mid 136.688322 -222.761556)
					(end 137.341102 -222.761556)
				)
			)
		)
	)
	(zone
		(layers "B.Cu" "In4.Cu" "In6.Cu" "In11.Cu" "In13.Cu" "In15.Cu")
		(hatch none 0.5)
		(connect_pads
			(clearance 0)
		)
		(min_thickness 0.25)
		(keepout
			(tracks not_allowed)
			(vias allowed)
			(pads allowed)
			(copperpour not_allowed)
			(footprints allowed)
		)
		(placement
			(enabled no)
			(sheetname "")
		)
		(fill yes
			(thermal_gap 0.5)
			(thermal_bridge_width 0.5)
			(island_removal_mode 0)
		)
		(polygon
			(pts
				(arc
					(start 91.871038 -285.661354)
					(mid 91.218258 -285.661354)
					(end 91.871038 -285.661354)
				)
			)
		)
	)
	(zone
		(layers "B.Cu" "In4.Cu" "In6.Cu" "In11.Cu" "In13.Cu" "In15.Cu")
		(hatch none 0.5)
		(connect_pads
			(clearance 0)
		)
		(min_thickness 0.25)
		(keepout
			(tracks not_allowed)
			(vias allowed)
			(pads allowed)
			(copperpour not_allowed)
			(footprints allowed)
		)
		(placement
			(enabled no)
			(sheetname "")
		)
		(fill yes
			(thermal_gap 0.5)
			(thermal_bridge_width 0.5)
			(island_removal_mode 0)
		)
		(polygon
			(pts
				(arc
					(start 421.062404 -221.116652)
					(mid 420.409624 -221.116652)
					(end 421.062404 -221.116652)
				)
			)
		)
	)
	(zone
		(layers "B.Cu" "In4.Cu" "In6.Cu" "In11.Cu" "In13.Cu" "In15.Cu")
		(hatch none 0.5)
		(connect_pads
			(clearance 0)
		)
		(min_thickness 0.25)
		(keepout
			(tracks not_allowed)
			(vias allowed)
			(pads allowed)
			(copperpour not_allowed)
			(footprints allowed)
		)
		(placement
			(enabled no)
			(sheetname "")
		)
		(fill yes
			(thermal_gap 0.5)
			(thermal_bridge_width 0.5)
			(island_removal_mode 0)
		)
		(polygon
			(pts
				(arc
					(start 133.692138 -271.825212)
					(mid 133.039358 -271.825212)
					(end 133.692138 -271.825212)
				)
			)
		)
	)
	(zone
		(layers "B.Cu" "In4.Cu" "In6.Cu" "In11.Cu" "In13.Cu" "In15.Cu")
		(hatch none 0.5)
		(connect_pads
			(clearance 0)
		)
		(min_thickness 0.25)
		(keepout
			(tracks not_allowed)
			(vias allowed)
			(pads allowed)
			(copperpour not_allowed)
			(footprints allowed)
		)
		(placement
			(enabled no)
			(sheetname "")
		)
		(fill yes
			(thermal_gap 0.5)
			(thermal_bridge_width 0.5)
			(island_removal_mode 0)
		)
		(polygon
			(pts
				(arc
					(start 381.632206 -257.175254)
					(mid 380.979426 -257.175254)
					(end 381.632206 -257.175254)
				)
			)
		)
	)
	(zone
		(layers "B.Cu" "In4.Cu" "In6.Cu" "In11.Cu" "In13.Cu" "In15.Cu")
		(hatch none 0.5)
		(connect_pads
			(clearance 0)
		)
		(min_thickness 0.25)
		(keepout
			(tracks not_allowed)
			(vias allowed)
			(pads allowed)
			(copperpour not_allowed)
			(footprints allowed)
		)
		(placement
			(enabled no)
			(sheetname "")
		)
		(fill yes
			(thermal_gap 0.5)
			(thermal_bridge_width 0.5)
			(island_removal_mode 0)
		)
		(polygon
			(pts
				(arc
					(start 421.062404 -308.666642)
					(mid 420.409624 -308.666642)
					(end 421.062404 -308.666642)
				)
			)
		)
	)
	(zone
		(layers "B.Cu" "In4.Cu" "In6.Cu" "In11.Cu" "In13.Cu" "In15.Cu")
		(hatch none 0.5)
		(connect_pads
			(clearance 0)
		)
		(min_thickness 0.25)
		(keepout
			(tracks not_allowed)
			(vias allowed)
			(pads allowed)
			(copperpour not_allowed)
			(footprints allowed)
		)
		(placement
			(enabled no)
			(sheetname "")
		)
		(fill yes
			(thermal_gap 0.5)
			(thermal_bridge_width 0.5)
			(island_removal_mode 0)
		)
		(polygon
			(pts
				(arc
					(start 382.101852 -262.872474)
					(mid 381.449072 -262.872474)
					(end 382.101852 -262.872474)
				)
			)
		)
	)
	(zone
		(layers "B.Cu" "In4.Cu" "In6.Cu" "In11.Cu" "In13.Cu" "In15.Cu")
		(hatch none 0.5)
		(connect_pads
			(clearance 0)
		)
		(min_thickness 0.25)
		(keepout
			(tracks not_allowed)
			(vias allowed)
			(pads allowed)
			(copperpour not_allowed)
			(footprints allowed)
		)
		(placement
			(enabled no)
			(sheetname "")
		)
		(fill yes
			(thermal_gap 0.5)
			(thermal_bridge_width 0.5)
			(island_removal_mode 0)
		)
		(polygon
			(pts
				(arc
					(start 47.290736 -294.216582)
					(mid 46.637956 -294.216582)
					(end 47.290736 -294.216582)
				)
			)
		)
	)
	(zone
		(layers "B.Cu" "In4.Cu" "In6.Cu" "In11.Cu" "In13.Cu" "In15.Cu")
		(hatch none 0.5)
		(connect_pads
			(clearance 0)
		)
		(min_thickness 0.25)
		(keepout
			(tracks not_allowed)
			(vias allowed)
			(pads allowed)
			(copperpour not_allowed)
			(footprints allowed)
		)
		(placement
			(enabled no)
			(sheetname "")
		)
		(fill yes
			(thermal_gap 0.5)
			(thermal_bridge_width 0.5)
			(island_removal_mode 0)
		)
		(polygon
			(pts
				(arc
					(start 66.478404 -223.666558)
					(mid 65.825624 -223.666558)
					(end 66.478404 -223.666558)
				)
			)
		)
	)
	(zone
		(layers "B.Cu" "In4.Cu" "In6.Cu" "In11.Cu" "In13.Cu" "In15.Cu")
		(hatch none 0.5)
		(connect_pads
			(clearance 0)
		)
		(min_thickness 0.25)
		(keepout
			(tracks not_allowed)
			(vias allowed)
			(pads allowed)
			(copperpour not_allowed)
			(footprints allowed)
		)
		(placement
			(enabled no)
			(sheetname "")
		)
		(fill yes
			(thermal_gap 0.5)
			(thermal_bridge_width 0.5)
			(island_removal_mode 0)
		)
		(polygon
			(pts
				(arc
					(start 405.226774 -19.125438)
					(mid 404.523194 -19.125438)
					(end 405.226774 -19.125438)
				)
			)
		)
	)
	(zone
		(layers "B.Cu" "In4.Cu" "In6.Cu" "In11.Cu" "In13.Cu" "In15.Cu")
		(hatch none 0.5)
		(connect_pads
			(clearance 0)
		)
		(min_thickness 0.25)
		(keepout
			(tracks not_allowed)
			(vias allowed)
			(pads allowed)
			(copperpour not_allowed)
			(footprints allowed)
		)
		(placement
			(enabled no)
			(sheetname "")
		)
		(fill yes
			(thermal_gap 0.5)
			(thermal_bridge_width 0.5)
			(island_removal_mode 0)
		)
		(polygon
			(pts
				(arc
					(start 382.101852 -256.361438)
					(mid 381.449072 -256.361438)
					(end 382.101852 -256.361438)
				)
			)
		)
	)
	(zone
		(layers "B.Cu" "In4.Cu" "In6.Cu" "In11.Cu" "In13.Cu" "In15.Cu")
		(hatch none 0.5)
		(connect_pads
			(clearance 0)
		)
		(min_thickness 0.25)
		(keepout
			(tracks not_allowed)
			(vias allowed)
			(pads allowed)
			(copperpour not_allowed)
			(footprints allowed)
		)
		(placement
			(enabled no)
			(sheetname "")
		)
		(fill yes
			(thermal_gap 0.5)
			(thermal_bridge_width 0.5)
			(island_removal_mode 0)
		)
		(polygon
			(pts
				(arc
					(start 136.041384 -257.98907)
					(mid 135.388604 -257.98907)
					(end 136.041384 -257.98907)
				)
			)
		)
	)
	(zone
		(layers "B.Cu" "In4.Cu" "In6.Cu" "In11.Cu" "In13.Cu" "In15.Cu")
		(hatch none 0.5)
		(connect_pads
			(clearance 0)
		)
		(min_thickness 0.25)
		(keepout
			(tracks not_allowed)
			(vias allowed)
			(pads allowed)
			(copperpour not_allowed)
			(footprints allowed)
		)
		(placement
			(enabled no)
			(sheetname "")
		)
		(fill yes
			(thermal_gap 0.5)
			(thermal_bridge_width 0.5)
			(island_removal_mode 0)
		)
		(polygon
			(pts
				(arc
					(start 177.222404 -313.766708)
					(mid 176.569624 -313.766708)
					(end 177.222404 -313.766708)
				)
			)
		)
	)
	(zone
		(layers "B.Cu" "In4.Cu" "In6.Cu" "In11.Cu" "In13.Cu" "In15.Cu")
		(hatch none 0.5)
		(connect_pads
			(clearance 0)
		)
		(min_thickness 0.25)
		(keepout
			(tracks not_allowed)
			(vias allowed)
			(pads allowed)
			(copperpour not_allowed)
			(footprints allowed)
		)
		(placement
			(enabled no)
			(sheetname "")
		)
		(fill yes
			(thermal_gap 0.5)
			(thermal_bridge_width 0.5)
			(island_removal_mode 0)
		)
		(polygon
			(pts
				(arc
					(start 41.337484 -19.13636)
					(mid 40.633904 -19.13636)
					(end 41.337484 -19.13636)
				)
			)
		)
	)
	(zone
		(layers "B.Cu" "In4.Cu" "In6.Cu" "In11.Cu" "In13.Cu" "In15.Cu")
		(hatch none 0.5)
		(connect_pads
			(clearance 0)
		)
		(min_thickness 0.25)
		(keepout
			(tracks not_allowed)
			(vias allowed)
			(pads allowed)
			(copperpour not_allowed)
			(footprints allowed)
		)
		(placement
			(enabled no)
			(sheetname "")
		)
		(fill yes
			(thermal_gap 0.5)
			(thermal_bridge_width 0.5)
			(island_removal_mode 0)
		)
		(polygon
			(pts
				(arc
					(start 343.570052 -285.661354)
					(mid 342.917272 -285.661354)
					(end 343.570052 -285.661354)
				)
			)
		)
	)
	(zone
		(layers "B.Cu" "In4.Cu" "In6.Cu" "In11.Cu" "In13.Cu" "In15.Cu")
		(hatch none 0.5)
		(connect_pads
			(clearance 0)
		)
		(min_thickness 0.25)
		(keepout
			(tracks not_allowed)
			(vias allowed)
			(pads allowed)
			(copperpour not_allowed)
			(footprints allowed)
		)
		(placement
			(enabled no)
			(sheetname "")
		)
		(fill yes
			(thermal_gap 0.5)
			(thermal_bridge_width 0.5)
			(island_removal_mode 0)
		)
		(polygon
			(pts
				(arc
					(start 374.583452 -285.661354)
					(mid 373.930672 -285.661354)
					(end 374.583452 -285.661354)
				)
			)
		)
	)
	(zone
		(layers "B.Cu" "In4.Cu" "In6.Cu" "In11.Cu" "In13.Cu" "In15.Cu")
		(hatch none 0.5)
		(connect_pads
			(clearance 0)
		)
		(min_thickness 0.25)
		(keepout
			(tracks not_allowed)
			(vias allowed)
			(pads allowed)
			(copperpour not_allowed)
			(footprints allowed)
		)
		(placement
			(enabled no)
			(sheetname "")
		)
		(fill yes
			(thermal_gap 0.5)
			(thermal_bridge_width 0.5)
			(island_removal_mode 0)
		)
		(polygon
			(pts
				(arc
					(start 338.76107 -238.225584)
					(mid 338.10829 -238.225584)
					(end 338.76107 -238.225584)
				)
			)
		)
	)
	(zone
		(layers "B.Cu" "In4.Cu" "In6.Cu" "In11.Cu" "In13.Cu" "In15.Cu")
		(hatch none 0.5)
		(connect_pads
			(clearance 0)
		)
		(min_thickness 0.25)
		(keepout
			(tracks not_allowed)
			(vias allowed)
			(pads allowed)
			(copperpour not_allowed)
			(footprints allowed)
		)
		(placement
			(enabled no)
			(sheetname "")
		)
		(fill yes
			(thermal_gap 0.5)
			(thermal_bridge_width 0.5)
			(island_removal_mode 0)
		)
		(polygon
			(pts
				(arc
					(start 425.162472 -217.716608)
					(mid 424.509692 -217.716608)
					(end 425.162472 -217.716608)
				)
			)
		)
	)
	(zone
		(layers "B.Cu" "In4.Cu" "In6.Cu" "In11.Cu" "In13.Cu" "In15.Cu")
		(hatch none 0.5)
		(connect_pads
			(clearance 0)
		)
		(min_thickness 0.25)
		(keepout
			(tracks not_allowed)
			(vias allowed)
			(pads allowed)
			(copperpour not_allowed)
			(footprints allowed)
		)
		(placement
			(enabled no)
			(sheetname "")
		)
		(fill yes
			(thermal_gap 0.5)
			(thermal_bridge_width 0.5)
			(island_removal_mode 0)
		)
		(polygon
			(pts
				(arc
					(start 111.026956 -224.389442)
					(mid 110.374176 -224.389442)
					(end 111.026956 -224.389442)
				)
			)
		)
	)
	(zone
		(layers "B.Cu" "In4.Cu" "In6.Cu" "In11.Cu" "In13.Cu" "In15.Cu")
		(hatch none 0.5)
		(connect_pads
			(clearance 0)
		)
		(min_thickness 0.25)
		(keepout
			(tracks not_allowed)
			(vias allowed)
			(pads allowed)
			(copperpour not_allowed)
			(footprints allowed)
		)
		(placement
			(enabled no)
			(sheetname "")
		)
		(fill yes
			(thermal_gap 0.5)
			(thermal_bridge_width 0.5)
			(island_removal_mode 0)
		)
		(polygon
			(pts
				(arc
					(start 62.378336 -226.216718)
					(mid 61.725556 -226.216718)
					(end 62.378336 -226.216718)
				)
			)
		)
	)
	(zone
		(layers "B.Cu" "In4.Cu" "In6.Cu" "In11.Cu" "In13.Cu" "In15.Cu")
		(hatch none 0.5)
		(connect_pads
			(clearance 0)
		)
		(min_thickness 0.25)
		(keepout
			(tracks not_allowed)
			(vias allowed)
			(pads allowed)
			(copperpour not_allowed)
			(footprints allowed)
		)
		(placement
			(enabled no)
			(sheetname "")
		)
		(fill yes
			(thermal_gap 0.5)
			(thermal_bridge_width 0.5)
			(island_removal_mode 0)
		)
		(polygon
			(pts
				(arc
					(start 177.146204 -265.316716)
					(mid 176.493424 -265.316716)
					(end 177.146204 -265.316716)
				)
			)
		)
	)
	(zone
		(layers "B.Cu" "In4.Cu" "In6.Cu" "In11.Cu" "In13.Cu" "In15.Cu")
		(hatch none 0.5)
		(connect_pads
			(clearance 0)
		)
		(min_thickness 0.25)
		(keepout
			(tracks not_allowed)
			(vias allowed)
			(pads allowed)
			(copperpour not_allowed)
			(footprints allowed)
		)
		(placement
			(enabled no)
			(sheetname "")
		)
		(fill yes
			(thermal_gap 0.5)
			(thermal_bridge_width 0.5)
			(island_removal_mode 0)
		)
		(polygon
			(pts
				(arc
					(start 425.162472 -272.11655)
					(mid 424.509692 -272.11655)
					(end 425.162472 -272.11655)
				)
			)
		)
	)
	(zone
		(layers "B.Cu" "In4.Cu" "In6.Cu" "In11.Cu" "In13.Cu" "In15.Cu")
		(hatch none 0.5)
		(connect_pads
			(clearance 0)
		)
		(min_thickness 0.25)
		(keepout
			(tracks not_allowed)
			(vias allowed)
			(pads allowed)
			(copperpour not_allowed)
			(footprints allowed)
		)
		(placement
			(enabled no)
			(sheetname "")
		)
		(fill yes
			(thermal_gap 0.5)
			(thermal_bridge_width 0.5)
			(island_removal_mode 0)
		)
		(polygon
			(pts
				(arc
					(start 173.122336 -295.916604)
					(mid 172.469556 -295.916604)
					(end 173.122336 -295.916604)
				)
			)
		)
	)
	(zone
		(layers "B.Cu" "In4.Cu" "In6.Cu" "In11.Cu" "In13.Cu" "In15.Cu")
		(hatch none 0.5)
		(connect_pads
			(clearance 0)
		)
		(min_thickness 0.25)
		(keepout
			(tracks not_allowed)
			(vias allowed)
			(pads allowed)
			(copperpour not_allowed)
			(footprints allowed)
		)
		(placement
			(enabled no)
			(sheetname "")
		)
		(fill yes
			(thermal_gap 0.5)
			(thermal_bridge_width 0.5)
			(island_removal_mode 0)
		)
		(polygon
			(pts
				(arc
					(start 421.062404 -312.91657)
					(mid 420.409624 -312.91657)
					(end 421.062404 -312.91657)
				)
			)
		)
	)
	(zone
		(layers "B.Cu" "In4.Cu" "In6.Cu" "In11.Cu" "In13.Cu" "In15.Cu")
		(hatch none 0.5)
		(connect_pads
			(clearance 0)
		)
		(min_thickness 0.25)
		(keepout
			(tracks not_allowed)
			(vias allowed)
			(pads allowed)
			(copperpour not_allowed)
			(footprints allowed)
		)
		(placement
			(enabled no)
			(sheetname "")
		)
		(fill yes
			(thermal_gap 0.5)
			(thermal_bridge_width 0.5)
			(island_removal_mode 0)
		)
		(polygon
			(pts
				(arc
					(start 134.052056 -243.108988)
					(mid 133.399276 -243.108988)
					(end 134.052056 -243.108988)
				)
			)
		)
	)
	(zone
		(layers "B.Cu" "In4.Cu" "In6.Cu" "In11.Cu" "In13.Cu" "In15.Cu")
		(hatch none 0.5)
		(connect_pads
			(clearance 0)
		)
		(min_thickness 0.25)
		(keepout
			(tracks not_allowed)
			(vias allowed)
			(pads allowed)
			(copperpour not_allowed)
			(footprints allowed)
		)
		(placement
			(enabled no)
			(sheetname "")
		)
		(fill yes
			(thermal_gap 0.5)
			(thermal_bridge_width 0.5)
			(island_removal_mode 0)
		)
		(polygon
			(pts
				(arc
					(start 336.991452 -256.361438)
					(mid 336.338672 -256.361438)
					(end 336.991452 -256.361438)
				)
			)
		)
	)
	(zone
		(layers "B.Cu" "In4.Cu" "In6.Cu" "In11.Cu" "In13.Cu" "In15.Cu")
		(hatch none 0.5)
		(connect_pads
			(clearance 0)
		)
		(min_thickness 0.25)
		(keepout
			(tracks not_allowed)
			(vias allowed)
			(pads allowed)
			(copperpour not_allowed)
			(footprints allowed)
		)
		(placement
			(enabled no)
			(sheetname "")
		)
		(fill yes
			(thermal_gap 0.5)
			(thermal_bridge_width 0.5)
			(island_removal_mode 0)
		)
		(polygon
			(pts
				(arc
					(start 177.222404 -290.816538)
					(mid 176.569624 -290.816538)
					(end 177.222404 -290.816538)
				)
			)
		)
	)
	(zone
		(layers "B.Cu" "In4.Cu" "In6.Cu" "In11.Cu" "In13.Cu" "In15.Cu")
		(hatch none 0.5)
		(connect_pads
			(clearance 0)
		)
		(min_thickness 0.25)
		(keepout
			(tracks not_allowed)
			(vias allowed)
			(pads allowed)
			(copperpour not_allowed)
			(footprints allowed)
		)
		(placement
			(enabled no)
			(sheetname "")
		)
		(fill yes
			(thermal_gap 0.5)
			(thermal_bridge_width 0.5)
			(island_removal_mode 0)
		)
		(polygon
			(pts
				(arc
					(start 367.535206 -284.847538)
					(mid 366.882426 -284.847538)
					(end 367.535206 -284.847538)
				)
			)
		)
	)
	(zone
		(layers "B.Cu" "In4.Cu" "In6.Cu" "In11.Cu" "In13.Cu" "In15.Cu")
		(hatch none 0.5)
		(connect_pads
			(clearance 0)
		)
		(min_thickness 0.25)
		(keepout
			(tracks not_allowed)
			(vias allowed)
			(pads allowed)
			(copperpour not_allowed)
			(footprints allowed)
		)
		(placement
			(enabled no)
			(sheetname "")
		)
		(fill yes
			(thermal_gap 0.5)
			(thermal_bridge_width 0.5)
			(island_removal_mode 0)
		)
		(polygon
			(pts
				(arc
					(start 177.222404 -240.666778)
					(mid 176.569624 -240.666778)
					(end 177.222404 -240.666778)
				)
			)
		)
	)
	(zone
		(layers "B.Cu" "In4.Cu" "In6.Cu" "In11.Cu" "In13.Cu" "In15.Cu")
		(hatch none 0.5)
		(connect_pads
			(clearance 0)
		)
		(min_thickness 0.25)
		(keepout
			(tracks not_allowed)
			(vias allowed)
			(pads allowed)
			(copperpour not_allowed)
			(footprints allowed)
		)
		(placement
			(enabled no)
			(sheetname "")
		)
		(fill yes
			(thermal_gap 0.5)
			(thermal_bridge_width 0.5)
			(island_removal_mode 0)
		)
		(polygon
			(pts
				(arc
					(start 177.222404 -260.21665)
					(mid 176.569624 -260.21665)
					(end 177.222404 -260.21665)
				)
			)
		)
	)
	(zone
		(layers "B.Cu" "In4.Cu" "In6.Cu" "In11.Cu" "In13.Cu" "In15.Cu")
		(hatch none 0.5)
		(connect_pads
			(clearance 0)
		)
		(min_thickness 0.25)
		(keepout
			(tracks not_allowed)
			(vias allowed)
			(pads allowed)
			(copperpour not_allowed)
			(footprints allowed)
		)
		(placement
			(enabled no)
			(sheetname "")
		)
		(fill yes
			(thermal_gap 0.5)
			(thermal_bridge_width 0.5)
			(island_removal_mode 0)
		)
		(polygon
			(pts
				(arc
					(start 90.351356 -229.272846)
					(mid 89.698576 -229.272846)
					(end 90.351356 -229.272846)
				)
			)
		)
	)
	(zone
		(layers "B.Cu" "In4.Cu" "In6.Cu" "In11.Cu" "In13.Cu" "In15.Cu")
		(hatch none 0.5)
		(connect_pads
			(clearance 0)
		)
		(min_thickness 0.25)
		(keepout
			(tracks not_allowed)
			(vias allowed)
			(pads allowed)
			(copperpour not_allowed)
			(footprints allowed)
		)
		(placement
			(enabled no)
			(sheetname "")
		)
		(fill yes
			(thermal_gap 0.5)
			(thermal_bridge_width 0.5)
			(island_removal_mode 0)
		)
		(polygon
			(pts
				(arc
					(start 62.378336 -302.716692)
					(mid 61.725556 -302.716692)
					(end 62.378336 -302.716692)
				)
			)
		)
	)
	(zone
		(layers "B.Cu" "In4.Cu" "In6.Cu" "In11.Cu" "In13.Cu" "In15.Cu")
		(hatch none 0.5)
		(connect_pads
			(clearance 0)
		)
		(min_thickness 0.25)
		(keepout
			(tracks not_allowed)
			(vias allowed)
			(pads allowed)
			(copperpour not_allowed)
			(footprints allowed)
		)
		(placement
			(enabled no)
			(sheetname "")
		)
		(fill yes
			(thermal_gap 0.5)
			(thermal_bridge_width 0.5)
			(island_removal_mode 0)
		)
		(polygon
			(pts
				(arc
					(start 90.351356 -226.017328)
					(mid 89.698576 -226.017328)
					(end 90.351356 -226.017328)
				)
			)
		)
	)
	(zone
		(layers "B.Cu" "In4.Cu" "In6.Cu" "In11.Cu" "In13.Cu" "In15.Cu")
		(hatch none 0.5)
		(connect_pads
			(clearance 0)
		)
		(min_thickness 0.25)
		(keepout
			(tracks not_allowed)
			(vias allowed)
			(pads allowed)
			(copperpour not_allowed)
			(footprints allowed)
		)
		(placement
			(enabled no)
			(sheetname "")
		)
		(fill yes
			(thermal_gap 0.5)
			(thermal_bridge_width 0.5)
			(island_removal_mode 0)
		)
		(polygon
			(pts
				(arc
					(start 134.991856 -231.714548)
					(mid 134.339076 -231.714548)
					(end 134.991856 -231.714548)
				)
			)
		)
	)
	(zone
		(layers "B.Cu" "In4.Cu" "In6.Cu" "In11.Cu" "In13.Cu" "In15.Cu")
		(hatch none 0.5)
		(connect_pads
			(clearance 0)
		)
		(min_thickness 0.25)
		(keepout
			(tracks not_allowed)
			(vias allowed)
			(pads allowed)
			(copperpour not_allowed)
			(footprints allowed)
		)
		(placement
			(enabled no)
			(sheetname "")
		)
		(fill yes
			(thermal_gap 0.5)
			(thermal_bridge_width 0.5)
			(island_removal_mode 0)
		)
		(polygon
			(pts
				(arc
					(start 90.351356 -245.55069)
					(mid 89.698576 -245.55069)
					(end 90.351356 -245.55069)
				)
			)
		)
	)
	(zone
		(layers "B.Cu" "In4.Cu" "In6.Cu" "In11.Cu" "In13.Cu" "In15.Cu")
		(hatch none 0.5)
		(connect_pads
			(clearance 0)
		)
		(min_thickness 0.25)
		(keepout
			(tracks not_allowed)
			(vias allowed)
			(pads allowed)
			(copperpour not_allowed)
			(footprints allowed)
		)
		(placement
			(enabled no)
			(sheetname "")
		)
		(fill yes
			(thermal_gap 0.5)
			(thermal_bridge_width 0.5)
			(island_removal_mode 0)
		)
		(polygon
			(pts
				(arc
					(start 173.122336 -294.216582)
					(mid 172.469556 -294.216582)
					(end 173.122336 -294.216582)
				)
			)
		)
	)
	(zone
		(layers "B.Cu" "In4.Cu" "In6.Cu" "In11.Cu" "In13.Cu" "In15.Cu")
		(hatch none 0.5)
		(connect_pads
			(clearance 0)
		)
		(min_thickness 0.25)
		(keepout
			(tracks not_allowed)
			(vias allowed)
			(pads allowed)
			(copperpour not_allowed)
			(footprints allowed)
		)
		(placement
			(enabled no)
			(sheetname "")
		)
		(fill yes
			(thermal_gap 0.5)
			(thermal_bridge_width 0.5)
			(island_removal_mode 0)
		)
		(polygon
			(pts
				(arc
					(start 43.847004 -259.366766)
					(mid 43.194224 -259.366766)
					(end 43.847004 -259.366766)
				)
			)
		)
	)
	(zone
		(layers "B.Cu" "In4.Cu" "In6.Cu" "In11.Cu" "In13.Cu" "In15.Cu")
		(hatch none 0.5)
		(connect_pads
			(clearance 0)
		)
		(min_thickness 0.25)
		(keepout
			(tracks not_allowed)
			(vias allowed)
			(pads allowed)
			(copperpour not_allowed)
			(footprints allowed)
		)
		(placement
			(enabled no)
			(sheetname "")
		)
		(fill yes
			(thermal_gap 0.5)
			(thermal_bridge_width 0.5)
			(island_removal_mode 0)
		)
		(polygon
			(pts
				(arc
					(start 173.122336 -310.366664)
					(mid 172.469556 -310.366664)
					(end 173.122336 -310.366664)
				)
			)
		)
	)
	(zone
		(layers "B.Cu" "In4.Cu" "In6.Cu" "In11.Cu" "In13.Cu" "In15.Cu")
		(hatch none 0.5)
		(connect_pads
			(clearance 0)
		)
		(min_thickness 0.25)
		(keepout
			(tracks not_allowed)
			(vias allowed)
			(pads allowed)
			(copperpour not_allowed)
			(footprints allowed)
		)
		(placement
			(enabled no)
			(sheetname "")
		)
		(fill yes
			(thermal_gap 0.5)
			(thermal_bridge_width 0.5)
			(island_removal_mode 0)
		)
		(polygon
			(pts
				(arc
					(start 338.291424 -232.528364)
					(mid 337.638644 -232.528364)
					(end 338.291424 -232.528364)
				)
			)
		)
	)
	(zone
		(layers "B.Cu" "In4.Cu" "In6.Cu" "In11.Cu" "In13.Cu" "In15.Cu")
		(hatch none 0.5)
		(connect_pads
			(clearance 0)
		)
		(min_thickness 0.25)
		(keepout
			(tracks not_allowed)
			(vias allowed)
			(pads allowed)
			(copperpour not_allowed)
			(footprints allowed)
		)
		(placement
			(enabled no)
			(sheetname "")
		)
		(fill yes
			(thermal_gap 0.5)
			(thermal_bridge_width 0.5)
			(island_removal_mode 0)
		)
		(polygon
			(pts
				(arc
					(start 177.222404 -315.46673)
					(mid 176.569624 -315.46673)
					(end 177.222404 -315.46673)
				)
			)
		)
	)
	(zone
		(layers "B.Cu" "In4.Cu" "In6.Cu" "In11.Cu" "In13.Cu" "In15.Cu")
		(hatch none 0.5)
		(connect_pads
			(clearance 0)
		)
		(min_thickness 0.25)
		(keepout
			(tracks not_allowed)
			(vias allowed)
			(pads allowed)
			(copperpour not_allowed)
			(footprints allowed)
		)
		(placement
			(enabled no)
			(sheetname "")
		)
		(fill yes
			(thermal_gap 0.5)
			(thermal_bridge_width 0.5)
			(island_removal_mode 0)
		)
		(polygon
			(pts
				(arc
					(start 338.76107 -228.45903)
					(mid 338.10829 -228.45903)
					(end 338.76107 -228.45903)
				)
			)
		)
	)
	(zone
		(layers "B.Cu" "In4.Cu" "In6.Cu" "In11.Cu" "In13.Cu" "In15.Cu")
		(hatch none 0.5)
		(connect_pads
			(clearance 0)
		)
		(min_thickness 0.25)
		(keepout
			(tracks not_allowed)
			(vias allowed)
			(pads allowed)
			(copperpour not_allowed)
			(footprints allowed)
		)
		(placement
			(enabled no)
			(sheetname "")
		)
		(fill yes
			(thermal_gap 0.5)
			(thermal_bridge_width 0.5)
			(island_removal_mode 0)
		)
		(polygon
			(pts
				(arc
					(start 51.390804 -234.716574)
					(mid 50.738024 -234.716574)
					(end 51.390804 -234.716574)
				)
			)
		)
	)
	(zone
		(layers "B.Cu" "In4.Cu" "In6.Cu" "In11.Cu" "In13.Cu" "In15.Cu")
		(hatch none 0.5)
		(connect_pads
			(clearance 0)
		)
		(min_thickness 0.25)
		(keepout
			(tracks not_allowed)
			(vias allowed)
			(pads allowed)
			(copperpour not_allowed)
			(footprints allowed)
		)
		(placement
			(enabled no)
			(sheetname "")
		)
		(fill yes
			(thermal_gap 0.5)
			(thermal_bridge_width 0.5)
			(island_removal_mode 0)
		)
		(polygon
			(pts
				(arc
					(start 405.949404 -228.766624)
					(mid 405.296624 -228.766624)
					(end 405.949404 -228.766624)
				)
			)
		)
	)
	(zone
		(layers "B.Cu" "In4.Cu" "In6.Cu" "In11.Cu" "In13.Cu" "In15.Cu")
		(hatch none 0.5)
		(connect_pads
			(clearance 0)
		)
		(min_thickness 0.25)
		(keepout
			(tracks not_allowed)
			(vias allowed)
			(pads allowed)
			(copperpour not_allowed)
			(footprints allowed)
		)
		(placement
			(enabled no)
			(sheetname "")
		)
		(fill yes
			(thermal_gap 0.5)
			(thermal_bridge_width 0.5)
			(island_removal_mode 0)
		)
		(polygon
			(pts
				(arc
					(start 47.290736 -262.76681)
					(mid 46.637956 -262.76681)
					(end 47.290736 -262.76681)
				)
			)
		)
	)
	(zone
		(layers "B.Cu" "In4.Cu" "In6.Cu" "In11.Cu" "In13.Cu" "In15.Cu")
		(hatch none 0.5)
		(connect_pads
			(clearance 0)
		)
		(min_thickness 0.25)
		(keepout
			(tracks not_allowed)
			(vias allowed)
			(pads allowed)
			(copperpour not_allowed)
			(footprints allowed)
		)
		(placement
			(enabled no)
			(sheetname "")
		)
		(fill yes
			(thermal_gap 0.5)
			(thermal_bridge_width 0.5)
			(island_removal_mode 0)
		)
		(polygon
			(pts
				(arc
					(start 421.062404 -294.216582)
					(mid 420.409624 -294.216582)
					(end 421.062404 -294.216582)
				)
			)
		)
	)
	(zone
		(layers "B.Cu" "In4.Cu" "In6.Cu" "In11.Cu" "In13.Cu" "In15.Cu")
		(hatch none 0.5)
		(connect_pads
			(clearance 0)
		)
		(min_thickness 0.25)
		(keepout
			(tracks not_allowed)
			(vias allowed)
			(pads allowed)
			(copperpour not_allowed)
			(footprints allowed)
		)
		(placement
			(enabled no)
			(sheetname "")
		)
		(fill yes
			(thermal_gap 0.5)
			(thermal_bridge_width 0.5)
			(island_removal_mode 0)
		)
		(polygon
			(pts
				(arc
					(start 383.041652 -264.50036)
					(mid 382.388872 -264.50036)
					(end 383.041652 -264.50036)
				)
			)
		)
	)
	(zone
		(layers "B.Cu" "In4.Cu" "In6.Cu" "In11.Cu" "In13.Cu" "In15.Cu")
		(hatch none 0.5)
		(connect_pads
			(clearance 0)
		)
		(min_thickness 0.25)
		(keepout
			(tracks not_allowed)
			(vias allowed)
			(pads allowed)
			(copperpour not_allowed)
			(footprints allowed)
		)
		(placement
			(enabled no)
			(sheetname "")
		)
		(fill yes
			(thermal_gap 0.5)
			(thermal_bridge_width 0.5)
			(island_removal_mode 0)
		)
		(polygon
			(pts
				(arc
					(start 177.222404 -259.366766)
					(mid 176.569624 -259.366766)
					(end 177.222404 -259.366766)
				)
			)
		)
	)
	(zone
		(layers "B.Cu" "In4.Cu" "In6.Cu" "In11.Cu" "In13.Cu" "In15.Cu")
		(hatch none 0.5)
		(connect_pads
			(clearance 0)
		)
		(min_thickness 0.25)
		(keepout
			(tracks not_allowed)
			(vias allowed)
			(pads allowed)
			(copperpour not_allowed)
			(footprints allowed)
		)
		(placement
			(enabled no)
			(sheetname "")
		)
		(fill yes
			(thermal_gap 0.5)
			(thermal_bridge_width 0.5)
			(island_removal_mode 0)
		)
		(polygon
			(pts
				(arc
					(start 88.471756 -227.64496)
					(mid 87.818976 -227.64496)
					(end 88.471756 -227.64496)
				)
			)
		)
	)
	(zone
		(layers "B.Cu" "In4.Cu" "In6.Cu" "In11.Cu" "In13.Cu" "In15.Cu")
		(hatch none 0.5)
		(connect_pads
			(clearance 0)
		)
		(min_thickness 0.25)
		(keepout
			(tracks not_allowed)
			(vias allowed)
			(pads allowed)
			(copperpour not_allowed)
			(footprints allowed)
		)
		(placement
			(enabled no)
			(sheetname "")
		)
		(fill yes
			(thermal_gap 0.5)
			(thermal_bridge_width 0.5)
			(island_removal_mode 0)
		)
		(polygon
			(pts
				(arc
					(start 90.930984 -274.266914)
					(mid 90.278204 -274.266914)
					(end 90.930984 -274.266914)
				)
			)
		)
	)
	(zone
		(layers "B.Cu" "In4.Cu" "In6.Cu" "In11.Cu" "In13.Cu" "In15.Cu")
		(hatch none 0.5)
		(connect_pads
			(clearance 0)
		)
		(min_thickness 0.25)
		(keepout
			(tracks not_allowed)
			(vias allowed)
			(pads allowed)
			(copperpour not_allowed)
			(footprints allowed)
		)
		(placement
			(enabled no)
			(sheetname "")
		)
		(fill yes
			(thermal_gap 0.5)
			(thermal_bridge_width 0.5)
			(island_removal_mode 0)
		)
		(polygon
			(pts
				(arc
					(start 310.318404 -301.01667)
					(mid 309.665624 -301.01667)
					(end 310.318404 -301.01667)
				)
			)
		)
	)
	(zone
		(layers "B.Cu" "In4.Cu" "In6.Cu" "In11.Cu" "In13.Cu" "In15.Cu")
		(hatch none 0.5)
		(connect_pads
			(clearance 0)
		)
		(min_thickness 0.25)
		(keepout
			(tracks not_allowed)
			(vias allowed)
			(pads allowed)
			(copperpour not_allowed)
			(footprints allowed)
		)
		(placement
			(enabled no)
			(sheetname "")
		)
		(fill yes
			(thermal_gap 0.5)
			(thermal_bridge_width 0.5)
			(island_removal_mode 0)
		)
		(polygon
			(pts
				(arc
					(start 133.582156 -245.55069)
					(mid 132.929376 -245.55069)
					(end 133.582156 -245.55069)
				)
			)
		)
	)
	(zone
		(layers "B.Cu" "In4.Cu" "In6.Cu" "In11.Cu" "In13.Cu" "In15.Cu")
		(hatch none 0.5)
		(connect_pads
			(clearance 0)
		)
		(min_thickness 0.25)
		(keepout
			(tracks not_allowed)
			(vias allowed)
			(pads allowed)
			(copperpour not_allowed)
			(footprints allowed)
		)
		(placement
			(enabled no)
			(sheetname "")
		)
		(fill yes
			(thermal_gap 0.5)
			(thermal_bridge_width 0.5)
			(island_removal_mode 0)
		)
		(polygon
			(pts
				(arc
					(start 138.281156 -221.133924)
					(mid 137.628376 -221.133924)
					(end 138.281156 -221.133924)
				)
			)
		)
	)
	(zone
		(layers "B.Cu" "In4.Cu" "In6.Cu" "In11.Cu" "In13.Cu" "In15.Cu")
		(hatch none 0.5)
		(connect_pads
			(clearance 0)
		)
		(min_thickness 0.25)
		(keepout
			(tracks not_allowed)
			(vias allowed)
			(pads allowed)
			(copperpour not_allowed)
			(footprints allowed)
		)
		(placement
			(enabled no)
			(sheetname "")
		)
		(fill yes
			(thermal_gap 0.5)
			(thermal_bridge_width 0.5)
			(island_removal_mode 0)
		)
		(polygon
			(pts
				(arc
					(start 345.449652 -285.661354)
					(mid 344.796872 -285.661354)
					(end 345.449652 -285.661354)
				)
			)
		)
	)
	(zone
		(layers "B.Cu" "In4.Cu" "In6.Cu" "In11.Cu" "In13.Cu" "In15.Cu")
		(hatch none 0.5)
		(connect_pads
			(clearance 0)
		)
		(min_thickness 0.25)
		(keepout
			(tracks not_allowed)
			(vias allowed)
			(pads allowed)
			(copperpour not_allowed)
			(footprints allowed)
		)
		(placement
			(enabled no)
			(sheetname "")
		)
		(fill yes
			(thermal_gap 0.5)
			(thermal_bridge_width 0.5)
			(island_removal_mode 0)
		)
		(polygon
			(pts
				(arc
					(start 373.98452 -407.00452)
					(mid 373.28094 -407.00452)
					(end 373.98452 -407.00452)
				)
			)
		)
	)
	(zone
		(layers "B.Cu" "In4.Cu" "In6.Cu" "In11.Cu" "In13.Cu" "In15.Cu")
		(hatch none 0.5)
		(connect_pads
			(clearance 0)
		)
		(min_thickness 0.25)
		(keepout
			(tracks not_allowed)
			(vias allowed)
			(pads allowed)
			(copperpour not_allowed)
			(footprints allowed)
		)
		(placement
			(enabled no)
			(sheetname "")
		)
		(fill yes
			(thermal_gap 0.5)
			(thermal_bridge_width 0.5)
			(island_removal_mode 0)
		)
		(polygon
			(pts
				(arc
					(start 383.041652 -275.8948)
					(mid 382.388872 -275.8948)
					(end 383.041652 -275.8948)
				)
			)
		)
	)
	(zone
		(layers "B.Cu" "In4.Cu" "In6.Cu" "In11.Cu" "In13.Cu" "In15.Cu")
		(hatch none 0.5)
		(connect_pads
			(clearance 0)
		)
		(min_thickness 0.25)
		(keepout
			(tracks not_allowed)
			(vias allowed)
			(pads allowed)
			(copperpour not_allowed)
			(footprints allowed)
		)
		(placement
			(enabled no)
			(sheetname "")
		)
		(fill yes
			(thermal_gap 0.5)
			(thermal_bridge_width 0.5)
			(island_removal_mode 0)
		)
		(polygon
			(pts
				(arc
					(start 47.290736 -249.166634)
					(mid 46.637956 -249.166634)
					(end 47.290736 -249.166634)
				)
			)
		)
	)
	(zone
		(layers "B.Cu" "In4.Cu" "In6.Cu" "In11.Cu" "In13.Cu" "In15.Cu")
		(hatch none 0.5)
		(connect_pads
			(clearance 0)
		)
		(min_thickness 0.25)
		(keepout
			(tracks not_allowed)
			(vias allowed)
			(pads allowed)
			(copperpour not_allowed)
			(footprints allowed)
		)
		(placement
			(enabled no)
			(sheetname "")
		)
		(fill yes
			(thermal_gap 0.5)
			(thermal_bridge_width 0.5)
			(island_removal_mode 0)
		)
		(polygon
			(pts
				(arc
					(start 90.461084 -258.80314)
					(mid 89.808304 -258.80314)
					(end 90.461084 -258.80314)
				)
			)
		)
	)
	(zone
		(layers "B.Cu" "In4.Cu" "In6.Cu" "In11.Cu" "In13.Cu" "In15.Cu")
		(hatch none 0.5)
		(connect_pads
			(clearance 0)
		)
		(min_thickness 0.25)
		(keepout
			(tracks not_allowed)
			(vias allowed)
			(pads allowed)
			(copperpour not_allowed)
			(footprints allowed)
		)
		(placement
			(enabled no)
			(sheetname "")
		)
		(fill yes
			(thermal_gap 0.5)
			(thermal_bridge_width 0.5)
			(island_removal_mode 0)
		)
		(polygon
			(pts
				(arc
					(start 177.222404 -204.96657)
					(mid 176.569624 -204.96657)
					(end 177.222404 -204.96657)
				)
			)
		)
	)
	(zone
		(layers "B.Cu" "In4.Cu" "In6.Cu" "In11.Cu" "In13.Cu" "In15.Cu")
		(hatch none 0.5)
		(connect_pads
			(clearance 0)
		)
		(min_thickness 0.25)
		(keepout
			(tracks not_allowed)
			(vias allowed)
			(pads allowed)
			(copperpour not_allowed)
			(footprints allowed)
		)
		(placement
			(enabled no)
			(sheetname "")
		)
		(fill yes
			(thermal_gap 0.5)
			(thermal_bridge_width 0.5)
			(island_removal_mode 0)
		)
		(polygon
			(pts
				(arc
					(start 425.162472 -250.016772)
					(mid 424.509692 -250.016772)
					(end 425.162472 -250.016772)
				)
			)
		)
	)
	(zone
		(layers "B.Cu" "In4.Cu" "In6.Cu" "In11.Cu" "In13.Cu" "In15.Cu")
		(hatch none 0.5)
		(connect_pads
			(clearance 0)
		)
		(min_thickness 0.25)
		(keepout
			(tracks not_allowed)
			(vias allowed)
			(pads allowed)
			(copperpour not_allowed)
			(footprints allowed)
		)
		(placement
			(enabled no)
			(sheetname "")
		)
		(fill yes
			(thermal_gap 0.5)
			(thermal_bridge_width 0.5)
			(island_removal_mode 0)
		)
		(polygon
			(pts
				(arc
					(start 51.416204 -259.366766)
					(mid 50.763424 -259.366766)
					(end 51.416204 -259.366766)
				)
			)
		)
	)
	(zone
		(layers "B.Cu" "In4.Cu" "In6.Cu" "In11.Cu" "In13.Cu" "In15.Cu")
		(hatch none 0.5)
		(connect_pads
			(clearance 0)
		)
		(min_thickness 0.25)
		(keepout
			(tracks not_allowed)
			(vias allowed)
			(pads allowed)
			(copperpour not_allowed)
			(footprints allowed)
		)
		(placement
			(enabled no)
			(sheetname "")
		)
		(fill yes
			(thermal_gap 0.5)
			(thermal_bridge_width 0.5)
			(island_removal_mode 0)
		)
		(polygon
			(pts
				(arc
					(start 47.290736 -218.566746)
					(mid 46.637956 -218.566746)
					(end 47.290736 -218.566746)
				)
			)
		)
	)
	(zone
		(layers "B.Cu" "In4.Cu" "In6.Cu" "In11.Cu" "In13.Cu" "In15.Cu")
		(hatch none 0.5)
		(connect_pads
			(clearance 0)
		)
		(min_thickness 0.25)
		(keepout
			(tracks not_allowed)
			(vias allowed)
			(pads allowed)
			(copperpour not_allowed)
			(footprints allowed)
		)
		(placement
			(enabled no)
			(sheetname "")
		)
		(fill yes
			(thermal_gap 0.5)
			(thermal_bridge_width 0.5)
			(island_removal_mode 0)
		)
		(polygon
			(pts
				(arc
					(start 295.230804 -271.266666)
					(mid 294.578024 -271.266666)
					(end 295.230804 -271.266666)
				)
			)
		)
	)
	(zone
		(layers "B.Cu" "In4.Cu" "In6.Cu" "In11.Cu" "In13.Cu" "In15.Cu")
		(hatch none 0.5)
		(connect_pads
			(clearance 0)
		)
		(min_thickness 0.25)
		(keepout
			(tracks not_allowed)
			(vias allowed)
			(pads allowed)
			(copperpour not_allowed)
			(footprints allowed)
		)
		(placement
			(enabled no)
			(sheetname "")
		)
		(fill yes
			(thermal_gap 0.5)
			(thermal_bridge_width 0.5)
			(island_removal_mode 0)
		)
		(polygon
			(pts
				(arc
					(start 134.991602 -228.45903)
					(mid 134.338822 -228.45903)
					(end 134.991602 -228.45903)
				)
			)
		)
	)
	(zone
		(layers "B.Cu" "In4.Cu" "In6.Cu" "In11.Cu" "In13.Cu" "In15.Cu")
		(hatch none 0.5)
		(connect_pads
			(clearance 0)
		)
		(min_thickness 0.25)
		(keepout
			(tracks not_allowed)
			(vias allowed)
			(pads allowed)
			(copperpour not_allowed)
			(footprints allowed)
		)
		(placement
			(enabled no)
			(sheetname "")
		)
		(fill yes
			(thermal_gap 0.5)
			(thermal_bridge_width 0.5)
			(island_removal_mode 0)
		)
		(polygon
			(pts
				(arc
					(start 184.766204 -267.016738)
					(mid 184.113424 -267.016738)
					(end 184.766204 -267.016738)
				)
			)
		)
	)
	(zone
		(layers "B.Cu" "In4.Cu" "In6.Cu" "In11.Cu" "In13.Cu" "In15.Cu")
		(hatch none 0.5)
		(connect_pads
			(clearance 0)
		)
		(min_thickness 0.25)
		(keepout
			(tracks not_allowed)
			(vias allowed)
			(pads allowed)
			(copperpour not_allowed)
			(footprints allowed)
		)
		(placement
			(enabled no)
			(sheetname "")
		)
		(fill yes
			(thermal_gap 0.5)
			(thermal_bridge_width 0.5)
			(island_removal_mode 0)
		)
		(polygon
			(pts
				(arc
					(start 338.401406 -260.430772)
					(mid 337.748626 -260.430772)
					(end 338.401406 -260.430772)
				)
			)
		)
	)
	(zone
		(layers "B.Cu" "In4.Cu" "In6.Cu" "In11.Cu" "In13.Cu" "In15.Cu")
		(hatch none 0.5)
		(connect_pads
			(clearance 0)
		)
		(min_thickness 0.25)
		(keepout
			(tracks not_allowed)
			(vias allowed)
			(pads allowed)
			(copperpour not_allowed)
			(footprints allowed)
		)
		(placement
			(enabled no)
			(sheetname "")
		)
		(fill yes
			(thermal_gap 0.5)
			(thermal_bridge_width 0.5)
			(island_removal_mode 0)
		)
		(polygon
			(pts
				(arc
					(start 425.162472 -214.316564)
					(mid 424.509692 -214.316564)
					(end 425.162472 -214.316564)
				)
			)
		)
	)
	(zone
		(layers "B.Cu" "In4.Cu" "In6.Cu" "In11.Cu" "In13.Cu" "In15.Cu")
		(hatch none 0.5)
		(connect_pads
			(clearance 0)
		)
		(min_thickness 0.25)
		(keepout
			(tracks not_allowed)
			(vias allowed)
			(pads allowed)
			(copperpour not_allowed)
			(footprints allowed)
		)
		(placement
			(enabled no)
			(sheetname "")
		)
		(fill yes
			(thermal_gap 0.5)
			(thermal_bridge_width 0.5)
			(island_removal_mode 0)
		)
		(polygon
			(pts
				(arc
					(start 348.739206 -284.847538)
					(mid 348.086426 -284.847538)
					(end 348.739206 -284.847538)
				)
			)
		)
	)
	(zone
		(layers "B.Cu" "In4.Cu" "In6.Cu" "In11.Cu" "In13.Cu" "In15.Cu")
		(hatch none 0.5)
		(connect_pads
			(clearance 0)
		)
		(min_thickness 0.25)
		(keepout
			(tracks not_allowed)
			(vias allowed)
			(pads allowed)
			(copperpour not_allowed)
			(footprints allowed)
		)
		(placement
			(enabled no)
			(sheetname "")
		)
		(fill yes
			(thermal_gap 0.5)
			(thermal_bridge_width 0.5)
			(island_removal_mode 0)
		)
		(polygon
			(pts
				(arc
					(start 295.230804 -316.316614)
					(mid 294.578024 -316.316614)
					(end 295.230804 -316.316614)
				)
			)
		)
	)
	(zone
		(layers "B.Cu" "In4.Cu" "In6.Cu" "In11.Cu" "In13.Cu" "In15.Cu")
		(hatch none 0.5)
		(connect_pads
			(clearance 0)
		)
		(min_thickness 0.25)
		(keepout
			(tracks not_allowed)
			(vias allowed)
			(pads allowed)
			(copperpour not_allowed)
			(footprints allowed)
		)
		(placement
			(enabled no)
			(sheetname "")
		)
		(fill yes
			(thermal_gap 0.5)
			(thermal_bridge_width 0.5)
			(island_removal_mode 0)
		)
		(polygon
			(pts
				(arc
					(start 89.521284 -266.941808)
					(mid 88.868504 -266.941808)
					(end 89.521284 -266.941808)
				)
			)
		)
	)
	(zone
		(layers "B.Cu" "In4.Cu" "In6.Cu" "In11.Cu" "In13.Cu" "In15.Cu")
		(hatch none 0.5)
		(connect_pads
			(clearance 0)
		)
		(min_thickness 0.25)
		(keepout
			(tracks not_allowed)
			(vias allowed)
			(pads allowed)
			(copperpour not_allowed)
			(footprints allowed)
		)
		(placement
			(enabled no)
			(sheetname "")
		)
		(fill yes
			(thermal_gap 0.5)
			(thermal_bridge_width 0.5)
			(island_removal_mode 0)
		)
		(polygon
			(pts
				(arc
					(start 383.401824 -240.667286)
					(mid 382.749044 -240.667286)
					(end 383.401824 -240.667286)
				)
			)
		)
	)
	(zone
		(layers "B.Cu" "In4.Cu" "In6.Cu" "In11.Cu" "In13.Cu" "In15.Cu")
		(hatch none 0.5)
		(connect_pads
			(clearance 0)
		)
		(min_thickness 0.25)
		(keepout
			(tracks not_allowed)
			(vias allowed)
			(pads allowed)
			(copperpour not_allowed)
			(footprints allowed)
		)
		(placement
			(enabled no)
			(sheetname "")
		)
		(fill yes
			(thermal_gap 0.5)
			(thermal_bridge_width 0.5)
			(island_removal_mode 0)
		)
		(polygon
			(pts
				(arc
					(start 314.418472 -231.316784)
					(mid 313.765692 -231.316784)
					(end 314.418472 -231.316784)
				)
			)
		)
	)
	(zone
		(layers "B.Cu" "In4.Cu" "In6.Cu" "In11.Cu" "In13.Cu" "In15.Cu")
		(hatch none 0.5)
		(connect_pads
			(clearance 0)
		)
		(min_thickness 0.25)
		(keepout
			(tracks not_allowed)
			(vias allowed)
			(pads allowed)
			(copperpour not_allowed)
			(footprints allowed)
		)
		(placement
			(enabled no)
			(sheetname "")
		)
		(fill yes
			(thermal_gap 0.5)
			(thermal_bridge_width 0.5)
			(island_removal_mode 0)
		)
		(polygon
			(pts
				(arc
					(start 51.390804 -233.016806)
					(mid 50.738024 -233.016806)
					(end 51.390804 -233.016806)
				)
			)
		)
	)
	(zone
		(layers "B.Cu" "In4.Cu" "In6.Cu" "In11.Cu" "In13.Cu" "In15.Cu")
		(hatch none 0.5)
		(connect_pads
			(clearance 0)
		)
		(min_thickness 0.25)
		(keepout
			(tracks not_allowed)
			(vias allowed)
			(pads allowed)
			(copperpour not_allowed)
			(footprints allowed)
		)
		(placement
			(enabled no)
			(sheetname "")
		)
		(fill yes
			(thermal_gap 0.5)
			(thermal_bridge_width 0.5)
			(island_removal_mode 0)
		)
		(polygon
			(pts
				(arc
					(start 136.871202 -221.94774)
					(mid 136.218422 -221.94774)
					(end 136.871202 -221.94774)
				)
			)
		)
	)
	(zone
		(layers "B.Cu" "In4.Cu" "In6.Cu" "In11.Cu" "In13.Cu" "In15.Cu")
		(hatch none 0.5)
		(connect_pads
			(clearance 0)
		)
		(min_thickness 0.25)
		(keepout
			(tracks not_allowed)
			(vias allowed)
			(pads allowed)
			(copperpour not_allowed)
			(footprints allowed)
		)
		(placement
			(enabled no)
			(sheetname "")
		)
		(fill yes
			(thermal_gap 0.5)
			(thermal_bridge_width 0.5)
			(island_removal_mode 0)
		)
		(polygon
			(pts
				(arc
					(start 135.101584 -259.616956)
					(mid 134.448804 -259.616956)
					(end 135.101584 -259.616956)
				)
			)
		)
	)
	(zone
		(layers "B.Cu" "In4.Cu" "In6.Cu" "In11.Cu" "In13.Cu" "In15.Cu")
		(hatch none 0.5)
		(connect_pads
			(clearance 0)
		)
		(min_thickness 0.25)
		(keepout
			(tracks not_allowed)
			(vias allowed)
			(pads allowed)
			(copperpour not_allowed)
			(footprints allowed)
		)
		(placement
			(enabled no)
			(sheetname "")
		)
		(fill yes
			(thermal_gap 0.5)
			(thermal_bridge_width 0.5)
			(island_removal_mode 0)
		)
		(polygon
			(pts
				(arc
					(start 344.153998 -400.858228)
					(mid 343.450418 -400.858228)
					(end 344.153998 -400.858228)
				)
			)
		)
	)
	(zone
		(layers "B.Cu" "In4.Cu" "In6.Cu" "In11.Cu" "In13.Cu" "In15.Cu")
		(hatch none 0.5)
		(connect_pads
			(clearance 0)
		)
		(min_thickness 0.25)
		(keepout
			(tracks not_allowed)
			(vias allowed)
			(pads allowed)
			(copperpour not_allowed)
			(footprints allowed)
		)
		(placement
			(enabled no)
			(sheetname "")
		)
		(fill yes
			(thermal_gap 0.5)
			(thermal_bridge_width 0.5)
			(island_removal_mode 0)
		)
		(polygon
			(pts
				(arc
					(start 91.400884 -284.847538)
					(mid 90.748104 -284.847538)
					(end 91.400884 -284.847538)
				)
			)
		)
	)
	(zone
		(layers "B.Cu" "In4.Cu" "In6.Cu" "In11.Cu" "In13.Cu" "In15.Cu")
		(hatch none 0.5)
		(connect_pads
			(clearance 0)
		)
		(min_thickness 0.25)
		(keepout
			(tracks not_allowed)
			(vias allowed)
			(pads allowed)
			(copperpour not_allowed)
			(footprints allowed)
		)
		(placement
			(enabled no)
			(sheetname "")
		)
		(fill yes
			(thermal_gap 0.5)
			(thermal_bridge_width 0.5)
			(island_removal_mode 0)
		)
		(polygon
			(pts
				(arc
					(start 382.93167 -241.481102)
					(mid 382.27889 -241.481102)
					(end 382.93167 -241.481102)
				)
			)
		)
	)
	(zone
		(layers "B.Cu" "In4.Cu" "In6.Cu" "In11.Cu" "In13.Cu" "In15.Cu")
		(hatch none 0.5)
		(connect_pads
			(clearance 0)
		)
		(min_thickness 0.25)
		(keepout
			(tracks not_allowed)
			(vias allowed)
			(pads allowed)
			(copperpour not_allowed)
			(footprints allowed)
		)
		(placement
			(enabled no)
			(sheetname "")
		)
		(fill yes
			(thermal_gap 0.5)
			(thermal_bridge_width 0.5)
			(island_removal_mode 0)
		)
		(polygon
			(pts
				(arc
					(start 421.062404 -293.366698)
					(mid 420.409624 -293.366698)
					(end 421.062404 -293.366698)
				)
			)
		)
	)
	(zone
		(layers "B.Cu" "In4.Cu" "In6.Cu" "In11.Cu" "In13.Cu" "In15.Cu")
		(hatch none 0.5)
		(connect_pads
			(clearance 0)
		)
		(min_thickness 0.25)
		(keepout
			(tracks not_allowed)
			(vias allowed)
			(pads allowed)
			(copperpour not_allowed)
			(footprints allowed)
		)
		(placement
			(enabled no)
			(sheetname "")
		)
		(fill yes
			(thermal_gap 0.5)
			(thermal_bridge_width 0.5)
			(island_removal_mode 0)
		)
		(polygon
			(pts
				(arc
					(start 299.330872 -248.31675)
					(mid 298.678092 -248.31675)
					(end 299.330872 -248.31675)
				)
			)
		)
	)
	(zone
		(layers "B.Cu" "In4.Cu" "In6.Cu" "In11.Cu" "In13.Cu" "In15.Cu")
		(hatch none 0.5)
		(connect_pads
			(clearance 0)
		)
		(min_thickness 0.25)
		(keepout
			(tracks not_allowed)
			(vias allowed)
			(pads allowed)
			(copperpour not_allowed)
			(footprints allowed)
		)
		(placement
			(enabled no)
			(sheetname "")
		)
		(fill yes
			(thermal_gap 0.5)
			(thermal_bridge_width 0.5)
			(island_removal_mode 0)
		)
		(polygon
			(pts
				(arc
					(start 120.534938 -286.475424)
					(mid 119.882158 -286.475424)
					(end 120.534938 -286.475424)
				)
			)
		)
	)
	(zone
		(layers "B.Cu" "In4.Cu" "In6.Cu" "In11.Cu" "In13.Cu" "In15.Cu")
		(hatch none 0.5)
		(connect_pads
			(clearance 0)
		)
		(min_thickness 0.25)
		(keepout
			(tracks not_allowed)
			(vias allowed)
			(pads allowed)
			(copperpour not_allowed)
			(footprints allowed)
		)
		(placement
			(enabled no)
			(sheetname "")
		)
		(fill yes
			(thermal_gap 0.5)
			(thermal_bridge_width 0.5)
			(island_removal_mode 0)
		)
		(polygon
			(pts
				(arc
					(start 337.461352 -263.686544)
					(mid 336.808572 -263.686544)
					(end 337.461352 -263.686544)
				)
			)
		)
	)
	(zone
		(layers "B.Cu" "In4.Cu" "In6.Cu" "In11.Cu" "In13.Cu" "In15.Cu")
		(hatch none 0.5)
		(connect_pads
			(clearance 0)
		)
		(min_thickness 0.25)
		(keepout
			(tracks not_allowed)
			(vias allowed)
			(pads allowed)
			(copperpour not_allowed)
			(footprints allowed)
		)
		(placement
			(enabled no)
			(sheetname "")
		)
		(fill yes
			(thermal_gap 0.5)
			(thermal_bridge_width 0.5)
			(island_removal_mode 0)
		)
		(polygon
			(pts
				(arc
					(start 162.109404 -306.116736)
					(mid 161.456624 -306.116736)
					(end 162.109404 -306.116736)
				)
			)
		)
	)
	(zone
		(layers "B.Cu" "In4.Cu" "In6.Cu" "In11.Cu" "In13.Cu" "In15.Cu")
		(hatch none 0.5)
		(connect_pads
			(clearance 0)
		)
		(min_thickness 0.25)
		(keepout
			(tracks not_allowed)
			(vias allowed)
			(pads allowed)
			(copperpour not_allowed)
			(footprints allowed)
		)
		(placement
			(enabled no)
			(sheetname "")
		)
		(fill yes
			(thermal_gap 0.5)
			(thermal_bridge_width 0.5)
			(island_removal_mode 0)
		)
		(polygon
			(pts
				(arc
					(start 382.101852 -261.244842)
					(mid 381.449072 -261.244842)
					(end 382.101852 -261.244842)
				)
			)
		)
	)
	(zone
		(layers "B.Cu" "In4.Cu" "In6.Cu" "In11.Cu" "In13.Cu" "In15.Cu")
		(hatch none 0.5)
		(connect_pads
			(clearance 0)
		)
		(min_thickness 0.25)
		(keepout
			(tracks not_allowed)
			(vias allowed)
			(pads allowed)
			(copperpour not_allowed)
			(footprints allowed)
		)
		(placement
			(enabled no)
			(sheetname "")
		)
		(fill yes
			(thermal_gap 0.5)
			(thermal_bridge_width 0.5)
			(island_removal_mode 0)
		)
		(polygon
			(pts
				(arc
					(start 338.871052 -275.8948)
					(mid 338.218272 -275.8948)
					(end 338.871052 -275.8948)
				)
			)
		)
	)
	(zone
		(layers "B.Cu" "In4.Cu" "In6.Cu" "In11.Cu" "In13.Cu" "In15.Cu")
		(hatch none 0.5)
		(connect_pads
			(clearance 0)
		)
		(min_thickness 0.25)
		(keepout
			(tracks not_allowed)
			(vias allowed)
			(pads allowed)
			(copperpour not_allowed)
			(footprints allowed)
		)
		(placement
			(enabled no)
			(sheetname "")
		)
		(fill yes
			(thermal_gap 0.5)
			(thermal_bridge_width 0.5)
			(island_removal_mode 0)
		)
		(polygon
			(pts
				(arc
					(start 120.064784 -285.661354)
					(mid 119.412004 -285.661354)
					(end 120.064784 -285.661354)
				)
			)
		)
	)
	(zone
		(layers "B.Cu" "In4.Cu" "In6.Cu" "In11.Cu" "In13.Cu" "In15.Cu")
		(hatch none 0.5)
		(connect_pads
			(clearance 0)
		)
		(min_thickness 0.25)
		(keepout
			(tracks not_allowed)
			(vias allowed)
			(pads allowed)
			(copperpour not_allowed)
			(footprints allowed)
		)
		(placement
			(enabled no)
			(sheetname "")
		)
		(fill yes
			(thermal_gap 0.5)
			(thermal_bridge_width 0.5)
			(island_removal_mode 0)
		)
		(polygon
			(pts
				(arc
					(start 295.230804 -210.066636)
					(mid 294.578024 -210.066636)
					(end 295.230804 -210.066636)
				)
			)
		)
	)
	(zone
		(layers "B.Cu" "In4.Cu" "In6.Cu" "In11.Cu" "In13.Cu" "In15.Cu")
		(hatch none 0.5)
		(connect_pads
			(clearance 0)
		)
		(min_thickness 0.25)
		(keepout
			(tracks not_allowed)
			(vias allowed)
			(pads allowed)
			(copperpour not_allowed)
			(footprints allowed)
		)
		(placement
			(enabled no)
			(sheetname "")
		)
		(fill yes
			(thermal_gap 0.5)
			(thermal_bridge_width 0.5)
			(island_removal_mode 0)
		)
		(polygon
			(pts
				(arc
					(start 349.679006 -286.475424)
					(mid 349.026226 -286.475424)
					(end 349.679006 -286.475424)
				)
			)
		)
	)
	(zone
		(layers "B.Cu" "In4.Cu" "In6.Cu" "In11.Cu" "In13.Cu" "In15.Cu")
		(hatch none 0.5)
		(connect_pads
			(clearance 0)
		)
		(min_thickness 0.25)
		(keepout
			(tracks not_allowed)
			(vias allowed)
			(pads allowed)
			(copperpour not_allowed)
			(footprints allowed)
		)
		(placement
			(enabled no)
			(sheetname "")
		)
		(fill yes
			(thermal_gap 0.5)
			(thermal_bridge_width 0.5)
			(island_removal_mode 0)
		)
		(polygon
			(pts
				(arc
					(start 295.230804 -235.566712)
					(mid 294.578024 -235.566712)
					(end 295.230804 -235.566712)
				)
			)
		)
	)
	(zone
		(layers "B.Cu" "In4.Cu" "In6.Cu" "In11.Cu" "In13.Cu" "In15.Cu")
		(hatch none 0.5)
		(connect_pads
			(clearance 0)
		)
		(min_thickness 0.25)
		(keepout
			(tracks not_allowed)
			(vias allowed)
			(pads allowed)
			(copperpour not_allowed)
			(footprints allowed)
		)
		(placement
			(enabled no)
			(sheetname "")
		)
		(fill yes
			(thermal_gap 0.5)
			(thermal_bridge_width 0.5)
			(island_removal_mode 0)
		)
		(polygon
			(pts
				(arc
					(start 425.162472 -311.216548)
					(mid 424.509692 -311.216548)
					(end 425.162472 -311.216548)
				)
			)
		)
	)
	(zone
		(layers "B.Cu" "In4.Cu" "In6.Cu" "In11.Cu" "In13.Cu" "In15.Cu")
		(hatch none 0.5)
		(connect_pads
			(clearance 0)
		)
		(min_thickness 0.25)
		(keepout
			(tracks not_allowed)
			(vias allowed)
			(pads allowed)
			(copperpour not_allowed)
			(footprints allowed)
		)
		(placement
			(enabled no)
			(sheetname "")
		)
		(fill yes
			(thermal_gap 0.5)
			(thermal_bridge_width 0.5)
			(island_removal_mode 0)
		)
		(polygon
			(pts
				(arc
					(start 382.931924 -246.364506)
					(mid 382.279144 -246.364506)
					(end 382.931924 -246.364506)
				)
			)
		)
	)
	(zone
		(layers "B.Cu" "In4.Cu" "In6.Cu" "In11.Cu" "In13.Cu" "In15.Cu")
		(hatch none 0.5)
		(connect_pads
			(clearance 0)
		)
		(min_thickness 0.25)
		(keepout
			(tracks not_allowed)
			(vias allowed)
			(pads allowed)
			(copperpour not_allowed)
			(footprints allowed)
		)
		(placement
			(enabled no)
			(sheetname "")
		)
		(fill yes
			(thermal_gap 0.5)
			(thermal_bridge_width 0.5)
			(island_removal_mode 0)
		)
		(polygon
			(pts
				(arc
					(start 88.471756 -247.178322)
					(mid 87.818976 -247.178322)
					(end 88.471756 -247.178322)
				)
			)
		)
	)
	(zone
		(layers "B.Cu" "In4.Cu" "In6.Cu" "In11.Cu" "In13.Cu" "In15.Cu")
		(hatch none 0.5)
		(connect_pads
			(clearance 0)
		)
		(min_thickness 0.25)
		(keepout
			(tracks not_allowed)
			(vias allowed)
			(pads allowed)
			(copperpour not_allowed)
			(footprints allowed)
		)
		(placement
			(enabled no)
			(sheetname "")
		)
		(fill yes
			(thermal_gap 0.5)
			(thermal_bridge_width 0.5)
			(island_removal_mode 0)
		)
		(polygon
			(pts
				(arc
					(start 299.330872 -217.716608)
					(mid 298.678092 -217.716608)
					(end 299.330872 -217.716608)
				)
			)
		)
	)
	(zone
		(layers "B.Cu" "In4.Cu" "In6.Cu" "In11.Cu" "In13.Cu" "In15.Cu")
		(hatch none 0.5)
		(connect_pads
			(clearance 0)
		)
		(min_thickness 0.25)
		(keepout
			(tracks not_allowed)
			(vias allowed)
			(pads allowed)
			(copperpour not_allowed)
			(footprints allowed)
		)
		(placement
			(enabled no)
			(sheetname "")
		)
		(fill yes
			(thermal_gap 0.5)
			(thermal_bridge_width 0.5)
			(island_removal_mode 0)
		)
		(polygon
			(pts
				(arc
					(start 299.330872 -236.416596)
					(mid 298.678092 -236.416596)
					(end 299.330872 -236.416596)
				)
			)
		)
	)
	(zone
		(layers "B.Cu" "In4.Cu" "In6.Cu" "In11.Cu" "In13.Cu" "In15.Cu")
		(hatch none 0.5)
		(connect_pads
			(clearance 0)
		)
		(min_thickness 0.25)
		(keepout
			(tracks not_allowed)
			(vias allowed)
			(pads allowed)
			(copperpour not_allowed)
			(footprints allowed)
		)
		(placement
			(enabled no)
			(sheetname "")
		)
		(fill yes
			(thermal_gap 0.5)
			(thermal_bridge_width 0.5)
			(island_removal_mode 0)
		)
		(polygon
			(pts
				(arc
					(start 381.162052 -277.522432)
					(mid 380.509272 -277.522432)
					(end 381.162052 -277.522432)
				)
			)
		)
	)
	(zone
		(layers "B.Cu" "In4.Cu" "In6.Cu" "In11.Cu" "In13.Cu" "In15.Cu")
		(hatch none 0.5)
		(connect_pads
			(clearance 0)
		)
		(min_thickness 0.25)
		(keepout
			(tracks not_allowed)
			(vias allowed)
			(pads allowed)
			(copperpour not_allowed)
			(footprints allowed)
		)
		(placement
			(enabled no)
			(sheetname "")
		)
		(fill yes
			(thermal_gap 0.5)
			(thermal_bridge_width 0.5)
			(island_removal_mode 0)
		)
		(polygon
			(pts
				(arc
					(start 90.351356 -240.667286)
					(mid 89.698576 -240.667286)
					(end 90.351356 -240.667286)
				)
			)
		)
	)
	(zone
		(layers "B.Cu" "In4.Cu" "In6.Cu" "In11.Cu" "In13.Cu" "In15.Cu")
		(hatch none 0.5)
		(connect_pads
			(clearance 0)
		)
		(min_thickness 0.25)
		(keepout
			(tracks not_allowed)
			(vias allowed)
			(pads allowed)
			(copperpour not_allowed)
			(footprints allowed)
		)
		(placement
			(enabled no)
			(sheetname "")
		)
		(fill yes
			(thermal_gap 0.5)
			(thermal_bridge_width 0.5)
			(island_removal_mode 0)
		)
		(polygon
			(pts
				(arc
					(start 50.583084 -17.61236)
					(mid 49.879504 -17.61236)
					(end 50.583084 -17.61236)
				)
			)
		)
	)
	(zone
		(layers "B.Cu" "In4.Cu" "In6.Cu" "In11.Cu" "In13.Cu" "In15.Cu")
		(hatch none 0.5)
		(connect_pads
			(clearance 0)
		)
		(min_thickness 0.25)
		(keepout
			(tracks not_allowed)
			(vias allowed)
			(pads allowed)
			(copperpour not_allowed)
			(footprints allowed)
		)
		(placement
			(enabled no)
			(sheetname "")
		)
		(fill yes
			(thermal_gap 0.5)
			(thermal_bridge_width 0.5)
			(island_removal_mode 0)
		)
		(polygon
			(pts
				(arc
					(start 364.605824 -224.389442)
					(mid 363.953044 -224.389442)
					(end 364.605824 -224.389442)
				)
			)
		)
	)
	(zone
		(layers "B.Cu" "In4.Cu" "In6.Cu" "In11.Cu" "In13.Cu" "In15.Cu")
		(hatch none 0.5)
		(connect_pads
			(clearance 0)
		)
		(min_thickness 0.25)
		(keepout
			(tracks not_allowed)
			(vias allowed)
			(pads allowed)
			(copperpour not_allowed)
			(footprints allowed)
		)
		(placement
			(enabled no)
			(sheetname "")
		)
		(fill yes
			(thermal_gap 0.5)
			(thermal_bridge_width 0.5)
			(island_removal_mode 0)
		)
		(polygon
			(pts
				(arc
					(start 122.414538 -286.475424)
					(mid 121.761758 -286.475424)
					(end 122.414538 -286.475424)
				)
			)
		)
	)
	(zone
		(layers "B.Cu" "In4.Cu" "In6.Cu" "In11.Cu" "In13.Cu" "In15.Cu")
		(hatch none 0.5)
		(connect_pads
			(clearance 0)
		)
		(min_thickness 0.25)
		(keepout
			(tracks not_allowed)
			(vias allowed)
			(pads allowed)
			(copperpour not_allowed)
			(footprints allowed)
		)
		(placement
			(enabled no)
			(sheetname "")
		)
		(fill yes
			(thermal_gap 0.5)
			(thermal_bridge_width 0.5)
			(island_removal_mode 0)
		)
		(polygon
			(pts
				(arc
					(start 337.461352 -253.919736)
					(mid 336.808572 -253.919736)
					(end 337.461352 -253.919736)
				)
			)
		)
	)
	(zone
		(layers "B.Cu" "In4.Cu" "In6.Cu" "In11.Cu" "In13.Cu" "In15.Cu")
		(hatch none 0.5)
		(connect_pads
			(clearance 0)
		)
		(min_thickness 0.25)
		(keepout
			(tracks not_allowed)
			(vias allowed)
			(pads allowed)
			(copperpour not_allowed)
			(footprints allowed)
		)
		(placement
			(enabled no)
			(sheetname "")
		)
		(fill yes
			(thermal_gap 0.5)
			(thermal_bridge_width 0.5)
			(island_removal_mode 0)
		)
		(polygon
			(pts
				(arc
					(start 90.930984 -275.8948)
					(mid 90.278204 -275.8948)
					(end 90.930984 -275.8948)
				)
			)
		)
	)
	(zone
		(layers "B.Cu" "In4.Cu" "In6.Cu" "In11.Cu" "In13.Cu" "In15.Cu")
		(hatch none 0.5)
		(connect_pads
			(clearance 0)
		)
		(min_thickness 0.25)
		(keepout
			(tracks not_allowed)
			(vias allowed)
			(pads allowed)
			(copperpour not_allowed)
			(footprints allowed)
		)
		(placement
			(enabled no)
			(sheetname "")
		)
		(fill yes
			(thermal_gap 0.5)
			(thermal_bridge_width 0.5)
			(island_removal_mode 0)
		)
		(polygon
			(pts
				(arc
					(start 432.706272 -244.916706)
					(mid 432.053492 -244.916706)
					(end 432.706272 -244.916706)
				)
			)
		)
	)
	(zone
		(layers "B.Cu" "In4.Cu" "In6.Cu" "In11.Cu" "In13.Cu" "In15.Cu")
		(hatch none 0.5)
		(connect_pads
			(clearance 0)
		)
		(min_thickness 0.25)
		(keepout
			(tracks not_allowed)
			(vias allowed)
			(pads allowed)
			(copperpour not_allowed)
			(footprints allowed)
		)
		(placement
			(enabled no)
			(sheetname "")
		)
		(fill yes
			(thermal_gap 0.5)
			(thermal_bridge_width 0.5)
			(island_removal_mode 0)
		)
		(polygon
			(pts
				(arc
					(start 336.411824 -247.178322)
					(mid 335.759044 -247.178322)
					(end 336.411824 -247.178322)
				)
			)
		)
	)
	(zone
		(layers "B.Cu" "In4.Cu" "In6.Cu" "In11.Cu" "In13.Cu" "In15.Cu")
		(hatch none 0.5)
		(connect_pads
			(clearance 0)
		)
		(min_thickness 0.25)
		(keepout
			(tracks not_allowed)
			(vias allowed)
			(pads allowed)
			(copperpour not_allowed)
			(footprints allowed)
		)
		(placement
			(enabled no)
			(sheetname "")
		)
		(fill yes
			(thermal_gap 0.5)
			(thermal_bridge_width 0.5)
			(island_removal_mode 0)
		)
		(polygon
			(pts
				(arc
					(start 295.230804 -209.216752)
					(mid 294.578024 -209.216752)
					(end 295.230804 -209.216752)
				)
			)
		)
	)
	(zone
		(layers "B.Cu" "In4.Cu" "In6.Cu" "In11.Cu" "In13.Cu" "In15.Cu")
		(hatch none 0.5)
		(connect_pads
			(clearance 0)
		)
		(min_thickness 0.25)
		(keepout
			(tracks not_allowed)
			(vias allowed)
			(pads allowed)
			(copperpour not_allowed)
			(footprints allowed)
		)
		(placement
			(enabled no)
			(sheetname "")
		)
		(fill yes
			(thermal_gap 0.5)
			(thermal_bridge_width 0.5)
			(island_removal_mode 0)
		)
		(polygon
			(pts
				(arc
					(start 366.485424 -224.389442)
					(mid 365.832644 -224.389442)
					(end 366.485424 -224.389442)
				)
			)
		)
	)
	(zone
		(layers "B.Cu" "In4.Cu" "In6.Cu" "In11.Cu" "In13.Cu" "In15.Cu")
		(hatch none 0.5)
		(connect_pads
			(clearance 0)
		)
		(min_thickness 0.25)
		(keepout
			(tracks not_allowed)
			(vias allowed)
			(pads allowed)
			(copperpour not_allowed)
			(footprints allowed)
		)
		(placement
			(enabled no)
			(sheetname "")
		)
		(fill yes
			(thermal_gap 0.5)
			(thermal_bridge_width 0.5)
			(island_removal_mode 0)
		)
		(polygon
			(pts
				(arc
					(start 383.401824 -243.922804)
					(mid 382.749044 -243.922804)
					(end 383.401824 -243.922804)
				)
			)
		)
	)
	(zone
		(layers "B.Cu" "In4.Cu" "In6.Cu" "In11.Cu" "In13.Cu" "In15.Cu")
		(hatch none 0.5)
		(connect_pads
			(clearance 0)
		)
		(min_thickness 0.25)
		(keepout
			(tracks not_allowed)
			(vias allowed)
			(pads allowed)
			(copperpour not_allowed)
			(footprints allowed)
		)
		(placement
			(enabled no)
			(sheetname "")
		)
		(fill yes
			(thermal_gap 0.5)
			(thermal_bridge_width 0.5)
			(island_removal_mode 0)
		)
		(polygon
			(pts
				(arc
					(start 421.062404 -297.616626)
					(mid 420.409624 -297.616626)
					(end 421.062404 -297.616626)
				)
			)
		)
	)
	(zone
		(layers "B.Cu" "In4.Cu" "In6.Cu" "In11.Cu" "In13.Cu" "In15.Cu")
		(hatch none 0.5)
		(connect_pads
			(clearance 0)
		)
		(min_thickness 0.25)
		(keepout
			(tracks not_allowed)
			(vias allowed)
			(pads allowed)
			(copperpour not_allowed)
			(footprints allowed)
		)
		(placement
			(enabled no)
			(sheetname "")
		)
		(fill yes
			(thermal_gap 0.5)
			(thermal_bridge_width 0.5)
			(island_removal_mode 0)
		)
		(polygon
			(pts
				(arc
					(start 425.162472 -273.816572)
					(mid 424.509692 -273.816572)
					(end 425.162472 -273.816572)
				)
			)
		)
	)
	(zone
		(layers "B.Cu" "In4.Cu" "In6.Cu" "In11.Cu" "In13.Cu" "In15.Cu")
		(hatch none 0.5)
		(connect_pads
			(clearance 0)
		)
		(min_thickness 0.25)
		(keepout
			(tracks not_allowed)
			(vias allowed)
			(pads allowed)
			(copperpour not_allowed)
			(footprints allowed)
		)
		(placement
			(enabled no)
			(sheetname "")
		)
		(fill yes
			(thermal_gap 0.5)
			(thermal_bridge_width 0.5)
			(island_removal_mode 0)
		)
		(polygon
			(pts
				(arc
					(start 344.692224 -49.859692)
					(mid 344.039444 -49.859692)
					(end 344.692224 -49.859692)
				)
			)
		)
	)
	(zone
		(layers "B.Cu" "In4.Cu" "In6.Cu" "In11.Cu" "In13.Cu" "In15.Cu")
		(hatch none 0.5)
		(connect_pads
			(clearance 0)
		)
		(min_thickness 0.25)
		(keepout
			(tracks not_allowed)
			(vias allowed)
			(pads allowed)
			(copperpour not_allowed)
			(footprints allowed)
		)
		(placement
			(enabled no)
			(sheetname "")
		)
		(fill yes
			(thermal_gap 0.5)
			(thermal_bridge_width 0.5)
			(island_removal_mode 0)
		)
		(polygon
			(pts
				(arc
					(start 128.993138 -284.847538)
					(mid 128.340358 -284.847538)
					(end 128.993138 -284.847538)
				)
			)
		)
	)
	(zone
		(layers "B.Cu" "In4.Cu" "In6.Cu" "In11.Cu" "In13.Cu" "In15.Cu")
		(hatch none 0.5)
		(connect_pads
			(clearance 0)
		)
		(min_thickness 0.25)
		(keepout
			(tracks not_allowed)
			(vias allowed)
			(pads allowed)
			(copperpour not_allowed)
			(footprints allowed)
		)
		(placement
			(enabled no)
			(sheetname "")
		)
		(fill yes
			(thermal_gap 0.5)
			(thermal_bridge_width 0.5)
			(island_removal_mode 0)
		)
		(polygon
			(pts
				(arc
					(start 109.147356 -224.389442)
					(mid 108.494576 -224.389442)
					(end 109.147356 -224.389442)
				)
			)
		)
	)
	(zone
		(layers "B.Cu" "In4.Cu" "In6.Cu" "In11.Cu" "In13.Cu" "In15.Cu")
		(hatch none 0.5)
		(connect_pads
			(clearance 0)
		)
		(min_thickness 0.25)
		(keepout
			(tracks not_allowed)
			(vias allowed)
			(pads allowed)
			(copperpour not_allowed)
			(footprints allowed)
		)
		(placement
			(enabled no)
			(sheetname "")
		)
		(fill yes
			(thermal_gap 0.5)
			(thermal_bridge_width 0.5)
			(island_removal_mode 0)
		)
		(polygon
			(pts
				(arc
					(start 95.629984 -285.661354)
					(mid 94.977204 -285.661354)
					(end 95.629984 -285.661354)
				)
			)
		)
	)
	(zone
		(layers "B.Cu" "In4.Cu" "In6.Cu" "In11.Cu" "In13.Cu" "In15.Cu")
		(hatch none 0.5)
		(connect_pads
			(clearance 0)
		)
		(min_thickness 0.25)
		(keepout
			(tracks not_allowed)
			(vias allowed)
			(pads allowed)
			(copperpour not_allowed)
			(footprints allowed)
		)
		(placement
			(enabled no)
			(sheetname "")
		)
		(fill yes
			(thermal_gap 0.5)
			(thermal_bridge_width 0.5)
			(island_removal_mode 0)
		)
		(polygon
			(pts
				(arc
					(start 180.666136 -267.866622)
					(mid 180.013356 -267.866622)
					(end 180.666136 -267.866622)
				)
			)
		)
	)
	(zone
		(layers "B.Cu" "In4.Cu" "In6.Cu" "In11.Cu" "In13.Cu" "In15.Cu")
		(hatch none 0.5)
		(connect_pads
			(clearance 0)
		)
		(min_thickness 0.25)
		(keepout
			(tracks not_allowed)
			(vias allowed)
			(pads allowed)
			(copperpour not_allowed)
			(footprints allowed)
		)
		(placement
			(enabled no)
			(sheetname "")
		)
		(fill yes
			(thermal_gap 0.5)
			(thermal_bridge_width 0.5)
			(island_removal_mode 0)
		)
		(polygon
			(pts
				(arc
					(start 338.291424 -245.55069)
					(mid 337.638644 -245.55069)
					(end 338.291424 -245.55069)
				)
			)
		)
	)
	(zone
		(layers "B.Cu" "In4.Cu" "In6.Cu" "In11.Cu" "In13.Cu" "In15.Cu")
		(hatch none 0.5)
		(connect_pads
			(clearance 0)
		)
		(min_thickness 0.25)
		(keepout
			(tracks not_allowed)
			(vias allowed)
			(pads allowed)
			(copperpour not_allowed)
			(footprints allowed)
		)
		(placement
			(enabled no)
			(sheetname "")
		)
		(fill yes
			(thermal_gap 0.5)
			(thermal_bridge_width 0.5)
			(island_removal_mode 0)
		)
		(polygon
			(pts
				(arc
					(start 385.281424 -221.133924)
					(mid 384.628644 -221.133924)
					(end 385.281424 -221.133924)
				)
			)
		)
	)
	(zone
		(layers "B.Cu" "In4.Cu" "In6.Cu" "In11.Cu" "In13.Cu" "In15.Cu")
		(hatch none 0.5)
		(connect_pads
			(clearance 0)
		)
		(min_thickness 0.25)
		(keepout
			(tracks not_allowed)
			(vias allowed)
			(pads allowed)
			(copperpour not_allowed)
			(footprints allowed)
		)
		(placement
			(enabled no)
			(sheetname "")
		)
		(fill yes
			(thermal_gap 0.5)
			(thermal_bridge_width 0.5)
			(island_removal_mode 0)
		)
		(polygon
			(pts
				(arc
					(start 338.401152 -268.569694)
					(mid 337.748372 -268.569694)
					(end 338.401152 -268.569694)
				)
			)
		)
	)
	(zone
		(layers "B.Cu" "In4.Cu" "In6.Cu" "In11.Cu" "In13.Cu" "In15.Cu")
		(hatch none 0.5)
		(connect_pads
			(clearance 0)
		)
		(min_thickness 0.25)
		(keepout
			(tracks not_allowed)
			(vias allowed)
			(pads allowed)
			(copperpour not_allowed)
			(footprints allowed)
		)
		(placement
			(enabled no)
			(sheetname "")
		)
		(fill yes
			(thermal_gap 0.5)
			(thermal_bridge_width 0.5)
			(island_removal_mode 0)
		)
		(polygon
			(pts
				(arc
					(start 104.088184 -285.661354)
					(mid 103.435404 -285.661354)
					(end 104.088184 -285.661354)
				)
			)
		)
	)
	(zone
		(layers "B.Cu" "In4.Cu" "In6.Cu" "In11.Cu" "In13.Cu" "In15.Cu")
		(hatch none 0.5)
		(connect_pads
			(clearance 0)
		)
		(min_thickness 0.25)
		(keepout
			(tracks not_allowed)
			(vias allowed)
			(pads allowed)
			(copperpour not_allowed)
			(footprints allowed)
		)
		(placement
			(enabled no)
			(sheetname "")
		)
		(fill yes
			(thermal_gap 0.5)
			(thermal_bridge_width 0.5)
			(island_removal_mode 0)
		)
		(polygon
			(pts
				(arc
					(start 381.992124 -230.086662)
					(mid 381.339344 -230.086662)
					(end 381.992124 -230.086662)
				)
			)
		)
	)
	(zone
		(layers "B.Cu" "In4.Cu" "In6.Cu" "In11.Cu" "In13.Cu" "In15.Cu")
		(hatch none 0.5)
		(connect_pads
			(clearance 0)
		)
		(min_thickness 0.25)
		(keepout
			(tracks not_allowed)
			(vias allowed)
			(pads allowed)
			(copperpour not_allowed)
			(footprints allowed)
		)
		(placement
			(enabled no)
			(sheetname "")
		)
		(fill yes
			(thermal_gap 0.5)
			(thermal_bridge_width 0.5)
			(island_removal_mode 0)
		)
		(polygon
			(pts
				(arc
					(start 88.941402 -246.364506)
					(mid 88.288622 -246.364506)
					(end 88.941402 -246.364506)
				)
			)
		)
	)
	(zone
		(layers "B.Cu" "In4.Cu" "In6.Cu" "In11.Cu" "In13.Cu" "In15.Cu")
		(hatch none 0.5)
		(connect_pads
			(clearance 0)
		)
		(min_thickness 0.25)
		(keepout
			(tracks not_allowed)
			(vias allowed)
			(pads allowed)
			(copperpour not_allowed)
			(footprints allowed)
		)
		(placement
			(enabled no)
			(sheetname "")
		)
		(fill yes
			(thermal_gap 0.5)
			(thermal_bridge_width 0.5)
			(island_removal_mode 0)
		)
		(polygon
			(pts
				(arc
					(start 89.521284 -253.919736)
					(mid 88.868504 -253.919736)
					(end 89.521284 -253.919736)
				)
			)
		)
	)
	(zone
		(layers "B.Cu" "In4.Cu" "In6.Cu" "In11.Cu" "In13.Cu" "In15.Cu")
		(hatch none 0.5)
		(connect_pads
			(clearance 0)
		)
		(min_thickness 0.25)
		(keepout
			(tracks not_allowed)
			(vias allowed)
			(pads allowed)
			(copperpour not_allowed)
			(footprints allowed)
		)
		(placement
			(enabled no)
			(sheetname "")
		)
		(fill yes
			(thermal_gap 0.5)
			(thermal_bridge_width 0.5)
			(island_removal_mode 0)
		)
		(polygon
			(pts
				(arc
					(start 336.881724 -236.597952)
					(mid 336.228944 -236.597952)
					(end 336.881724 -236.597952)
				)
			)
		)
	)
	(zone
		(layers "B.Cu" "In4.Cu" "In6.Cu" "In11.Cu" "In13.Cu" "In15.Cu")
		(hatch none 0.5)
		(connect_pads
			(clearance 0)
		)
		(min_thickness 0.25)
		(keepout
			(tracks not_allowed)
			(vias allowed)
			(pads allowed)
			(copperpour not_allowed)
			(footprints allowed)
		)
		(placement
			(enabled no)
			(sheetname "")
		)
		(fill yes
			(thermal_gap 0.5)
			(thermal_bridge_width 0.5)
			(island_removal_mode 0)
		)
		(polygon
			(pts
				(arc
					(start 347.217238 -400.858228)
					(mid 346.513658 -400.858228)
					(end 347.217238 -400.858228)
				)
			)
		)
	)
	(zone
		(layers "B.Cu" "In4.Cu" "In6.Cu" "In11.Cu" "In13.Cu" "In15.Cu")
		(hatch none 0.5)
		(connect_pads
			(clearance 0)
		)
		(min_thickness 0.25)
		(keepout
			(tracks not_allowed)
			(vias allowed)
			(pads allowed)
			(copperpour not_allowed)
			(footprints allowed)
		)
		(placement
			(enabled no)
			(sheetname "")
		)
		(fill yes
			(thermal_gap 0.5)
			(thermal_bridge_width 0.5)
			(island_removal_mode 0)
		)
		(polygon
			(pts
				(arc
					(start 382.101852 -271.011396)
					(mid 381.449072 -271.011396)
					(end 382.101852 -271.011396)
				)
			)
		)
	)
	(zone
		(layers "B.Cu" "In4.Cu" "In6.Cu" "In11.Cu" "In13.Cu" "In15.Cu")
		(hatch none 0.5)
		(connect_pads
			(clearance 0)
		)
		(min_thickness 0.25)
		(keepout
			(tracks not_allowed)
			(vias allowed)
			(pads allowed)
			(copperpour not_allowed)
			(footprints allowed)
		)
		(placement
			(enabled no)
			(sheetname "")
		)
		(fill yes
			(thermal_gap 0.5)
			(thermal_bridge_width 0.5)
			(island_removal_mode 0)
		)
		(polygon
			(pts
				(arc
					(start 147.222464 -407.00452)
					(mid 146.518884 -407.00452)
					(end 147.222464 -407.00452)
				)
			)
		)
	)
	(zone
		(layers "B.Cu" "In4.Cu" "In6.Cu" "In11.Cu" "In13.Cu" "In15.Cu")
		(hatch none 0.5)
		(connect_pads
			(clearance 0)
		)
		(min_thickness 0.25)
		(keepout
			(tracks not_allowed)
			(vias allowed)
			(pads allowed)
			(copperpour not_allowed)
			(footprints allowed)
		)
		(placement
			(enabled no)
			(sheetname "")
		)
		(fill yes
			(thermal_gap 0.5)
			(thermal_bridge_width 0.5)
			(island_removal_mode 0)
		)
		(polygon
			(pts
				(arc
					(start 295.230804 -221.116652)
					(mid 294.578024 -221.116652)
					(end 295.230804 -221.116652)
				)
			)
		)
	)
	(zone
		(layers "B.Cu" "In4.Cu" "In6.Cu" "In11.Cu" "In13.Cu" "In15.Cu")
		(hatch none 0.5)
		(connect_pads
			(clearance 0)
		)
		(min_thickness 0.25)
		(keepout
			(tracks not_allowed)
			(vias allowed)
			(pads allowed)
			(copperpour not_allowed)
			(footprints allowed)
		)
		(placement
			(enabled no)
			(sheetname "")
		)
		(fill yes
			(thermal_gap 0.5)
			(thermal_bridge_width 0.5)
			(island_removal_mode 0)
		)
		(polygon
			(pts
				(arc
					(start 66.478404 -306.116736)
					(mid 65.825624 -306.116736)
					(end 66.478404 -306.116736)
				)
			)
		)
	)
	(zone
		(layers "B.Cu" "In4.Cu" "In6.Cu" "In11.Cu" "In13.Cu" "In15.Cu")
		(hatch none 0.5)
		(connect_pads
			(clearance 0)
		)
		(min_thickness 0.25)
		(keepout
			(tracks not_allowed)
			(vias allowed)
			(pads allowed)
			(copperpour not_allowed)
			(footprints allowed)
		)
		(placement
			(enabled no)
			(sheetname "")
		)
		(fill yes
			(thermal_gap 0.5)
			(thermal_bridge_width 0.5)
			(island_removal_mode 0)
		)
		(polygon
			(pts
				(arc
					(start 358.967024 -224.389442)
					(mid 358.314244 -224.389442)
					(end 358.967024 -224.389442)
				)
			)
		)
	)
	(zone
		(layers "B.Cu" "In4.Cu" "In6.Cu" "In11.Cu" "In13.Cu" "In15.Cu")
		(hatch none 0.5)
		(connect_pads
			(clearance 0)
		)
		(min_thickness 0.25)
		(keepout
			(tracks not_allowed)
			(vias allowed)
			(pads allowed)
			(copperpour not_allowed)
			(footprints allowed)
		)
		(placement
			(enabled no)
			(sheetname "")
		)
		(fill yes
			(thermal_gap 0.5)
			(thermal_bridge_width 0.5)
			(island_removal_mode 0)
		)
		(polygon
			(pts
				(arc
					(start 421.062404 -312.066686)
					(mid 420.409624 -312.066686)
					(end 421.062404 -312.066686)
				)
			)
		)
	)
	(zone
		(layers "B.Cu" "In4.Cu" "In6.Cu" "In11.Cu" "In13.Cu" "In15.Cu")
		(hatch none 0.5)
		(connect_pads
			(clearance 0)
		)
		(min_thickness 0.25)
		(keepout
			(tracks not_allowed)
			(vias allowed)
			(pads allowed)
			(copperpour not_allowed)
			(footprints allowed)
		)
		(placement
			(enabled no)
			(sheetname "")
		)
		(fill yes
			(thermal_gap 0.5)
			(thermal_bridge_width 0.5)
			(island_removal_mode 0)
		)
		(polygon
			(pts
				(arc
					(start 93.280738 -284.847538)
					(mid 92.627958 -284.847538)
					(end 93.280738 -284.847538)
				)
			)
		)
	)
	(zone
		(layers "B.Cu" "In4.Cu" "In6.Cu" "In11.Cu" "In13.Cu" "In15.Cu")
		(hatch none 0.5)
		(connect_pads
			(clearance 0)
		)
		(min_thickness 0.25)
		(keepout
			(tracks not_allowed)
			(vias allowed)
			(pads allowed)
			(copperpour not_allowed)
			(footprints allowed)
		)
		(placement
			(enabled no)
			(sheetname "")
		)
		(fill yes
			(thermal_gap 0.5)
			(thermal_bridge_width 0.5)
			(island_removal_mode 0)
		)
		(polygon
			(pts
				(arc
					(start 336.991452 -264.50036)
					(mid 336.338672 -264.50036)
					(end 336.991452 -264.50036)
				)
			)
		)
	)
	(zone
		(layers "B.Cu" "In4.Cu" "In6.Cu" "In11.Cu" "In13.Cu" "In15.Cu")
		(hatch none 0.5)
		(connect_pads
			(clearance 0)
		)
		(min_thickness 0.25)
		(keepout
			(tracks not_allowed)
			(vias allowed)
			(pads allowed)
			(copperpour not_allowed)
			(footprints allowed)
		)
		(placement
			(enabled no)
			(sheetname "")
		)
		(fill yes
			(thermal_gap 0.5)
			(thermal_bridge_width 0.5)
			(island_removal_mode 0)
		)
		(polygon
			(pts
				(arc
					(start 66.478404 -225.36658)
					(mid 65.825624 -225.36658)
					(end 66.478404 -225.36658)
				)
			)
		)
	)
	(zone
		(layers "B.Cu" "In4.Cu" "In6.Cu" "In11.Cu" "In13.Cu" "In15.Cu")
		(hatch none 0.5)
		(connect_pads
			(clearance 0)
		)
		(min_thickness 0.25)
		(keepout
			(tracks not_allowed)
			(vias allowed)
			(pads allowed)
			(copperpour not_allowed)
			(footprints allowed)
		)
		(placement
			(enabled no)
			(sheetname "")
		)
		(fill yes
			(thermal_gap 0.5)
			(thermal_bridge_width 0.5)
			(island_removal_mode 0)
		)
		(polygon
			(pts
				(arc
					(start 338.871052 -261.244842)
					(mid 338.218272 -261.244842)
					(end 338.871052 -261.244842)
				)
			)
		)
	)
	(zone
		(layers "B.Cu" "In4.Cu" "In6.Cu" "In11.Cu" "In13.Cu" "In15.Cu")
		(hatch none 0.5)
		(connect_pads
			(clearance 0)
		)
		(min_thickness 0.25)
		(keepout
			(tracks not_allowed)
			(vias allowed)
			(pads allowed)
			(copperpour not_allowed)
			(footprints allowed)
		)
		(placement
			(enabled no)
			(sheetname "")
		)
		(fill yes
			(thermal_gap 0.5)
			(thermal_bridge_width 0.5)
			(island_removal_mode 0)
		)
		(polygon
			(pts
				(arc
					(start 89.521538 -262.058658)
					(mid 88.868758 -262.058658)
					(end 89.521538 -262.058658)
				)
			)
		)
	)
	(zone
		(layers "B.Cu" "In4.Cu" "In6.Cu" "In11.Cu" "In13.Cu" "In15.Cu")
		(hatch none 0.5)
		(connect_pads
			(clearance 0)
		)
		(min_thickness 0.25)
		(keepout
			(tracks not_allowed)
			(vias allowed)
			(pads allowed)
			(copperpour not_allowed)
			(footprints allowed)
		)
		(placement
			(enabled no)
			(sheetname "")
		)
		(fill yes
			(thermal_gap 0.5)
			(thermal_bridge_width 0.5)
			(island_removal_mode 0)
		)
		(polygon
			(pts
				(arc
					(start 123.823984 -285.661354)
					(mid 123.171204 -285.661354)
					(end 123.823984 -285.661354)
				)
			)
		)
	)
	(zone
		(layers "B.Cu" "In4.Cu" "In6.Cu" "In11.Cu" "In13.Cu" "In15.Cu")
		(hatch none 0.5)
		(connect_pads
			(clearance 0)
		)
		(min_thickness 0.25)
		(keepout
			(tracks not_allowed)
			(vias allowed)
			(pads allowed)
			(copperpour not_allowed)
			(footprints allowed)
		)
		(placement
			(enabled no)
			(sheetname "")
		)
		(fill yes
			(thermal_gap 0.5)
			(thermal_bridge_width 0.5)
			(island_removal_mode 0)
		)
		(polygon
			(pts
				(arc
					(start 121.004584 -285.661354)
					(mid 120.351804 -285.661354)
					(end 121.004584 -285.661354)
				)
			)
		)
	)
	(zone
		(layers "B.Cu" "In4.Cu" "In6.Cu" "In11.Cu" "In13.Cu" "In15.Cu")
		(hatch none 0.5)
		(connect_pads
			(clearance 0)
		)
		(min_thickness 0.25)
		(keepout
			(tracks not_allowed)
			(vias allowed)
			(pads allowed)
			(copperpour not_allowed)
			(footprints allowed)
		)
		(placement
			(enabled no)
			(sheetname "")
		)
		(fill yes
			(thermal_gap 0.5)
			(thermal_bridge_width 0.5)
			(island_removal_mode 0)
		)
		(polygon
			(pts
				(arc
					(start 299.356272 -265.316716)
					(mid 298.703492 -265.316716)
					(end 299.356272 -265.316716)
				)
			)
		)
	)
	(zone
		(layers "B.Cu" "In4.Cu" "In6.Cu" "In11.Cu" "In13.Cu" "In15.Cu")
		(hatch none 0.5)
		(connect_pads
			(clearance 0)
		)
		(min_thickness 0.25)
		(keepout
			(tracks not_allowed)
			(vias allowed)
			(pads allowed)
			(copperpour not_allowed)
			(footprints allowed)
		)
		(placement
			(enabled no)
			(sheetname "")
		)
		(fill yes
			(thermal_gap 0.5)
			(thermal_bridge_width 0.5)
			(island_removal_mode 0)
		)
		(polygon
			(pts
				(arc
					(start 346.389452 -285.661354)
					(mid 345.736672 -285.661354)
					(end 346.389452 -285.661354)
				)
			)
		)
	)
	(zone
		(layers "B.Cu" "In4.Cu" "In6.Cu" "In11.Cu" "In13.Cu" "In15.Cu")
		(hatch none 0.5)
		(connect_pads
			(clearance 0)
		)
		(min_thickness 0.25)
		(keepout
			(tracks not_allowed)
			(vias allowed)
			(pads allowed)
			(copperpour not_allowed)
			(footprints allowed)
		)
		(placement
			(enabled no)
			(sheetname "")
		)
		(fill yes
			(thermal_gap 0.5)
			(thermal_bridge_width 0.5)
			(island_removal_mode 0)
		)
		(polygon
			(pts
				(arc
					(start 134.161784 -261.244842)
					(mid 133.509004 -261.244842)
					(end 134.161784 -261.244842)
				)
			)
		)
	)
	(zone
		(layers "B.Cu" "In4.Cu" "In6.Cu" "In11.Cu" "In13.Cu" "In15.Cu")
		(hatch none 0.5)
		(connect_pads
			(clearance 0)
		)
		(min_thickness 0.25)
		(keepout
			(tracks not_allowed)
			(vias allowed)
			(pads allowed)
			(copperpour not_allowed)
			(footprints allowed)
		)
		(placement
			(enabled no)
			(sheetname "")
		)
		(fill yes
			(thermal_gap 0.5)
			(thermal_bridge_width 0.5)
			(island_removal_mode 0)
		)
		(polygon
			(pts
				(arc
					(start 135.101584 -271.011396)
					(mid 134.448804 -271.011396)
					(end 135.101584 -271.011396)
				)
			)
		)
	)
	(zone
		(layers "B.Cu" "In4.Cu" "In6.Cu" "In11.Cu" "In13.Cu" "In15.Cu")
		(hatch none 0.5)
		(connect_pads
			(clearance 0)
		)
		(min_thickness 0.25)
		(keepout
			(tracks not_allowed)
			(vias allowed)
			(pads allowed)
			(copperpour not_allowed)
			(footprints allowed)
		)
		(placement
			(enabled no)
			(sheetname "")
		)
		(fill yes
			(thermal_gap 0.5)
			(thermal_bridge_width 0.5)
			(island_removal_mode 0)
		)
		(polygon
			(pts
				(arc
					(start 295.230804 -261.066788)
					(mid 294.578024 -261.066788)
					(end 295.230804 -261.066788)
				)
			)
		)
	)
	(zone
		(layers "B.Cu" "In4.Cu" "In6.Cu" "In11.Cu" "In13.Cu" "In15.Cu")
		(hatch none 0.5)
		(connect_pads
			(clearance 0)
		)
		(min_thickness 0.25)
		(keepout
			(tracks not_allowed)
			(vias allowed)
			(pads allowed)
			(copperpour not_allowed)
			(footprints allowed)
		)
		(placement
			(enabled no)
			(sheetname "")
		)
		(fill yes
			(thermal_gap 0.5)
			(thermal_bridge_width 0.5)
			(island_removal_mode 0)
		)
		(polygon
			(pts
				(arc
					(start 173.122336 -215.166702)
					(mid 172.469556 -215.166702)
					(end 173.122336 -215.166702)
				)
			)
		)
	)
	(zone
		(layers "B.Cu" "In4.Cu" "In6.Cu" "In11.Cu" "In13.Cu" "In15.Cu")
		(hatch none 0.5)
		(connect_pads
			(clearance 0)
		)
		(min_thickness 0.25)
		(keepout
			(tracks not_allowed)
			(vias allowed)
			(pads allowed)
			(copperpour not_allowed)
			(footprints allowed)
		)
		(placement
			(enabled no)
			(sheetname "")
		)
		(fill yes
			(thermal_gap 0.5)
			(thermal_bridge_width 0.5)
			(island_removal_mode 0)
		)
		(polygon
			(pts
				(arc
					(start 317.448438 -400.858228)
					(mid 316.744858 -400.858228)
					(end 317.448438 -400.858228)
				)
			)
		)
	)
	(zone
		(layers "B.Cu" "In4.Cu" "In6.Cu" "In11.Cu" "In13.Cu" "In15.Cu")
		(hatch none 0.5)
		(connect_pads
			(clearance 0)
		)
		(min_thickness 0.25)
		(keepout
			(tracks not_allowed)
			(vias allowed)
			(pads allowed)
			(copperpour not_allowed)
			(footprints allowed)
		)
		(placement
			(enabled no)
			(sheetname "")
		)
		(fill yes
			(thermal_gap 0.5)
			(thermal_bridge_width 0.5)
			(island_removal_mode 0)
		)
		(polygon
			(pts
				(arc
					(start 295.230804 -312.91657)
					(mid 294.578024 -312.91657)
					(end 295.230804 -312.91657)
				)
			)
		)
	)
	(zone
		(layers "B.Cu" "In4.Cu" "In6.Cu" "In11.Cu" "In13.Cu" "In15.Cu")
		(hatch none 0.5)
		(connect_pads
			(clearance 0)
		)
		(min_thickness 0.25)
		(keepout
			(tracks not_allowed)
			(vias allowed)
			(pads allowed)
			(copperpour not_allowed)
			(footprints allowed)
		)
		(placement
			(enabled no)
			(sheetname "")
		)
		(fill yes
			(thermal_gap 0.5)
			(thermal_bridge_width 0.5)
			(island_removal_mode 0)
		)
		(polygon
			(pts
				(arc
					(start 47.290736 -213.46668)
					(mid 46.637956 -213.46668)
					(end 47.290736 -213.46668)
				)
			)
		)
	)
	(zone
		(layers "B.Cu" "In4.Cu" "In6.Cu" "In11.Cu" "In13.Cu" "In15.Cu")
		(hatch none 0.5)
		(connect_pads
			(clearance 0)
		)
		(min_thickness 0.25)
		(keepout
			(tracks not_allowed)
			(vias allowed)
			(pads allowed)
			(copperpour not_allowed)
			(footprints allowed)
		)
		(placement
			(enabled no)
			(sheetname "")
		)
		(fill yes
			(thermal_gap 0.5)
			(thermal_bridge_width 0.5)
			(island_removal_mode 0)
		)
		(polygon
			(pts
				(arc
					(start 406.81656 -407.00452)
					(mid 406.11298 -407.00452)
					(end 406.81656 -407.00452)
				)
			)
		)
	)
	(zone
		(layers "B.Cu" "In4.Cu" "In6.Cu" "In11.Cu" "In13.Cu" "In15.Cu")
		(hatch none 0.5)
		(connect_pads
			(clearance 0)
		)
		(min_thickness 0.25)
		(keepout
			(tracks not_allowed)
			(vias allowed)
			(pads allowed)
			(copperpour not_allowed)
			(footprints allowed)
		)
		(placement
			(enabled no)
			(sheetname "")
		)
		(fill yes
			(thermal_gap 0.5)
			(thermal_bridge_width 0.5)
			(island_removal_mode 0)
		)
		(polygon
			(pts
				(arc
					(start 408.020774 -17.601438)
					(mid 407.317194 -17.601438)
					(end 408.020774 -17.601438)
				)
			)
		)
	)
	(zone
		(layers "B.Cu" "In4.Cu" "In6.Cu" "In11.Cu" "In13.Cu" "In15.Cu")
		(hatch none 0.5)
		(connect_pads
			(clearance 0)
		)
		(min_thickness 0.25)
		(keepout
			(tracks not_allowed)
			(vias allowed)
			(pads allowed)
			(copperpour not_allowed)
			(footprints allowed)
		)
		(placement
			(enabled no)
			(sheetname "")
		)
		(fill yes
			(thermal_gap 0.5)
			(thermal_bridge_width 0.5)
			(island_removal_mode 0)
		)
		(polygon
			(pts
				(arc
					(start 295.230804 -294.216582)
					(mid 294.578024 -294.216582)
					(end 295.230804 -294.216582)
				)
			)
		)
	)
	(zone
		(layers "B.Cu" "In4.Cu" "In6.Cu" "In11.Cu" "In13.Cu" "In15.Cu")
		(hatch none 0.5)
		(connect_pads
			(clearance 0)
		)
		(min_thickness 0.25)
		(keepout
			(tracks not_allowed)
			(vias allowed)
			(pads allowed)
			(copperpour not_allowed)
			(footprints allowed)
		)
		(placement
			(enabled no)
			(sheetname "")
		)
		(fill yes
			(thermal_gap 0.5)
			(thermal_bridge_width 0.5)
			(island_removal_mode 0)
		)
		(polygon
			(pts
				(arc
					(start 421.062404 -241.516662)
					(mid 420.409624 -241.516662)
					(end 421.062404 -241.516662)
				)
			)
		)
	)
	(zone
		(layers "B.Cu" "In4.Cu" "In6.Cu" "In11.Cu" "In13.Cu" "In15.Cu")
		(hatch none 0.5)
		(connect_pads
			(clearance 0)
		)
		(min_thickness 0.25)
		(keepout
			(tracks not_allowed)
			(vias allowed)
			(pads allowed)
			(copperpour not_allowed)
			(footprints allowed)
		)
		(placement
			(enabled no)
			(sheetname "")
		)
		(fill yes
			(thermal_gap 0.5)
			(thermal_bridge_width 0.5)
			(island_removal_mode 0)
		)
		(polygon
			(pts
				(arc
					(start 421.062404 -238.116618)
					(mid 420.409624 -238.116618)
					(end 421.062404 -238.116618)
				)
			)
		)
	)
	(zone
		(layers "B.Cu" "In4.Cu" "In6.Cu" "In11.Cu" "In13.Cu" "In15.Cu")
		(hatch none 0.5)
		(connect_pads
			(clearance 0)
		)
		(min_thickness 0.25)
		(keepout
			(tracks not_allowed)
			(vias allowed)
			(pads allowed)
			(copperpour not_allowed)
			(footprints allowed)
		)
		(placement
			(enabled no)
			(sheetname "")
		)
		(fill yes
			(thermal_gap 0.5)
			(thermal_bridge_width 0.5)
			(island_removal_mode 0)
		)
		(polygon
			(pts
				(arc
					(start 341.954358 -400.858228)
					(mid 341.250778 -400.858228)
					(end 341.954358 -400.858228)
				)
			)
		)
	)
	(zone
		(layers "B.Cu" "In4.Cu" "In6.Cu" "In11.Cu" "In13.Cu" "In15.Cu")
		(hatch none 0.5)
		(connect_pads
			(clearance 0)
		)
		(min_thickness 0.25)
		(keepout
			(tracks not_allowed)
			(vias allowed)
			(pads allowed)
			(copperpour not_allowed)
			(footprints allowed)
		)
		(placement
			(enabled no)
			(sheetname "")
		)
		(fill yes
			(thermal_gap 0.5)
			(thermal_bridge_width 0.5)
			(island_removal_mode 0)
		)
		(polygon
			(pts
				(arc
					(start 90.461084 -286.475424)
					(mid 89.808304 -286.475424)
					(end 90.461084 -286.475424)
				)
			)
		)
	)
	(zone
		(layers "B.Cu" "In4.Cu" "In6.Cu" "In11.Cu" "In13.Cu" "In15.Cu")
		(hatch none 0.5)
		(connect_pads
			(clearance 0)
		)
		(min_thickness 0.25)
		(keepout
			(tracks not_allowed)
			(vias allowed)
			(pads allowed)
			(copperpour not_allowed)
			(footprints allowed)
		)
		(placement
			(enabled no)
			(sheetname "")
		)
		(fill yes
			(thermal_gap 0.5)
			(thermal_bridge_width 0.5)
			(island_removal_mode 0)
		)
		(polygon
			(pts
				(arc
					(start 314.418472 -306.116736)
					(mid 313.765692 -306.116736)
					(end 314.418472 -306.116736)
				)
			)
		)
	)
	(zone
		(layers "B.Cu" "In4.Cu" "In6.Cu" "In11.Cu" "In13.Cu" "In15.Cu")
		(hatch none 0.5)
		(connect_pads
			(clearance 0)
		)
		(min_thickness 0.25)
		(keepout
			(tracks not_allowed)
			(vias allowed)
			(pads allowed)
			(copperpour not_allowed)
			(footprints allowed)
		)
		(placement
			(enabled no)
			(sheetname "")
		)
		(fill yes
			(thermal_gap 0.5)
			(thermal_bridge_width 0.5)
			(island_removal_mode 0)
		)
		(polygon
			(pts
				(arc
					(start 383.511806 -266.942062)
					(mid 382.859026 -266.942062)
					(end 383.511806 -266.942062)
				)
			)
		)
	)
	(zone
		(layers "B.Cu" "In4.Cu" "In6.Cu" "In11.Cu" "In13.Cu" "In15.Cu")
		(hatch none 0.5)
		(connect_pads
			(clearance 0)
		)
		(min_thickness 0.25)
		(keepout
			(tracks not_allowed)
			(vias allowed)
			(pads allowed)
			(copperpour not_allowed)
			(footprints allowed)
		)
		(placement
			(enabled no)
			(sheetname "")
		)
		(fill yes
			(thermal_gap 0.5)
			(thermal_bridge_width 0.5)
			(island_removal_mode 0)
		)
		(polygon
			(pts
				(arc
					(start 177.222404 -233.016806)
					(mid 176.569624 -233.016806)
					(end 177.222404 -233.016806)
				)
			)
		)
	)
	(zone
		(layers "B.Cu" "In4.Cu" "In6.Cu" "In11.Cu" "In13.Cu" "In15.Cu")
		(hatch none 0.5)
		(connect_pads
			(clearance 0)
		)
		(min_thickness 0.25)
		(keepout
			(tracks not_allowed)
			(vias allowed)
			(pads allowed)
			(copperpour not_allowed)
			(footprints allowed)
		)
		(placement
			(enabled no)
			(sheetname "")
		)
		(fill yes
			(thermal_gap 0.5)
			(thermal_bridge_width 0.5)
			(island_removal_mode 0)
		)
		(polygon
			(pts
				(arc
					(start 339.341206 -260.430772)
					(mid 338.688426 -260.430772)
					(end 339.341206 -260.430772)
				)
			)
		)
	)
	(zone
		(layers "B.Cu" "In4.Cu" "In6.Cu" "In11.Cu" "In13.Cu" "In15.Cu")
		(hatch none 0.5)
		(connect_pads
			(clearance 0)
		)
		(min_thickness 0.25)
		(keepout
			(tracks not_allowed)
			(vias allowed)
			(pads allowed)
			(copperpour not_allowed)
			(footprints allowed)
		)
		(placement
			(enabled no)
			(sheetname "")
		)
		(fill yes
			(thermal_gap 0.5)
			(thermal_bridge_width 0.5)
			(island_removal_mode 0)
		)
		(polygon
			(pts
				(arc
					(start 409.951174 -19.125438)
					(mid 409.247594 -19.125438)
					(end 409.951174 -19.125438)
				)
			)
		)
	)
	(zone
		(layers "B.Cu" "In4.Cu" "In6.Cu" "In11.Cu" "In13.Cu" "In15.Cu")
		(hatch none 0.5)
		(connect_pads
			(clearance 0)
		)
		(min_thickness 0.25)
		(keepout
			(tracks not_allowed)
			(vias allowed)
			(pads allowed)
			(copperpour not_allowed)
			(footprints allowed)
		)
		(placement
			(enabled no)
			(sheetname "")
		)
		(fill yes
			(thermal_gap 0.5)
			(thermal_bridge_width 0.5)
			(island_removal_mode 0)
		)
		(polygon
			(pts
				(arc
					(start 135.571484 -278.336502)
					(mid 134.918704 -278.336502)
					(end 135.571484 -278.336502)
				)
			)
		)
	)
	(zone
		(layers "B.Cu" "In4.Cu" "In6.Cu" "In11.Cu" "In13.Cu" "In15.Cu")
		(hatch none 0.5)
		(connect_pads
			(clearance 0)
		)
		(min_thickness 0.25)
		(keepout
			(tracks not_allowed)
			(vias allowed)
			(pads allowed)
			(copperpour not_allowed)
			(footprints allowed)
		)
		(placement
			(enabled no)
			(sheetname "")
		)
		(fill yes
			(thermal_gap 0.5)
			(thermal_bridge_width 0.5)
			(island_removal_mode 0)
		)
		(polygon
			(pts
				(arc
					(start 162.109404 -223.666558)
					(mid 161.456624 -223.666558)
					(end 162.109404 -223.666558)
				)
			)
		)
	)
	(zone
		(layers "B.Cu" "In4.Cu" "In6.Cu" "In11.Cu" "In13.Cu" "In15.Cu")
		(hatch none 0.5)
		(connect_pads
			(clearance 0)
		)
		(min_thickness 0.25)
		(keepout
			(tracks not_allowed)
			(vias allowed)
			(pads allowed)
			(copperpour not_allowed)
			(footprints allowed)
		)
		(placement
			(enabled no)
			(sheetname "")
		)
		(fill yes
			(thermal_gap 0.5)
			(thermal_bridge_width 0.5)
			(island_removal_mode 0)
		)
		(polygon
			(pts
				(arc
					(start 337.351624 -242.294918)
					(mid 336.698844 -242.294918)
					(end 337.351624 -242.294918)
				)
			)
		)
	)
	(zone
		(layers "B.Cu" "In4.Cu" "In6.Cu" "In11.Cu" "In13.Cu" "In15.Cu")
		(hatch none 0.5)
		(connect_pads
			(clearance 0)
		)
		(min_thickness 0.25)
		(keepout
			(tracks not_allowed)
			(vias allowed)
			(pads allowed)
			(copperpour not_allowed)
			(footprints allowed)
		)
		(placement
			(enabled no)
			(sheetname "")
		)
		(fill yes
			(thermal_gap 0.5)
			(thermal_bridge_width 0.5)
			(island_removal_mode 0)
		)
		(polygon
			(pts
				(arc
					(start 336.411824 -232.528364)
					(mid 335.759044 -232.528364)
					(end 336.411824 -232.528364)
				)
			)
		)
	)
	(zone
		(layers "B.Cu" "In4.Cu" "In6.Cu" "In11.Cu" "In13.Cu" "In15.Cu")
		(hatch none 0.5)
		(connect_pads
			(clearance 0)
		)
		(min_thickness 0.25)
		(keepout
			(tracks not_allowed)
			(vias allowed)
			(pads allowed)
			(copperpour not_allowed)
			(footprints allowed)
		)
		(placement
			(enabled no)
			(sheetname "")
		)
		(fill yes
			(thermal_gap 0.5)
			(thermal_bridge_width 0.5)
			(island_removal_mode 0)
		)
		(polygon
			(pts
				(arc
					(start 320.511678 -400.858228)
					(mid 319.808098 -400.858228)
					(end 320.511678 -400.858228)
				)
			)
		)
	)
	(zone
		(layers "B.Cu" "In4.Cu" "In6.Cu" "In11.Cu" "In13.Cu" "In15.Cu")
		(hatch none 0.5)
		(connect_pads
			(clearance 0)
		)
		(min_thickness 0.25)
		(keepout
			(tracks not_allowed)
			(vias allowed)
			(pads allowed)
			(copperpour not_allowed)
			(footprints allowed)
		)
		(placement
			(enabled no)
			(sheetname "")
		)
		(fill yes
			(thermal_gap 0.5)
			(thermal_bridge_width 0.5)
			(island_removal_mode 0)
		)
		(polygon
			(pts
				(arc
					(start 382.31064 -407.00452)
					(mid 381.60706 -407.00452)
					(end 382.31064 -407.00452)
				)
			)
		)
	)
	(zone
		(layers "B.Cu" "In4.Cu" "In6.Cu" "In11.Cu" "In13.Cu" "In15.Cu")
		(hatch none 0.5)
		(connect_pads
			(clearance 0)
		)
		(min_thickness 0.25)
		(keepout
			(tracks not_allowed)
			(vias allowed)
			(pads allowed)
			(copperpour not_allowed)
			(footprints allowed)
		)
		(placement
			(enabled no)
			(sheetname "")
		)
		(fill yes
			(thermal_gap 0.5)
			(thermal_bridge_width 0.5)
			(island_removal_mode 0)
		)
		(polygon
			(pts
				(arc
					(start 338.291424 -240.667286)
					(mid 337.638644 -240.667286)
					(end 338.291424 -240.667286)
				)
			)
		)
	)
	(zone
		(layers "B.Cu" "In4.Cu" "In6.Cu" "In11.Cu" "In13.Cu" "In15.Cu")
		(hatch none 0.5)
		(connect_pads
			(clearance 0)
		)
		(min_thickness 0.25)
		(keepout
			(tracks not_allowed)
			(vias allowed)
			(pads allowed)
			(copperpour not_allowed)
			(footprints allowed)
		)
		(placement
			(enabled no)
			(sheetname "")
		)
		(fill yes
			(thermal_gap 0.5)
			(thermal_bridge_width 0.5)
			(island_removal_mode 0)
		)
		(polygon
			(pts
				(arc
					(start 53.41112 -19.13636)
					(mid 52.70754 -19.13636)
					(end 53.41112 -19.13636)
				)
			)
		)
	)
	(zone
		(layers "B.Cu" "In4.Cu" "In6.Cu" "In11.Cu" "In13.Cu" "In15.Cu")
		(hatch none 0.5)
		(connect_pads
			(clearance 0)
		)
		(min_thickness 0.25)
		(keepout
			(tracks not_allowed)
			(vias allowed)
			(pads allowed)
			(copperpour not_allowed)
			(footprints allowed)
		)
		(placement
			(enabled no)
			(sheetname "")
		)
		(fill yes
			(thermal_gap 0.5)
			(thermal_bridge_width 0.5)
			(island_removal_mode 0)
		)
		(polygon
			(pts
				(arc
					(start 332.764638 -400.858228)
					(mid 332.061058 -400.858228)
					(end 332.764638 -400.858228)
				)
			)
		)
	)
	(zone
		(layers "B.Cu" "In4.Cu" "In6.Cu" "In11.Cu" "In13.Cu" "In15.Cu")
		(hatch none 0.5)
		(connect_pads
			(clearance 0)
		)
		(min_thickness 0.25)
		(keepout
			(tracks not_allowed)
			(vias allowed)
			(pads allowed)
			(copperpour not_allowed)
			(footprints allowed)
		)
		(placement
			(enabled no)
			(sheetname "")
		)
		(fill yes
			(thermal_gap 0.5)
			(thermal_bridge_width 0.5)
			(island_removal_mode 0)
		)
		(polygon
			(pts
				(arc
					(start 314.418472 -227.91674)
					(mid 313.765692 -227.91674)
					(end 314.418472 -227.91674)
				)
			)
		)
	)
	(zone
		(layers "B.Cu" "In4.Cu" "In6.Cu" "In11.Cu" "In13.Cu" "In15.Cu")
		(hatch none 0.5)
		(connect_pads
			(clearance 0)
		)
		(min_thickness 0.25)
		(keepout
			(tracks not_allowed)
			(vias allowed)
			(pads allowed)
			(copperpour not_allowed)
			(footprints allowed)
		)
		(placement
			(enabled no)
			(sheetname "")
		)
		(fill yes
			(thermal_gap 0.5)
			(thermal_bridge_width 0.5)
			(island_removal_mode 0)
		)
		(polygon
			(pts
				(arc
					(start 382.93167 -239.853216)
					(mid 382.27889 -239.853216)
					(end 382.93167 -239.853216)
				)
			)
		)
	)
	(zone
		(layers "B.Cu" "In4.Cu" "In6.Cu" "In11.Cu" "In13.Cu" "In15.Cu")
		(hatch none 0.5)
		(connect_pads
			(clearance 0)
		)
		(min_thickness 0.25)
		(keepout
			(tracks not_allowed)
			(vias allowed)
			(pads allowed)
			(copperpour not_allowed)
			(footprints allowed)
		)
		(placement
			(enabled no)
			(sheetname "")
		)
		(fill yes
			(thermal_gap 0.5)
			(thermal_bridge_width 0.5)
			(island_removal_mode 0)
		)
		(polygon
			(pts
				(arc
					(start 125.779784 -407.00452)
					(mid 125.076204 -407.00452)
					(end 125.779784 -407.00452)
				)
			)
		)
	)
	(zone
		(layers "B.Cu" "In4.Cu" "In6.Cu" "In11.Cu" "In13.Cu" "In15.Cu")
		(hatch none 0.5)
		(connect_pads
			(clearance 0)
		)
		(min_thickness 0.25)
		(keepout
			(tracks not_allowed)
			(vias allowed)
			(pads allowed)
			(copperpour not_allowed)
			(footprints allowed)
		)
		(placement
			(enabled no)
			(sheetname "")
		)
		(fill yes
			(thermal_gap 0.5)
			(thermal_bridge_width 0.5)
			(island_removal_mode 0)
		)
		(polygon
			(pts
				(arc
					(start 66.478404 -304.416714)
					(mid 65.825624 -304.416714)
					(end 66.478404 -304.416714)
				)
			)
		)
	)
	(zone
		(layers "B.Cu" "In4.Cu" "In6.Cu" "In11.Cu" "In13.Cu" "In15.Cu")
		(hatch none 0.5)
		(connect_pads
			(clearance 0)
		)
		(min_thickness 0.25)
		(keepout
			(tracks not_allowed)
			(vias allowed)
			(pads allowed)
			(copperpour not_allowed)
			(footprints allowed)
		)
		(placement
			(enabled no)
			(sheetname "")
		)
		(fill yes
			(thermal_gap 0.5)
			(thermal_bridge_width 0.5)
			(island_removal_mode 0)
		)
		(polygon
			(pts
				(arc
					(start 383.871724 -234.970066)
					(mid 383.218944 -234.970066)
					(end 383.871724 -234.970066)
				)
			)
		)
	)
	(zone
		(layers "B.Cu" "In4.Cu" "In6.Cu" "In11.Cu" "In13.Cu" "In15.Cu")
		(hatch none 0.5)
		(connect_pads
			(clearance 0)
		)
		(min_thickness 0.25)
		(keepout
			(tracks not_allowed)
			(vias allowed)
			(pads allowed)
			(copperpour not_allowed)
			(footprints allowed)
		)
		(placement
			(enabled no)
			(sheetname "")
		)
		(fill yes
			(thermal_gap 0.5)
			(thermal_bridge_width 0.5)
			(island_removal_mode 0)
		)
		(polygon
			(pts
				(arc
					(start 338.76107 -243.108988)
					(mid 338.10829 -243.108988)
					(end 338.76107 -243.108988)
				)
			)
		)
	)
	(zone
		(layers "B.Cu" "In4.Cu" "In6.Cu" "In11.Cu" "In13.Cu" "In15.Cu")
		(hatch none 0.5)
		(connect_pads
			(clearance 0)
		)
		(min_thickness 0.25)
		(keepout
			(tracks not_allowed)
			(vias allowed)
			(pads allowed)
			(copperpour not_allowed)
			(footprints allowed)
		)
		(placement
			(enabled no)
			(sheetname "")
		)
		(fill yes
			(thermal_gap 0.5)
			(thermal_bridge_width 0.5)
			(island_removal_mode 0)
		)
		(polygon
			(pts
				(arc
					(start 329.701398 -400.858228)
					(mid 328.997818 -400.858228)
					(end 329.701398 -400.858228)
				)
			)
		)
	)
	(zone
		(layers "B.Cu" "In4.Cu" "In6.Cu" "In11.Cu" "In13.Cu" "In15.Cu")
		(hatch none 0.5)
		(connect_pads
			(clearance 0)
		)
		(min_thickness 0.25)
		(keepout
			(tracks not_allowed)
			(vias allowed)
			(pads allowed)
			(copperpour not_allowed)
			(footprints allowed)
		)
		(placement
			(enabled no)
			(sheetname "")
		)
		(fill yes
			(thermal_gap 0.5)
			(thermal_bridge_width 0.5)
			(island_removal_mode 0)
		)
		(polygon
			(pts
				(arc
					(start 336.411824 -227.64496)
					(mid 335.759044 -227.64496)
					(end 336.411824 -227.64496)
				)
			)
		)
	)
	(zone
		(layers "B.Cu" "In4.Cu" "In6.Cu" "In11.Cu" "In13.Cu" "In15.Cu")
		(hatch none 0.5)
		(connect_pads
			(clearance 0)
		)
		(min_thickness 0.25)
		(keepout
			(tracks not_allowed)
			(vias allowed)
			(pads allowed)
			(copperpour not_allowed)
			(footprints allowed)
		)
		(placement
			(enabled no)
			(sheetname "")
		)
		(fill yes
			(thermal_gap 0.5)
			(thermal_bridge_width 0.5)
			(island_removal_mode 0)
		)
		(polygon
			(pts
				(arc
					(start 381.632206 -268.569694)
					(mid 380.979426 -268.569694)
					(end 381.632206 -268.569694)
				)
			)
		)
	)
	(zone
		(layers "B.Cu" "In4.Cu" "In6.Cu" "In11.Cu" "In13.Cu" "In15.Cu")
		(hatch none 0.5)
		(connect_pads
			(clearance 0)
		)
		(min_thickness 0.25)
		(keepout
			(tracks not_allowed)
			(vias allowed)
			(pads allowed)
			(copperpour not_allowed)
			(footprints allowed)
		)
		(placement
			(enabled no)
			(sheetname "")
		)
		(fill yes
			(thermal_gap 0.5)
			(thermal_bridge_width 0.5)
			(island_removal_mode 0)
		)
		(polygon
			(pts
				(arc
					(start 133.582156 -234.15625)
					(mid 132.929376 -234.15625)
					(end 133.582156 -234.15625)
				)
			)
		)
	)
	(zone
		(layers "B.Cu" "In4.Cu" "In6.Cu" "In11.Cu" "In13.Cu" "In15.Cu")
		(hatch none 0.5)
		(connect_pads
			(clearance 0)
		)
		(min_thickness 0.25)
		(keepout
			(tracks not_allowed)
			(vias allowed)
			(pads allowed)
			(copperpour not_allowed)
			(footprints allowed)
		)
		(placement
			(enabled no)
			(sheetname "")
		)
		(fill yes
			(thermal_gap 0.5)
			(thermal_bridge_width 0.5)
			(island_removal_mode 0)
		)
		(polygon
			(pts
				(arc
					(start 90.351356 -243.922804)
					(mid 89.698576 -243.922804)
					(end 90.351356 -243.922804)
				)
			)
		)
	)
	(zone
		(layers "B.Cu" "In4.Cu" "In6.Cu" "In11.Cu" "In13.Cu" "In15.Cu")
		(hatch none 0.5)
		(connect_pads
			(clearance 0)
		)
		(min_thickness 0.25)
		(keepout
			(tracks not_allowed)
			(vias allowed)
			(pads allowed)
			(copperpour not_allowed)
			(footprints allowed)
		)
		(placement
			(enabled no)
			(sheetname "")
		)
		(fill yes
			(thermal_gap 0.5)
			(thermal_bridge_width 0.5)
			(island_removal_mode 0)
		)
		(polygon
			(pts
				(arc
					(start 133.582156 -229.272846)
					(mid 132.929376 -229.272846)
					(end 133.582156 -229.272846)
				)
			)
		)
	)
	(zone
		(layers "B.Cu" "In4.Cu" "In6.Cu" "In11.Cu" "In13.Cu" "In15.Cu")
		(hatch none 0.5)
		(connect_pads
			(clearance 0)
		)
		(min_thickness 0.25)
		(keepout
			(tracks not_allowed)
			(vias allowed)
			(pads allowed)
			(copperpour not_allowed)
			(footprints allowed)
		)
		(placement
			(enabled no)
			(sheetname "")
		)
		(fill yes
			(thermal_gap 0.5)
			(thermal_bridge_width 0.5)
			(island_removal_mode 0)
		)
		(polygon
			(pts
				(arc
					(start 111.966756 -224.389442)
					(mid 111.313976 -224.389442)
					(end 111.966756 -224.389442)
				)
			)
		)
	)
	(zone
		(layers "B.Cu" "In4.Cu" "In6.Cu" "In11.Cu" "In13.Cu" "In15.Cu")
		(hatch none 0.5)
		(connect_pads
			(clearance 0)
		)
		(min_thickness 0.25)
		(keepout
			(tracks not_allowed)
			(vias allowed)
			(pads allowed)
			(copperpour not_allowed)
			(footprints allowed)
		)
		(placement
			(enabled no)
			(sheetname "")
		)
		(fill yes
			(thermal_gap 0.5)
			(thermal_bridge_width 0.5)
			(island_removal_mode 0)
		)
		(polygon
			(pts
				(arc
					(start 363.196124 -223.575626)
					(mid 362.543344 -223.575626)
					(end 363.196124 -223.575626)
				)
			)
		)
	)
	(zone
		(layers "B.Cu" "In4.Cu" "In6.Cu" "In11.Cu" "In13.Cu" "In15.Cu")
		(hatch none 0.5)
		(connect_pads
			(clearance 0)
		)
		(min_thickness 0.25)
		(keepout
			(tracks not_allowed)
			(vias allowed)
			(pads allowed)
			(copperpour not_allowed)
			(footprints allowed)
		)
		(placement
			(enabled no)
			(sheetname "")
		)
		(fill yes
			(thermal_gap 0.5)
			(thermal_bridge_width 0.5)
			(island_removal_mode 0)
		)
		(polygon
			(pts
				(arc
					(start 433.506626 -19.125438)
					(mid 432.803046 -19.125438)
					(end 433.506626 -19.125438)
				)
			)
		)
	)
	(zone
		(layers "B.Cu" "In4.Cu" "In6.Cu" "In11.Cu" "In13.Cu" "In15.Cu")
		(hatch none 0.5)
		(connect_pads
			(clearance 0)
		)
		(min_thickness 0.25)
		(keepout
			(tracks not_allowed)
			(vias allowed)
			(pads allowed)
			(copperpour not_allowed)
			(footprints allowed)
		)
		(placement
			(enabled no)
			(sheetname "")
		)
		(fill yes
			(thermal_gap 0.5)
			(thermal_bridge_width 0.5)
			(island_removal_mode 0)
		)
		(polygon
			(pts
				(arc
					(start 51.390804 -220.266768)
					(mid 50.738024 -220.266768)
					(end 51.390804 -220.266768)
				)
			)
		)
	)
	(zone
		(layers "B.Cu" "In4.Cu" "In6.Cu" "In11.Cu" "In13.Cu" "In15.Cu")
		(hatch none 0.5)
		(connect_pads
			(clearance 0)
		)
		(min_thickness 0.25)
		(keepout
			(tracks not_allowed)
			(vias allowed)
			(pads allowed)
			(copperpour not_allowed)
			(footprints allowed)
		)
		(placement
			(enabled no)
			(sheetname "")
		)
		(fill yes
			(thermal_gap 0.5)
			(thermal_bridge_width 0.5)
			(island_removal_mode 0)
		)
		(polygon
			(pts
				(arc
					(start 89.411556 -242.294918)
					(mid 88.758776 -242.294918)
					(end 89.411556 -242.294918)
				)
			)
		)
	)
	(zone
		(layers "B.Cu" "In4.Cu" "In6.Cu" "In11.Cu" "In13.Cu" "In15.Cu")
		(hatch none 0.5)
		(connect_pads
			(clearance 0)
		)
		(min_thickness 0.25)
		(keepout
			(tracks not_allowed)
			(vias allowed)
			(pads allowed)
			(copperpour not_allowed)
			(footprints allowed)
		)
		(placement
			(enabled no)
			(sheetname "")
		)
		(fill yes
			(thermal_gap 0.5)
			(thermal_bridge_width 0.5)
			(island_removal_mode 0)
		)
		(polygon
			(pts
				(arc
					(start 421.062404 -216.866724)
					(mid 420.409624 -216.866724)
					(end 421.062404 -216.866724)
				)
			)
		)
	)
	(zone
		(layers "B.Cu" "In4.Cu" "In6.Cu" "In11.Cu" "In13.Cu" "In15.Cu")
		(hatch none 0.5)
		(connect_pads
			(clearance 0)
		)
		(min_thickness 0.25)
		(keepout
			(tracks not_allowed)
			(vias allowed)
			(pads allowed)
			(copperpour not_allowed)
			(footprints allowed)
		)
		(placement
			(enabled no)
			(sheetname "")
		)
		(fill yes
			(thermal_gap 0.5)
			(thermal_bridge_width 0.5)
			(island_removal_mode 0)
		)
		(polygon
			(pts
				(arc
					(start 51.390804 -250.016772)
					(mid 50.738024 -250.016772)
					(end 51.390804 -250.016772)
				)
			)
		)
	)
	(zone
		(layers "B.Cu" "In4.Cu" "In6.Cu" "In11.Cu" "In13.Cu" "In15.Cu")
		(hatch none 0.5)
		(connect_pads
			(clearance 0)
		)
		(min_thickness 0.25)
		(keepout
			(tracks not_allowed)
			(vias allowed)
			(pads allowed)
			(copperpour not_allowed)
			(footprints allowed)
		)
		(placement
			(enabled no)
			(sheetname "")
		)
		(fill yes
			(thermal_gap 0.5)
			(thermal_bridge_width 0.5)
			(island_removal_mode 0)
		)
		(polygon
			(pts
				(arc
					(start 47.290736 -211.766658)
					(mid 46.637956 -211.766658)
					(end 47.290736 -211.766658)
				)
			)
		)
	)
	(zone
		(layers "B.Cu" "In4.Cu" "In6.Cu" "In11.Cu" "In13.Cu" "In15.Cu")
		(hatch none 0.5)
		(connect_pads
			(clearance 0)
		)
		(min_thickness 0.25)
		(keepout
			(tracks not_allowed)
			(vias allowed)
			(pads allowed)
			(copperpour not_allowed)
			(footprints allowed)
		)
		(placement
			(enabled no)
			(sheetname "")
		)
		(fill yes
			(thermal_gap 0.5)
			(thermal_bridge_width 0.5)
			(island_removal_mode 0)
		)
		(polygon
			(pts
				(arc
					(start 338.401152 -286.475424)
					(mid 337.748372 -286.475424)
					(end 338.401152 -286.475424)
				)
			)
		)
	)
	(zone
		(layers "B.Cu" "In4.Cu" "In6.Cu" "In11.Cu" "In13.Cu" "In15.Cu")
		(hatch none 0.5)
		(connect_pads
			(clearance 0)
		)
		(min_thickness 0.25)
		(keepout
			(tracks not_allowed)
			(vias allowed)
			(pads allowed)
			(copperpour not_allowed)
			(footprints allowed)
		)
		(placement
			(enabled no)
			(sheetname "")
		)
		(fill yes
			(thermal_gap 0.5)
			(thermal_bridge_width 0.5)
			(island_removal_mode 0)
		)
		(polygon
			(pts
				(arc
					(start 88.581484 -255.547622)
					(mid 87.928704 -255.547622)
					(end 88.581484 -255.547622)
				)
			)
		)
	)
	(zone
		(layers "B.Cu" "In4.Cu" "In6.Cu" "In11.Cu" "In13.Cu" "In15.Cu")
		(hatch none 0.5)
		(connect_pads
			(clearance 0)
		)
		(min_thickness 0.25)
		(keepout
			(tracks not_allowed)
			(vias allowed)
			(pads allowed)
			(copperpour not_allowed)
			(footprints allowed)
		)
		(placement
			(enabled no)
			(sheetname "")
		)
		(fill yes
			(thermal_gap 0.5)
			(thermal_bridge_width 0.5)
			(island_removal_mode 0)
		)
		(polygon
			(pts
				(arc
					(start 62.378336 -232.166668)
					(mid 61.725556 -232.166668)
					(end 62.378336 -232.166668)
				)
			)
		)
	)
	(zone
		(layers "B.Cu" "In4.Cu" "In6.Cu" "In11.Cu" "In13.Cu" "In15.Cu")
		(hatch none 0.5)
		(connect_pads
			(clearance 0)
		)
		(min_thickness 0.25)
		(keepout
			(tracks not_allowed)
			(vias allowed)
			(pads allowed)
			(copperpour not_allowed)
			(footprints allowed)
		)
		(placement
			(enabled no)
			(sheetname "")
		)
		(fill yes
			(thermal_gap 0.5)
			(thermal_bridge_width 0.5)
			(island_removal_mode 0)
		)
		(polygon
			(pts
				(arc
					(start 432.706272 -260.21665)
					(mid 432.053492 -260.21665)
					(end 432.706272 -260.21665)
				)
			)
		)
	)
	(zone
		(layers "B.Cu" "In4.Cu" "In6.Cu" "In11.Cu" "In13.Cu" "In15.Cu")
		(hatch none 0.5)
		(connect_pads
			(clearance 0)
		)
		(min_thickness 0.25)
		(keepout
			(tracks not_allowed)
			(vias allowed)
			(pads allowed)
			(copperpour not_allowed)
			(footprints allowed)
		)
		(placement
			(enabled no)
			(sheetname "")
		)
		(fill yes
			(thermal_gap 0.5)
			(thermal_bridge_width 0.5)
			(island_removal_mode 0)
		)
		(polygon
			(pts
				(arc
					(start 44.131484 -17.61236)
					(mid 43.427904 -17.61236)
					(end 44.131484 -17.61236)
				)
			)
		)
	)
	(zone
		(layers "B.Cu" "In4.Cu" "In6.Cu" "In11.Cu" "In13.Cu" "In15.Cu")
		(hatch none 0.5)
		(connect_pads
			(clearance 0)
		)
		(min_thickness 0.25)
		(keepout
			(tracks not_allowed)
			(vias allowed)
			(pads allowed)
			(copperpour not_allowed)
			(footprints allowed)
		)
		(placement
			(enabled no)
			(sheetname "")
		)
		(fill yes
			(thermal_gap 0.5)
			(thermal_bridge_width 0.5)
			(island_removal_mode 0)
		)
		(polygon
			(pts
				(arc
					(start 365.07547 -223.575626)
					(mid 364.42269 -223.575626)
					(end 365.07547 -223.575626)
				)
			)
		)
	)
	(zone
		(layers "B.Cu" "In4.Cu" "In6.Cu" "In11.Cu" "In13.Cu" "In15.Cu")
		(hatch none 0.5)
		(connect_pads
			(clearance 0)
		)
		(min_thickness 0.25)
		(keepout
			(tracks not_allowed)
			(vias allowed)
			(pads allowed)
			(copperpour not_allowed)
			(footprints allowed)
		)
		(placement
			(enabled no)
			(sheetname "")
		)
		(fill yes
			(thermal_gap 0.5)
			(thermal_bridge_width 0.5)
			(island_removal_mode 0)
		)
		(polygon
			(pts
				(arc
					(start 89.521284 -273.453098)
					(mid 88.868504 -273.453098)
					(end 89.521284 -273.453098)
				)
			)
		)
	)
	(zone
		(layers "B.Cu" "In4.Cu" "In6.Cu" "In11.Cu" "In13.Cu" "In15.Cu")
		(hatch none 0.5)
		(connect_pads
			(clearance 0)
		)
		(min_thickness 0.25)
		(keepout
			(tracks not_allowed)
			(vias allowed)
			(pads allowed)
			(copperpour not_allowed)
			(footprints allowed)
		)
		(placement
			(enabled no)
			(sheetname "")
		)
		(fill yes
			(thermal_gap 0.5)
			(thermal_bridge_width 0.5)
			(island_removal_mode 0)
		)
		(polygon
			(pts
				(arc
					(start 89.411556 -227.64496)
					(mid 88.758776 -227.64496)
					(end 89.411556 -227.64496)
				)
			)
		)
	)
	(zone
		(layers "B.Cu" "In4.Cu" "In6.Cu" "In11.Cu" "In13.Cu" "In15.Cu")
		(hatch none 0.5)
		(connect_pads
			(clearance 0)
		)
		(min_thickness 0.25)
		(keepout
			(tracks not_allowed)
			(vias allowed)
			(pads allowed)
			(copperpour not_allowed)
			(footprints allowed)
		)
		(placement
			(enabled no)
			(sheetname "")
		)
		(fill yes
			(thermal_gap 0.5)
			(thermal_bridge_width 0.5)
			(island_removal_mode 0)
		)
		(polygon
			(pts
				(arc
					(start 295.46423 -163.096448)
					(mid 294.76065 -163.096448)
					(end 295.46423 -163.096448)
				)
			)
		)
	)
	(zone
		(layers "B.Cu" "In4.Cu" "In6.Cu" "In11.Cu" "In13.Cu" "In15.Cu")
		(hatch none 0.5)
		(connect_pads
			(clearance 0)
		)
		(min_thickness 0.25)
		(keepout
			(tracks not_allowed)
			(vias allowed)
			(pads allowed)
			(copperpour not_allowed)
			(footprints allowed)
		)
		(placement
			(enabled no)
			(sheetname "")
		)
		(fill yes
			(thermal_gap 0.5)
			(thermal_bridge_width 0.5)
			(island_removal_mode 0)
		)
		(polygon
			(pts
				(arc
					(start 370.354606 -286.475424)
					(mid 369.701826 -286.475424)
					(end 370.354606 -286.475424)
				)
			)
		)
	)
	(zone
		(layers "B.Cu" "In4.Cu" "In6.Cu" "In11.Cu" "In13.Cu" "In15.Cu")
		(hatch none 0.5)
		(connect_pads
			(clearance 0)
		)
		(min_thickness 0.25)
		(keepout
			(tracks not_allowed)
			(vias allowed)
			(pads allowed)
			(copperpour not_allowed)
			(footprints allowed)
		)
		(placement
			(enabled no)
			(sheetname "")
		)
		(fill yes
			(thermal_gap 0.5)
			(thermal_bridge_width 0.5)
			(island_removal_mode 0)
		)
		(polygon
			(pts
				(arc
					(start 339.231224 -232.528364)
					(mid 338.578444 -232.528364)
					(end 339.231224 -232.528364)
				)
			)
		)
	)
	(zone
		(layers "B.Cu" "In4.Cu" "In6.Cu" "In11.Cu" "In13.Cu" "In15.Cu")
		(hatch none 0.5)
		(connect_pads
			(clearance 0)
		)
		(min_thickness 0.25)
		(keepout
			(tracks not_allowed)
			(vias allowed)
			(pads allowed)
			(copperpour not_allowed)
			(footprints allowed)
		)
		(placement
			(enabled no)
			(sheetname "")
		)
		(fill yes
			(thermal_gap 0.5)
			(thermal_bridge_width 0.5)
			(island_removal_mode 0)
		)
		(polygon
			(pts
				(arc
					(start 295.230804 -314.616592)
					(mid 294.578024 -314.616592)
					(end 295.230804 -314.616592)
				)
			)
		)
	)
	(zone
		(layers "B.Cu" "In4.Cu" "In6.Cu" "In11.Cu" "In13.Cu" "In15.Cu")
		(hatch none 0.5)
		(connect_pads
			(clearance 0)
		)
		(min_thickness 0.25)
		(keepout
			(tracks not_allowed)
			(vias allowed)
			(pads allowed)
			(copperpour not_allowed)
			(footprints allowed)
		)
		(placement
			(enabled no)
			(sheetname "")
		)
		(fill yes
			(thermal_gap 0.5)
			(thermal_bridge_width 0.5)
			(island_removal_mode 0)
		)
		(polygon
			(pts
				(arc
					(start 314.418472 -229.616762)
					(mid 313.765692 -229.616762)
					(end 314.418472 -229.616762)
				)
			)
		)
	)
	(zone
		(layers "B.Cu" "In4.Cu" "In6.Cu" "In11.Cu" "In13.Cu" "In15.Cu")
		(hatch none 0.5)
		(connect_pads
			(clearance 0)
		)
		(min_thickness 0.25)
		(keepout
			(tracks not_allowed)
			(vias allowed)
			(pads allowed)
			(copperpour not_allowed)
			(footprints allowed)
		)
		(placement
			(enabled no)
			(sheetname "")
		)
		(fill yes
			(thermal_gap 0.5)
			(thermal_bridge_width 0.5)
			(island_removal_mode 0)
		)
		(polygon
			(pts
				(arc
					(start 337.351624 -232.528364)
					(mid 336.698844 -232.528364)
					(end 337.351624 -232.528364)
				)
			)
		)
	)
	(zone
		(layers "B.Cu" "In4.Cu" "In6.Cu" "In11.Cu" "In13.Cu" "In15.Cu")
		(hatch none 0.5)
		(connect_pads
			(clearance 0)
		)
		(min_thickness 0.25)
		(keepout
			(tracks not_allowed)
			(vias allowed)
			(pads allowed)
			(copperpour not_allowed)
			(footprints allowed)
		)
		(placement
			(enabled no)
			(sheetname "")
		)
		(fill yes
			(thermal_gap 0.5)
			(thermal_bridge_width 0.5)
			(island_removal_mode 0)
		)
		(polygon
			(pts
				(arc
					(start 62.378336 -303.566576)
					(mid 61.725556 -303.566576)
					(end 62.378336 -303.566576)
				)
			)
		)
	)
	(zone
		(layers "B.Cu" "In4.Cu" "In6.Cu" "In11.Cu" "In13.Cu" "In15.Cu")
		(hatch none 0.5)
		(connect_pads
			(clearance 0)
		)
		(min_thickness 0.25)
		(keepout
			(tracks not_allowed)
			(vias allowed)
			(pads allowed)
			(copperpour not_allowed)
			(footprints allowed)
		)
		(placement
			(enabled no)
			(sheetname "")
		)
		(fill yes
			(thermal_gap 0.5)
			(thermal_bridge_width 0.5)
			(island_removal_mode 0)
		)
		(polygon
			(pts
				(arc
					(start 88.941402 -233.34218)
					(mid 88.288622 -233.34218)
					(end 88.941402 -233.34218)
				)
			)
		)
	)
	(zone
		(layers "B.Cu" "In4.Cu" "In6.Cu" "In11.Cu" "In13.Cu" "In15.Cu")
		(hatch none 0.5)
		(connect_pads
			(clearance 0)
		)
		(min_thickness 0.25)
		(keepout
			(tracks not_allowed)
			(vias allowed)
			(pads allowed)
			(copperpour not_allowed)
			(footprints allowed)
		)
		(placement
			(enabled no)
			(sheetname "")
		)
		(fill yes
			(thermal_gap 0.5)
			(thermal_bridge_width 0.5)
			(island_removal_mode 0)
		)
		(polygon
			(pts
				(arc
					(start 177.222404 -218.566746)
					(mid 176.569624 -218.566746)
					(end 177.222404 -218.566746)
				)
			)
		)
	)
	(zone
		(layers "B.Cu" "In4.Cu" "In6.Cu" "In11.Cu" "In13.Cu" "In15.Cu")
		(hatch none 0.5)
		(connect_pads
			(clearance 0)
		)
		(min_thickness 0.25)
		(keepout
			(tracks not_allowed)
			(vias allowed)
			(pads allowed)
			(copperpour not_allowed)
			(footprints allowed)
		)
		(placement
			(enabled no)
			(sheetname "")
		)
		(fill yes
			(thermal_gap 0.5)
			(thermal_bridge_width 0.5)
			(island_removal_mode 0)
		)
		(polygon
			(pts
				(arc
					(start 173.122336 -312.91657)
					(mid 172.469556 -312.91657)
					(end 173.122336 -312.91657)
				)
			)
		)
	)
	(zone
		(layers "B.Cu" "In4.Cu" "In6.Cu" "In11.Cu" "In13.Cu" "In15.Cu")
		(hatch none 0.5)
		(connect_pads
			(clearance 0)
		)
		(min_thickness 0.25)
		(keepout
			(tracks not_allowed)
			(vias allowed)
			(pads allowed)
			(copperpour not_allowed)
			(footprints allowed)
		)
		(placement
			(enabled no)
			(sheetname "")
		)
		(fill yes
			(thermal_gap 0.5)
			(thermal_bridge_width 0.5)
			(island_removal_mode 0)
		)
		(polygon
			(pts
				(arc
					(start 425.162472 -208.366614)
					(mid 424.509692 -208.366614)
					(end 425.162472 -208.366614)
				)
			)
		)
	)
	(zone
		(layers "B.Cu" "In4.Cu" "In6.Cu" "In11.Cu" "In13.Cu" "In15.Cu")
		(hatch none 0.5)
		(connect_pads
			(clearance 0)
		)
		(min_thickness 0.25)
		(keepout
			(tracks not_allowed)
			(vias allowed)
			(pads allowed)
			(copperpour not_allowed)
			(footprints allowed)
		)
		(placement
			(enabled no)
			(sheetname "")
		)
		(fill yes
			(thermal_gap 0.5)
			(thermal_bridge_width 0.5)
			(island_removal_mode 0)
		)
		(polygon
			(pts
				(arc
					(start 55.34152 -17.61236)
					(mid 54.63794 -17.61236)
					(end 55.34152 -17.61236)
				)
			)
		)
	)
	(zone
		(layers "B.Cu" "In4.Cu" "In6.Cu" "In11.Cu" "In13.Cu" "In15.Cu")
		(hatch none 0.5)
		(connect_pads
			(clearance 0)
		)
		(min_thickness 0.25)
		(keepout
			(tracks not_allowed)
			(vias allowed)
			(pads allowed)
			(copperpour not_allowed)
			(footprints allowed)
		)
		(placement
			(enabled no)
			(sheetname "")
		)
		(fill yes
			(thermal_gap 0.5)
			(thermal_bridge_width 0.5)
			(island_removal_mode 0)
		)
		(polygon
			(pts
				(arc
					(start 354.268024 -224.389442)
					(mid 353.615244 -224.389442)
					(end 354.268024 -224.389442)
				)
			)
		)
	)
	(zone
		(layers "B.Cu" "In4.Cu" "In6.Cu" "In11.Cu" "In13.Cu" "In15.Cu")
		(hatch none 0.5)
		(connect_pads
			(clearance 0)
		)
		(min_thickness 0.25)
		(keepout
			(tracks not_allowed)
			(vias allowed)
			(pads allowed)
			(copperpour not_allowed)
			(footprints allowed)
		)
		(placement
			(enabled no)
			(sheetname "")
		)
		(fill yes
			(thermal_gap 0.5)
			(thermal_bridge_width 0.5)
			(island_removal_mode 0)
		)
		(polygon
			(pts
				(arc
					(start 35.443668 -19.13636)
					(mid 34.740088 -19.13636)
					(end 35.443668 -19.13636)
				)
			)
		)
	)
	(zone
		(layers "B.Cu" "In4.Cu" "In6.Cu" "In11.Cu" "In13.Cu" "In15.Cu")
		(hatch none 0.5)
		(connect_pads
			(clearance 0)
		)
		(min_thickness 0.25)
		(keepout
			(tracks not_allowed)
			(vias allowed)
			(pads allowed)
			(copperpour not_allowed)
			(footprints allowed)
		)
		(placement
			(enabled no)
			(sheetname "")
		)
		(fill yes
			(thermal_gap 0.5)
			(thermal_bridge_width 0.5)
			(island_removal_mode 0)
		)
		(polygon
			(pts
				(arc
					(start 353.328224 -224.389442)
					(mid 352.675444 -224.389442)
					(end 353.328224 -224.389442)
				)
			)
		)
	)
	(zone
		(layers "B.Cu" "In4.Cu" "In6.Cu" "In11.Cu" "In13.Cu" "In15.Cu")
		(hatch none 0.5)
		(connect_pads
			(clearance 0)
		)
		(min_thickness 0.25)
		(keepout
			(tracks not_allowed)
			(vias allowed)
			(pads allowed)
			(copperpour not_allowed)
			(footprints allowed)
		)
		(placement
			(enabled no)
			(sheetname "")
		)
		(fill yes
			(thermal_gap 0.5)
			(thermal_bridge_width 0.5)
			(island_removal_mode 0)
		)
		(polygon
			(pts
				(arc
					(start 295.230804 -262.76681)
					(mid 294.578024 -262.76681)
					(end 295.230804 -262.76681)
				)
			)
		)
	)
	(zone
		(layers "B.Cu" "In4.Cu" "In6.Cu" "In11.Cu" "In13.Cu" "In15.Cu")
		(hatch none 0.5)
		(connect_pads
			(clearance 0)
		)
		(min_thickness 0.25)
		(keepout
			(tracks not_allowed)
			(vias allowed)
			(pads allowed)
			(copperpour not_allowed)
			(footprints allowed)
		)
		(placement
			(enabled no)
			(sheetname "")
		)
		(fill yes
			(thermal_gap 0.5)
			(thermal_bridge_width 0.5)
			(island_removal_mode 0)
		)
		(polygon
			(pts
				(arc
					(start 134.052056 -241.481102)
					(mid 133.399276 -241.481102)
					(end 134.052056 -241.481102)
				)
			)
		)
	)
	(zone
		(layers "B.Cu" "In4.Cu" "In6.Cu" "In11.Cu" "In13.Cu" "In15.Cu")
		(hatch none 0.5)
		(connect_pads
			(clearance 0)
		)
		(min_thickness 0.25)
		(keepout
			(tracks not_allowed)
			(vias allowed)
			(pads allowed)
			(copperpour not_allowed)
			(footprints allowed)
		)
		(placement
			(enabled no)
			(sheetname "")
		)
		(fill yes
			(thermal_gap 0.5)
			(thermal_bridge_width 0.5)
			(island_removal_mode 0)
		)
		(polygon
			(pts
				(arc
					(start 94.580202 -249.620024)
					(mid 93.927422 -249.620024)
					(end 94.580202 -249.620024)
				)
			)
		)
	)
	(zone
		(layers "B.Cu" "In4.Cu" "In6.Cu" "In11.Cu" "In13.Cu" "In15.Cu")
		(hatch none 0.5)
		(connect_pads
			(clearance 0)
		)
		(min_thickness 0.25)
		(keepout
			(tracks not_allowed)
			(vias allowed)
			(pads allowed)
			(copperpour not_allowed)
			(footprints allowed)
		)
		(placement
			(enabled no)
			(sheetname "")
		)
		(fill yes
			(thermal_gap 0.5)
			(thermal_bridge_width 0.5)
			(island_removal_mode 0)
		)
		(polygon
			(pts
				(arc
					(start 394.050774 -19.125438)
					(mid 393.347194 -19.125438)
					(end 394.050774 -19.125438)
				)
			)
		)
	)
	(zone
		(layers "B.Cu" "In4.Cu" "In6.Cu" "In11.Cu" "In13.Cu" "In15.Cu")
		(hatch none 0.5)
		(connect_pads
			(clearance 0)
		)
		(min_thickness 0.25)
		(keepout
			(tracks not_allowed)
			(vias allowed)
			(pads allowed)
			(copperpour not_allowed)
			(footprints allowed)
		)
		(placement
			(enabled no)
			(sheetname "")
		)
		(fill yes
			(thermal_gap 0.5)
			(thermal_bridge_width 0.5)
			(island_removal_mode 0)
		)
		(polygon
			(pts
				(arc
					(start 93.750384 -285.661354)
					(mid 93.097604 -285.661354)
					(end 93.750384 -285.661354)
				)
			)
		)
	)
	(zone
		(layers "B.Cu" "In4.Cu" "In6.Cu" "In11.Cu" "In13.Cu" "In15.Cu")
		(hatch none 0.5)
		(connect_pads
			(clearance 0)
		)
		(min_thickness 0.25)
		(keepout
			(tracks not_allowed)
			(vias allowed)
			(pads allowed)
			(copperpour not_allowed)
			(footprints allowed)
		)
		(placement
			(enabled no)
			(sheetname "")
		)
		(fill yes
			(thermal_gap 0.5)
			(thermal_bridge_width 0.5)
			(island_removal_mode 0)
		)
		(polygon
			(pts
				(arc
					(start 98.449384 -285.661354)
					(mid 97.796604 -285.661354)
					(end 98.449384 -285.661354)
				)
			)
		)
	)
	(zone
		(layers "B.Cu" "In4.Cu" "In6.Cu" "In11.Cu" "In13.Cu" "In15.Cu")
		(hatch none 0.5)
		(connect_pads
			(clearance 0)
		)
		(min_thickness 0.25)
		(keepout
			(tracks not_allowed)
			(vias allowed)
			(pads allowed)
			(copperpour not_allowed)
			(footprints allowed)
		)
		(placement
			(enabled no)
			(sheetname "")
		)
		(fill yes
			(thermal_gap 0.5)
			(thermal_bridge_width 0.5)
			(island_removal_mode 0)
		)
		(polygon
			(pts
				(arc
					(start 135.571738 -268.569694)
					(mid 134.918958 -268.569694)
					(end 135.571738 -268.569694)
				)
			)
		)
	)
	(zone
		(layers "B.Cu" "In4.Cu" "In6.Cu" "In11.Cu" "In13.Cu" "In15.Cu")
		(hatch none 0.5)
		(connect_pads
			(clearance 0)
		)
		(min_thickness 0.25)
		(keepout
			(tracks not_allowed)
			(vias allowed)
			(pads allowed)
			(copperpour not_allowed)
			(footprints allowed)
		)
		(placement
			(enabled no)
			(sheetname "")
		)
		(fill yes
			(thermal_gap 0.5)
			(thermal_bridge_width 0.5)
			(island_removal_mode 0)
		)
		(polygon
			(pts
				(arc
					(start 95.626428 -407.00452)
					(mid 94.922848 -407.00452)
					(end 95.626428 -407.00452)
				)
			)
		)
	)
	(zone
		(layers "B.Cu" "In4.Cu" "In6.Cu" "In11.Cu" "In13.Cu" "In15.Cu")
		(hatch none 0.5)
		(connect_pads
			(clearance 0)
		)
		(min_thickness 0.25)
		(keepout
			(tracks not_allowed)
			(vias allowed)
			(pads allowed)
			(copperpour not_allowed)
			(footprints allowed)
		)
		(placement
			(enabled no)
			(sheetname "")
		)
		(fill yes
			(thermal_gap 0.5)
			(thermal_bridge_width 0.5)
			(island_removal_mode 0)
		)
		(polygon
			(pts
				(arc
					(start 51.390804 -251.716794)
					(mid 50.738024 -251.716794)
					(end 51.390804 -251.716794)
				)
			)
		)
	)
	(zone
		(layers "B.Cu" "In4.Cu" "In6.Cu" "In11.Cu" "In13.Cu" "In15.Cu")
		(hatch none 0.5)
		(connect_pads
			(clearance 0)
		)
		(min_thickness 0.25)
		(keepout
			(tracks not_allowed)
			(vias allowed)
			(pads allowed)
			(copperpour not_allowed)
			(footprints allowed)
		)
		(placement
			(enabled no)
			(sheetname "")
		)
		(fill yes
			(thermal_gap 0.5)
			(thermal_bridge_width 0.5)
			(island_removal_mode 0)
		)
		(polygon
			(pts
				(arc
					(start 299.330872 -220.266768)
					(mid 298.678092 -220.266768)
					(end 299.330872 -220.266768)
				)
			)
		)
	)
	(zone
		(layers "B.Cu" "In4.Cu" "In6.Cu" "In11.Cu" "In13.Cu" "In15.Cu")
		(hatch none 0.5)
		(connect_pads
			(clearance 0)
		)
		(min_thickness 0.25)
		(keepout
			(tracks not_allowed)
			(vias allowed)
			(pads allowed)
			(copperpour not_allowed)
			(footprints allowed)
		)
		(placement
			(enabled no)
			(sheetname "")
		)
		(fill yes
			(thermal_gap 0.5)
			(thermal_bridge_width 0.5)
			(island_removal_mode 0)
		)
		(polygon
			(pts
				(arc
					(start 51.416204 -276.366986)
					(mid 50.763424 -276.366986)
					(end 51.416204 -276.366986)
				)
			)
		)
	)
	(zone
		(layers "B.Cu" "In4.Cu" "In6.Cu" "In11.Cu" "In13.Cu" "In15.Cu")
		(hatch none 0.5)
		(connect_pads
			(clearance 0)
		)
		(min_thickness 0.25)
		(keepout
			(tracks not_allowed)
			(vias allowed)
			(pads allowed)
			(copperpour not_allowed)
			(footprints allowed)
		)
		(placement
			(enabled no)
			(sheetname "")
		)
		(fill yes
			(thermal_gap 0.5)
			(thermal_bridge_width 0.5)
			(island_removal_mode 0)
		)
		(polygon
			(pts
				(arc
					(start 130.402584 -256.361438)
					(mid 129.749804 -256.361438)
					(end 130.402584 -256.361438)
				)
			)
		)
	)
	(zone
		(layers "B.Cu" "In4.Cu" "In6.Cu" "In11.Cu" "In13.Cu" "In15.Cu")
		(hatch none 0.5)
		(connect_pads
			(clearance 0)
		)
		(min_thickness 0.25)
		(keepout
			(tracks not_allowed)
			(vias allowed)
			(pads allowed)
			(copperpour not_allowed)
			(footprints allowed)
		)
		(placement
			(enabled no)
			(sheetname "")
		)
		(fill yes
			(thermal_gap 0.5)
			(thermal_bridge_width 0.5)
			(island_removal_mode 0)
		)
		(polygon
			(pts
				(arc
					(start 133.112002 -244.73662)
					(mid 132.459222 -244.73662)
					(end 133.112002 -244.73662)
				)
			)
		)
	)
	(zone
		(layers "B.Cu" "In4.Cu" "In6.Cu" "In11.Cu" "In13.Cu" "In15.Cu")
		(hatch none 0.5)
		(connect_pads
			(clearance 0)
		)
		(min_thickness 0.25)
		(keepout
			(tracks not_allowed)
			(vias allowed)
			(pads allowed)
			(copperpour not_allowed)
			(footprints allowed)
		)
		(placement
			(enabled no)
			(sheetname "")
		)
		(fill yes
			(thermal_gap 0.5)
			(thermal_bridge_width 0.5)
			(island_removal_mode 0)
		)
		(polygon
			(pts
				(arc
					(start 62.378336 -227.91674)
					(mid 61.725556 -227.91674)
					(end 62.378336 -227.91674)
				)
			)
		)
	)
	(zone
		(layers "B.Cu" "In4.Cu" "In6.Cu" "In11.Cu" "In13.Cu" "In15.Cu")
		(hatch none 0.5)
		(connect_pads
			(clearance 0)
		)
		(min_thickness 0.25)
		(keepout
			(tracks not_allowed)
			(vias allowed)
			(pads allowed)
			(copperpour not_allowed)
			(footprints allowed)
		)
		(placement
			(enabled no)
			(sheetname "")
		)
		(fill yes
			(thermal_gap 0.5)
			(thermal_bridge_width 0.5)
			(island_removal_mode 0)
		)
		(polygon
			(pts
				(arc
					(start 383.511552 -263.686544)
					(mid 382.858772 -263.686544)
					(end 383.511552 -263.686544)
				)
			)
		)
	)
	(zone
		(layers "B.Cu" "In4.Cu" "In6.Cu" "In11.Cu" "In13.Cu" "In15.Cu")
		(hatch none 0.5)
		(connect_pads
			(clearance 0)
		)
		(min_thickness 0.25)
		(keepout
			(tracks not_allowed)
			(vias allowed)
			(pads allowed)
			(copperpour not_allowed)
			(footprints allowed)
		)
		(placement
			(enabled no)
			(sheetname "")
		)
		(fill yes
			(thermal_gap 0.5)
			(thermal_bridge_width 0.5)
			(island_removal_mode 0)
		)
		(polygon
			(pts
				(arc
					(start 358.027224 -224.389442)
					(mid 357.374444 -224.389442)
					(end 358.027224 -224.389442)
				)
			)
		)
	)
	(zone
		(layers "B.Cu" "In4.Cu" "In6.Cu" "In11.Cu" "In13.Cu" "In15.Cu")
		(hatch none 0.5)
		(connect_pads
			(clearance 0)
		)
		(min_thickness 0.25)
		(keepout
			(tracks not_allowed)
			(vias allowed)
			(pads allowed)
			(copperpour not_allowed)
			(footprints allowed)
		)
		(placement
			(enabled no)
			(sheetname "")
		)
		(fill yes
			(thermal_gap 0.5)
			(thermal_bridge_width 0.5)
			(island_removal_mode 0)
		)
		(polygon
			(pts
				(arc
					(start 425.162472 -238.966756)
					(mid 424.509692 -238.966756)
					(end 425.162472 -238.966756)
				)
			)
		)
	)
	(zone
		(layers "B.Cu" "In4.Cu" "In6.Cu" "In11.Cu" "In13.Cu" "In15.Cu")
		(hatch none 0.5)
		(connect_pads
			(clearance 0)
		)
		(min_thickness 0.25)
		(keepout
			(tracks not_allowed)
			(vias allowed)
			(pads allowed)
			(copperpour not_allowed)
			(footprints allowed)
		)
		(placement
			(enabled no)
			(sheetname "")
		)
		(fill yes
			(thermal_gap 0.5)
			(thermal_bridge_width 0.5)
			(island_removal_mode 0)
		)
		(polygon
			(pts
				(arc
					(start 368.004852 -285.661354)
					(mid 367.352072 -285.661354)
					(end 368.004852 -285.661354)
				)
			)
		)
	)
	(zone
		(layers "B.Cu" "In4.Cu" "In6.Cu" "In11.Cu" "In13.Cu" "In15.Cu")
		(hatch none 0.5)
		(connect_pads
			(clearance 0)
		)
		(min_thickness 0.25)
		(keepout
			(tracks not_allowed)
			(vias allowed)
			(pads allowed)
			(copperpour not_allowed)
			(footprints allowed)
		)
		(placement
			(enabled no)
			(sheetname "")
		)
		(fill yes
			(thermal_gap 0.5)
			(thermal_bridge_width 0.5)
			(island_removal_mode 0)
		)
		(polygon
			(pts
				(arc
					(start 89.411556 -235.783882)
					(mid 88.758776 -235.783882)
					(end 89.411556 -235.783882)
				)
			)
		)
	)
	(zone
		(layers "B.Cu" "In4.Cu" "In6.Cu" "In11.Cu" "In13.Cu" "In15.Cu")
		(hatch none 0.5)
		(connect_pads
			(clearance 0)
		)
		(min_thickness 0.25)
		(keepout
			(tracks not_allowed)
			(vias allowed)
			(pads allowed)
			(copperpour not_allowed)
			(footprints allowed)
		)
		(placement
			(enabled no)
			(sheetname "")
		)
		(fill yes
			(thermal_gap 0.5)
			(thermal_bridge_width 0.5)
			(island_removal_mode 0)
		)
		(polygon
			(pts
				(arc
					(start 299.330872 -204.96657)
					(mid 298.678092 -204.96657)
					(end 299.330872 -204.96657)
				)
			)
		)
	)
	(zone
		(layers "B.Cu" "In4.Cu" "In6.Cu" "In11.Cu" "In13.Cu" "In15.Cu")
		(hatch none 0.5)
		(connect_pads
			(clearance 0)
		)
		(min_thickness 0.25)
		(keepout
			(tracks not_allowed)
			(vias allowed)
			(pads allowed)
			(copperpour not_allowed)
			(footprints allowed)
		)
		(placement
			(enabled no)
			(sheetname "")
		)
		(fill yes
			(thermal_gap 0.5)
			(thermal_bridge_width 0.5)
			(island_removal_mode 0)
		)
		(polygon
			(pts
				(arc
					(start 51.416204 -273.816572)
					(mid 50.763424 -273.816572)
					(end 51.416204 -273.816572)
				)
			)
		)
	)
	(zone
		(layers "B.Cu" "In4.Cu" "In6.Cu" "In11.Cu" "In13.Cu" "In15.Cu")
		(hatch none 0.5)
		(connect_pads
			(clearance 0)
		)
		(min_thickness 0.25)
		(keepout
			(tracks not_allowed)
			(vias allowed)
			(pads allowed)
			(copperpour not_allowed)
			(footprints allowed)
		)
		(placement
			(enabled no)
			(sheetname "")
		)
		(fill yes
			(thermal_gap 0.5)
			(thermal_bridge_width 0.5)
			(island_removal_mode 0)
		)
		(polygon
			(pts
				(arc
					(start 135.101584 -262.872474)
					(mid 134.448804 -262.872474)
					(end 135.101584 -262.872474)
				)
			)
		)
	)
	(zone
		(layers "B.Cu" "In4.Cu" "In6.Cu" "In11.Cu" "In13.Cu" "In15.Cu")
		(hatch none 0.5)
		(connect_pads
			(clearance 0)
		)
		(min_thickness 0.25)
		(keepout
			(tracks not_allowed)
			(vias allowed)
			(pads allowed)
			(copperpour not_allowed)
			(footprints allowed)
		)
		(placement
			(enabled no)
			(sheetname "")
		)
		(fill yes
			(thermal_gap 0.5)
			(thermal_bridge_width 0.5)
			(island_removal_mode 0)
		)
		(polygon
			(pts
				(arc
					(start 158.009336 -224.516696)
					(mid 157.356556 -224.516696)
					(end 158.009336 -224.516696)
				)
			)
		)
	)
	(zone
		(layers "B.Cu" "In4.Cu" "In6.Cu" "In11.Cu" "In13.Cu" "In15.Cu")
		(hatch none 0.5)
		(connect_pads
			(clearance 0)
		)
		(min_thickness 0.25)
		(keepout
			(tracks not_allowed)
			(vias allowed)
			(pads allowed)
			(copperpour not_allowed)
			(footprints allowed)
		)
		(placement
			(enabled no)
			(sheetname "")
		)
		(fill yes
			(thermal_gap 0.5)
			(thermal_bridge_width 0.5)
			(island_removal_mode 0)
		)
		(polygon
			(pts
				(arc
					(start 104.558338 -284.847538)
					(mid 103.905558 -284.847538)
					(end 104.558338 -284.847538)
				)
			)
		)
	)
	(zone
		(layers "B.Cu" "In4.Cu" "In6.Cu" "In11.Cu" "In13.Cu" "In15.Cu")
		(hatch none 0.5)
		(connect_pads
			(clearance 0)
		)
		(min_thickness 0.25)
		(keepout
			(tracks not_allowed)
			(vias allowed)
			(pads allowed)
			(copperpour not_allowed)
			(footprints allowed)
		)
		(placement
			(enabled no)
			(sheetname "")
		)
		(fill yes
			(thermal_gap 0.5)
			(thermal_bridge_width 0.5)
			(island_removal_mode 0)
		)
		(polygon
			(pts
				(arc
					(start 425.162472 -290.816538)
					(mid 424.509692 -290.816538)
					(end 425.162472 -290.816538)
				)
			)
		)
	)
	(zone
		(layers "B.Cu" "In4.Cu" "In6.Cu" "In11.Cu" "In13.Cu" "In15.Cu")
		(hatch none 0.5)
		(connect_pads
			(clearance 0)
		)
		(min_thickness 0.25)
		(keepout
			(tracks not_allowed)
			(vias allowed)
			(pads allowed)
			(copperpour not_allowed)
			(footprints allowed)
		)
		(placement
			(enabled no)
			(sheetname "")
		)
		(fill yes
			(thermal_gap 0.5)
			(thermal_bridge_width 0.5)
			(island_removal_mode 0)
		)
		(polygon
			(pts
				(arc
					(start 162.109404 -227.91674)
					(mid 161.456624 -227.91674)
					(end 162.109404 -227.91674)
				)
			)
		)
	)
	(zone
		(layers "B.Cu" "In4.Cu" "In6.Cu" "In11.Cu" "In13.Cu" "In15.Cu")
		(hatch none 0.5)
		(connect_pads
			(clearance 0)
		)
		(min_thickness 0.25)
		(keepout
			(tracks not_allowed)
			(vias allowed)
			(pads allowed)
			(copperpour not_allowed)
			(footprints allowed)
		)
		(placement
			(enabled no)
			(sheetname "")
		)
		(fill yes
			(thermal_gap 0.5)
			(thermal_bridge_width 0.5)
			(island_removal_mode 0)
		)
		(polygon
			(pts
				(arc
					(start 173.122336 -211.766658)
					(mid 172.469556 -211.766658)
					(end 173.122336 -211.766658)
				)
			)
		)
	)
	(zone
		(layers "B.Cu" "In4.Cu" "In6.Cu" "In11.Cu" "In13.Cu" "In15.Cu")
		(hatch none 0.5)
		(connect_pads
			(clearance 0)
		)
		(min_thickness 0.25)
		(keepout
			(tracks not_allowed)
			(vias allowed)
			(pads allowed)
			(copperpour not_allowed)
			(footprints allowed)
		)
		(placement
			(enabled no)
			(sheetname "")
		)
		(fill yes
			(thermal_gap 0.5)
			(thermal_bridge_width 0.5)
			(island_removal_mode 0)
		)
		(polygon
			(pts
				(arc
					(start 421.062404 -271.266666)
					(mid 420.409624 -271.266666)
					(end 421.062404 -271.266666)
				)
			)
		)
	)
	(zone
		(layers "B.Cu" "In4.Cu" "In6.Cu" "In11.Cu" "In13.Cu" "In15.Cu")
		(hatch none 0.5)
		(connect_pads
			(clearance 0)
		)
		(min_thickness 0.25)
		(keepout
			(tracks not_allowed)
			(vias allowed)
			(pads allowed)
			(copperpour not_allowed)
			(footprints allowed)
		)
		(placement
			(enabled no)
			(sheetname "")
		)
		(fill yes
			(thermal_gap 0.5)
			(thermal_bridge_width 0.5)
			(island_removal_mode 0)
		)
		(polygon
			(pts
				(arc
					(start 99.389184 -285.661354)
					(mid 98.736404 -285.661354)
					(end 99.389184 -285.661354)
				)
			)
		)
	)
	(zone
		(layers "B.Cu" "In4.Cu" "In6.Cu" "In11.Cu" "In13.Cu" "In15.Cu")
		(hatch none 0.5)
		(connect_pads
			(clearance 0)
		)
		(min_thickness 0.25)
		(keepout
			(tracks not_allowed)
			(vias allowed)
			(pads allowed)
			(copperpour not_allowed)
			(footprints allowed)
		)
		(placement
			(enabled no)
			(sheetname "")
		)
		(fill yes
			(thermal_gap 0.5)
			(thermal_bridge_width 0.5)
			(island_removal_mode 0)
		)
		(polygon
			(pts
				(arc
					(start 336.991452 -261.244842)
					(mid 336.338672 -261.244842)
					(end 336.991452 -261.244842)
				)
			)
		)
	)
	(zone
		(layers "B.Cu" "In4.Cu" "In6.Cu" "In11.Cu" "In13.Cu" "In15.Cu")
		(hatch none 0.5)
		(connect_pads
			(clearance 0)
		)
		(min_thickness 0.25)
		(keepout
			(tracks not_allowed)
			(vias allowed)
			(pads allowed)
			(copperpour not_allowed)
			(footprints allowed)
		)
		(placement
			(enabled no)
			(sheetname "")
		)
		(fill yes
			(thermal_gap 0.5)
			(thermal_bridge_width 0.5)
			(island_removal_mode 0)
		)
		(polygon
			(pts
				(arc
					(start 357.83647 -55.884572)
					(mid 357.13289 -55.884572)
					(end 357.83647 -55.884572)
				)
			)
		)
	)
	(zone
		(layers "B.Cu" "In4.Cu" "In6.Cu" "In11.Cu" "In13.Cu" "In15.Cu")
		(hatch none 0.5)
		(connect_pads
			(clearance 0)
		)
		(min_thickness 0.25)
		(keepout
			(tracks not_allowed)
			(vias allowed)
			(pads allowed)
			(copperpour not_allowed)
			(footprints allowed)
		)
		(placement
			(enabled no)
			(sheetname "")
		)
		(fill yes
			(thermal_gap 0.5)
			(thermal_bridge_width 0.5)
			(island_removal_mode 0)
		)
		(polygon
			(pts
				(arc
					(start 15.885668 -17.61236)
					(mid 15.182088 -17.61236)
					(end 15.885668 -17.61236)
				)
			)
		)
	)
	(zone
		(layers "B.Cu" "In4.Cu" "In6.Cu" "In11.Cu" "In13.Cu" "In15.Cu")
		(hatch none 0.5)
		(connect_pads
			(clearance 0)
		)
		(min_thickness 0.25)
		(keepout
			(tracks not_allowed)
			(vias allowed)
			(pads allowed)
			(copperpour not_allowed)
			(footprints allowed)
		)
		(placement
			(enabled no)
			(sheetname "")
		)
		(fill yes
			(thermal_gap 0.5)
			(thermal_bridge_width 0.5)
			(island_removal_mode 0)
		)
		(polygon
			(pts
				(arc
					(start 425.162472 -216.016586)
					(mid 424.509692 -216.016586)
					(end 425.162472 -216.016586)
				)
			)
		)
	)
	(zone
		(layers "B.Cu" "In4.Cu" "In6.Cu" "In11.Cu" "In13.Cu" "In15.Cu")
		(hatch none 0.5)
		(connect_pads
			(clearance 0)
		)
		(min_thickness 0.25)
		(keepout
			(tracks not_allowed)
			(vias allowed)
			(pads allowed)
			(copperpour not_allowed)
			(footprints allowed)
		)
		(placement
			(enabled no)
			(sheetname "")
		)
		(fill yes
			(thermal_gap 0.5)
			(thermal_bridge_width 0.5)
			(island_removal_mode 0)
		)
		(polygon
			(pts
				(arc
					(start 51.416204 -295.06672)
					(mid 50.763424 -295.06672)
					(end 51.416204 -295.06672)
				)
			)
		)
	)
	(zone
		(layers "B.Cu" "In4.Cu" "In6.Cu" "In11.Cu" "In13.Cu" "In15.Cu")
		(hatch none 0.5)
		(connect_pads
			(clearance 0)
		)
		(min_thickness 0.25)
		(keepout
			(tracks not_allowed)
			(vias allowed)
			(pads allowed)
			(copperpour not_allowed)
			(footprints allowed)
		)
		(placement
			(enabled no)
			(sheetname "")
		)
		(fill yes
			(thermal_gap 0.5)
			(thermal_bridge_width 0.5)
			(island_removal_mode 0)
		)
		(polygon
			(pts
				(arc
					(start 46.925484 -19.13636)
					(mid 46.221904 -19.13636)
					(end 46.925484 -19.13636)
				)
			)
		)
	)
	(zone
		(layers "B.Cu" "In4.Cu" "In6.Cu" "In11.Cu" "In13.Cu" "In15.Cu")
		(hatch none 0.5)
		(connect_pads
			(clearance 0)
		)
		(min_thickness 0.25)
		(keepout
			(tracks not_allowed)
			(vias allowed)
			(pads allowed)
			(copperpour not_allowed)
			(footprints allowed)
		)
		(placement
			(enabled no)
			(sheetname "")
		)
		(fill yes
			(thermal_gap 0.5)
			(thermal_bridge_width 0.5)
			(island_removal_mode 0)
		)
		(polygon
			(pts
				(arc
					(start 173.122336 -289.966654)
					(mid 172.469556 -289.966654)
					(end 173.122336 -289.966654)
				)
			)
		)
	)
	(zone
		(layers "B.Cu" "In4.Cu" "In6.Cu" "In11.Cu" "In13.Cu" "In15.Cu")
		(hatch none 0.5)
		(connect_pads
			(clearance 0)
		)
		(min_thickness 0.25)
		(keepout
			(tracks not_allowed)
			(vias allowed)
			(pads allowed)
			(copperpour not_allowed)
			(footprints allowed)
		)
		(placement
			(enabled no)
			(sheetname "")
		)
		(fill yes
			(thermal_gap 0.5)
			(thermal_bridge_width 0.5)
			(island_removal_mode 0)
		)
		(polygon
			(pts
				(arc
					(start 382.931924 -234.970066)
					(mid 382.279144 -234.970066)
					(end 382.931924 -234.970066)
				)
			)
		)
	)
	(zone
		(layers "B.Cu" "In4.Cu" "In6.Cu" "In11.Cu" "In13.Cu" "In15.Cu")
		(hatch none 0.5)
		(connect_pads
			(clearance 0)
		)
		(min_thickness 0.25)
		(keepout
			(tracks not_allowed)
			(vias allowed)
			(pads allowed)
			(copperpour not_allowed)
			(footprints allowed)
		)
		(placement
			(enabled no)
			(sheetname "")
		)
		(fill yes
			(thermal_gap 0.5)
			(thermal_bridge_width 0.5)
			(island_removal_mode 0)
		)
		(polygon
			(pts
				(arc
					(start 299.356272 -272.116804)
					(mid 298.703492 -272.116804)
					(end 299.356272 -272.116804)
				)
			)
		)
	)
	(zone
		(layers "B.Cu" "In4.Cu" "In6.Cu" "In11.Cu" "In13.Cu" "In15.Cu")
		(hatch none 0.5)
		(connect_pads
			(clearance 0)
		)
		(min_thickness 0.25)
		(keepout
			(tracks not_allowed)
			(vias allowed)
			(pads allowed)
			(copperpour not_allowed)
			(footprints allowed)
		)
		(placement
			(enabled no)
			(sheetname "")
		)
		(fill yes
			(thermal_gap 0.5)
			(thermal_bridge_width 0.5)
			(island_removal_mode 0)
		)
		(polygon
			(pts
				(arc
					(start 51.390804 -236.416596)
					(mid 50.738024 -236.416596)
					(end 51.390804 -236.416596)
				)
			)
		)
	)
	(zone
		(layers "B.Cu" "In4.Cu" "In6.Cu" "In11.Cu" "In13.Cu" "In15.Cu")
		(hatch none 0.5)
		(connect_pads
			(clearance 0)
		)
		(min_thickness 0.25)
		(keepout
			(tracks not_allowed)
			(vias allowed)
			(pads allowed)
			(copperpour not_allowed)
			(footprints allowed)
		)
		(placement
			(enabled no)
			(sheetname "")
		)
		(fill yes
			(thermal_gap 0.5)
			(thermal_bridge_width 0.5)
			(island_removal_mode 0)
		)
		(polygon
			(pts
				(arc
					(start 378.812806 -255.547622)
					(mid 378.160026 -255.547622)
					(end 378.812806 -255.547622)
				)
			)
		)
	)
	(zone
		(layers "B.Cu" "In4.Cu" "In6.Cu" "In11.Cu" "In13.Cu" "In15.Cu")
		(hatch none 0.5)
		(connect_pads
			(clearance 0)
		)
		(min_thickness 0.25)
		(keepout
			(tracks not_allowed)
			(vias allowed)
			(pads allowed)
			(copperpour not_allowed)
			(footprints allowed)
		)
		(placement
			(enabled no)
			(sheetname "")
		)
		(fill yes
			(thermal_gap 0.5)
			(thermal_bridge_width 0.5)
			(island_removal_mode 0)
		)
		(polygon
			(pts
				(arc
					(start 75.047348 -407.00452)
					(mid 74.343768 -407.00452)
					(end 75.047348 -407.00452)
				)
			)
		)
	)
	(zone
		(layers "B.Cu" "In4.Cu" "In6.Cu" "In11.Cu" "In13.Cu" "In15.Cu")
		(hatch none 0.5)
		(connect_pads
			(clearance 0)
		)
		(min_thickness 0.25)
		(keepout
			(tracks not_allowed)
			(vias allowed)
			(pads allowed)
			(copperpour not_allowed)
			(footprints allowed)
		)
		(placement
			(enabled no)
			(sheetname "")
		)
		(fill yes
			(thermal_gap 0.5)
			(thermal_bridge_width 0.5)
			(island_removal_mode 0)
		)
		(polygon
			(pts
				(arc
					(start 419.50259 -17.601438)
					(mid 418.79901 -17.601438)
					(end 419.50259 -17.601438)
				)
			)
		)
	)
	(zone
		(layers "B.Cu" "In4.Cu" "In6.Cu" "In11.Cu" "In13.Cu" "In15.Cu")
		(hatch none 0.5)
		(connect_pads
			(clearance 0)
		)
		(min_thickness 0.25)
		(keepout
			(tracks not_allowed)
			(vias allowed)
			(pads allowed)
			(copperpour not_allowed)
			(footprints allowed)
		)
		(placement
			(enabled no)
			(sheetname "")
		)
		(fill yes
			(thermal_gap 0.5)
			(thermal_bridge_width 0.5)
			(island_removal_mode 0)
		)
		(polygon
			(pts
				(arc
					(start 132.282184 -285.661354)
					(mid 131.629404 -285.661354)
					(end 132.282184 -285.661354)
				)
			)
		)
	)
	(zone
		(layers "B.Cu" "In4.Cu" "In6.Cu" "In11.Cu" "In13.Cu" "In15.Cu")
		(hatch none 0.5)
		(connect_pads
			(clearance 0)
		)
		(min_thickness 0.25)
		(keepout
			(tracks not_allowed)
			(vias allowed)
			(pads allowed)
			(copperpour not_allowed)
			(footprints allowed)
		)
		(placement
			(enabled no)
			(sheetname "")
		)
		(fill yes
			(thermal_gap 0.5)
			(thermal_bridge_width 0.5)
			(island_removal_mode 0)
		)
		(polygon
			(pts
				(arc
					(start 376.18416 -407.00452)
					(mid 375.48058 -407.00452)
					(end 376.18416 -407.00452)
				)
			)
		)
	)
	(zone
		(layers "B.Cu" "In4.Cu" "In6.Cu" "In11.Cu" "In13.Cu" "In15.Cu")
		(hatch none 0.5)
		(connect_pads
			(clearance 0)
		)
		(min_thickness 0.25)
		(keepout
			(tracks not_allowed)
			(vias allowed)
			(pads allowed)
			(copperpour not_allowed)
			(footprints allowed)
		)
		(placement
			(enabled no)
			(sheetname "")
		)
		(fill yes
			(thermal_gap 0.5)
			(thermal_bridge_width 0.5)
			(island_removal_mode 0)
		)
		(polygon
			(pts
				(arc
					(start 338.401152 -257.175254)
					(mid 337.748372 -257.175254)
					(end 338.401152 -257.175254)
				)
			)
		)
	)
	(zone
		(layers "B.Cu" "In4.Cu" "In6.Cu" "In11.Cu" "In13.Cu" "In15.Cu")
		(hatch none 0.5)
		(connect_pads
			(clearance 0)
		)
		(min_thickness 0.25)
		(keepout
			(tracks not_allowed)
			(vias allowed)
			(pads allowed)
			(copperpour not_allowed)
			(footprints allowed)
		)
		(placement
			(enabled no)
			(sheetname "")
		)
		(fill yes
			(thermal_gap 0.5)
			(thermal_bridge_width 0.5)
			(island_removal_mode 0)
		)
		(polygon
			(pts
				(arc
					(start 90.930984 -261.244842)
					(mid 90.278204 -261.244842)
					(end 90.930984 -261.244842)
				)
			)
		)
	)
	(zone
		(layers "B.Cu" "In4.Cu" "In6.Cu" "In11.Cu" "In13.Cu" "In15.Cu")
		(hatch none 0.5)
		(connect_pads
			(clearance 0)
		)
		(min_thickness 0.25)
		(keepout
			(tracks not_allowed)
			(vias allowed)
			(pads allowed)
			(copperpour not_allowed)
			(footprints allowed)
		)
		(placement
			(enabled no)
			(sheetname "")
		)
		(fill yes
			(thermal_gap 0.5)
			(thermal_bridge_width 0.5)
			(island_removal_mode 0)
		)
		(polygon
			(pts
				(arc
					(start 383.981452 -272.639282)
					(mid 383.328672 -272.639282)
					(end 383.981452 -272.639282)
				)
			)
		)
	)
	(zone
		(layers "B.Cu" "In4.Cu" "In6.Cu" "In11.Cu" "In13.Cu" "In15.Cu")
		(hatch none 0.5)
		(connect_pads
			(clearance 0)
		)
		(min_thickness 0.25)
		(keepout
			(tracks not_allowed)
			(vias allowed)
			(pads allowed)
			(copperpour not_allowed)
			(footprints allowed)
		)
		(placement
			(enabled no)
			(sheetname "")
		)
		(fill yes
			(thermal_gap 0.5)
			(thermal_bridge_width 0.5)
			(island_removal_mode 0)
		)
		(polygon
			(pts
				(arc
					(start 173.122336 -249.166634)
					(mid 172.469556 -249.166634)
					(end 173.122336 -249.166634)
				)
			)
		)
	)
	(zone
		(layers "B.Cu" "In4.Cu" "In6.Cu" "In11.Cu" "In13.Cu" "In15.Cu")
		(hatch none 0.5)
		(connect_pads
			(clearance 0)
		)
		(min_thickness 0.25)
		(keepout
			(tracks not_allowed)
			(vias allowed)
			(pads allowed)
			(copperpour not_allowed)
			(footprints allowed)
		)
		(placement
			(enabled no)
			(sheetname "")
		)
		(fill yes
			(thermal_gap 0.5)
			(thermal_bridge_width 0.5)
			(island_removal_mode 0)
		)
		(polygon
			(pts
				(arc
					(start 132.282184 -256.361438)
					(mid 131.629404 -256.361438)
					(end 132.282184 -256.361438)
				)
			)
		)
	)
	(zone
		(layers "B.Cu" "In4.Cu" "In6.Cu" "In11.Cu" "In13.Cu" "In15.Cu")
		(hatch none 0.5)
		(connect_pads
			(clearance 0)
		)
		(min_thickness 0.25)
		(keepout
			(tracks not_allowed)
			(vias allowed)
			(pads allowed)
			(copperpour not_allowed)
			(footprints allowed)
		)
		(placement
			(enabled no)
			(sheetname "")
		)
		(fill yes
			(thermal_gap 0.5)
			(thermal_bridge_width 0.5)
			(island_removal_mode 0)
		)
		(polygon
			(pts
				(arc
					(start 184.766204 -260.21665)
					(mid 184.113424 -260.21665)
					(end 184.766204 -260.21665)
				)
			)
		)
	)
	(zone
		(layers "B.Cu" "In4.Cu" "In6.Cu" "In11.Cu" "In13.Cu" "In15.Cu")
		(hatch none 0.5)
		(connect_pads
			(clearance 0)
		)
		(min_thickness 0.25)
		(keepout
			(tracks not_allowed)
			(vias allowed)
			(pads allowed)
			(copperpour not_allowed)
			(footprints allowed)
		)
		(placement
			(enabled no)
			(sheetname "")
		)
		(fill yes
			(thermal_gap 0.5)
			(thermal_bridge_width 0.5)
			(island_removal_mode 0)
		)
		(polygon
			(pts
				(arc
					(start 401.569174 -17.601438)
					(mid 400.865594 -17.601438)
					(end 401.569174 -17.601438)
				)
			)
		)
	)
	(zone
		(layers "B.Cu" "In4.Cu" "In6.Cu" "In11.Cu" "In13.Cu" "In15.Cu")
		(hatch none 0.5)
		(connect_pads
			(clearance 0)
		)
		(min_thickness 0.25)
		(keepout
			(tracks not_allowed)
			(vias allowed)
			(pads allowed)
			(copperpour not_allowed)
			(footprints allowed)
		)
		(placement
			(enabled no)
			(sheetname "")
		)
		(fill yes
			(thermal_gap 0.5)
			(thermal_bridge_width 0.5)
			(island_removal_mode 0)
		)
		(polygon
			(pts
				(arc
					(start 134.052056 -239.853216)
					(mid 133.399276 -239.853216)
					(end 134.052056 -239.853216)
				)
			)
		)
	)
	(zone
		(layers "B.Cu" "In4.Cu" "In6.Cu" "In11.Cu" "In13.Cu" "In15.Cu")
		(hatch none 0.5)
		(connect_pads
			(clearance 0)
		)
		(min_thickness 0.25)
		(keepout
			(tracks not_allowed)
			(vias allowed)
			(pads allowed)
			(copperpour not_allowed)
			(footprints allowed)
		)
		(placement
			(enabled no)
			(sheetname "")
		)
		(fill yes
			(thermal_gap 0.5)
			(thermal_bridge_width 0.5)
			(island_removal_mode 0)
		)
		(polygon
			(pts
				(arc
					(start 155.548584 -407.00452)
					(mid 154.845004 -407.00452)
					(end 155.548584 -407.00452)
				)
			)
		)
	)
	(zone
		(layers "B.Cu" "In4.Cu" "In6.Cu" "In11.Cu" "In13.Cu" "In15.Cu")
		(hatch none 0.5)
		(connect_pads
			(clearance 0)
		)
		(min_thickness 0.25)
		(keepout
			(tracks not_allowed)
			(vias allowed)
			(pads allowed)
			(copperpour not_allowed)
			(footprints allowed)
		)
		(placement
			(enabled no)
			(sheetname "")
		)
		(fill yes
			(thermal_gap 0.5)
			(thermal_bridge_width 0.5)
			(island_removal_mode 0)
		)
		(polygon
			(pts
				(arc
					(start 97.509584 -285.661354)
					(mid 96.856804 -285.661354)
					(end 97.509584 -285.661354)
				)
			)
		)
	)
	(zone
		(layers "B.Cu" "In4.Cu" "In6.Cu" "In11.Cu" "In13.Cu" "In15.Cu")
		(hatch none 0.5)
		(connect_pads
			(clearance 0)
		)
		(min_thickness 0.25)
		(keepout
			(tracks not_allowed)
			(vias allowed)
			(pads allowed)
			(copperpour not_allowed)
			(footprints allowed)
		)
		(placement
			(enabled no)
			(sheetname "")
		)
		(fill yes
			(thermal_gap 0.5)
			(thermal_bridge_width 0.5)
			(island_removal_mode 0)
		)
		(polygon
			(pts
				(arc
					(start 135.101584 -277.522432)
					(mid 134.448804 -277.522432)
					(end 135.101584 -277.522432)
				)
			)
		)
	)
	(zone
		(layers "B.Cu" "In4.Cu" "In6.Cu" "In11.Cu" "In13.Cu" "In15.Cu")
		(hatch none 0.5)
		(connect_pads
			(clearance 0)
		)
		(min_thickness 0.25)
		(keepout
			(tracks not_allowed)
			(vias allowed)
			(pads allowed)
			(copperpour not_allowed)
			(footprints allowed)
		)
		(placement
			(enabled no)
			(sheetname "")
		)
		(fill yes
			(thermal_gap 0.5)
			(thermal_bridge_width 0.5)
			(island_removal_mode 0)
		)
		(polygon
			(pts
				(arc
					(start 383.401824 -235.783882)
					(mid 382.749044 -235.783882)
					(end 383.401824 -235.783882)
				)
			)
		)
	)
	(zone
		(layers "B.Cu" "In4.Cu" "In6.Cu" "In11.Cu" "In13.Cu" "In15.Cu")
		(hatch none 0.5)
		(connect_pads
			(clearance 0)
		)
		(min_thickness 0.25)
		(keepout
			(tracks not_allowed)
			(vias allowed)
			(pads allowed)
			(copperpour not_allowed)
			(footprints allowed)
		)
		(placement
			(enabled no)
			(sheetname "")
		)
		(fill yes
			(thermal_gap 0.5)
			(thermal_bridge_width 0.5)
			(island_removal_mode 0)
		)
		(polygon
			(pts
				(arc
					(start 377.873006 -255.547622)
					(mid 377.220226 -255.547622)
					(end 377.873006 -255.547622)
				)
			)
		)
	)
	(zone
		(layers "B.Cu" "In4.Cu" "In6.Cu" "In11.Cu" "In13.Cu" "In15.Cu")
		(hatch none 0.5)
		(connect_pads
			(clearance 0)
		)
		(min_thickness 0.25)
		(keepout
			(tracks not_allowed)
			(vias allowed)
			(pads allowed)
			(copperpour not_allowed)
			(footprints allowed)
		)
		(placement
			(enabled no)
			(sheetname "")
		)
		(fill yes
			(thermal_gap 0.5)
			(thermal_bridge_width 0.5)
			(island_removal_mode 0)
		)
		(polygon
			(pts
				(arc
					(start 313.521598 -400.858228)
					(mid 312.818018 -400.858228)
					(end 313.521598 -400.858228)
				)
			)
		)
	)
	(zone
		(layers "B.Cu" "In4.Cu" "In6.Cu" "In11.Cu" "In13.Cu" "In15.Cu")
		(hatch none 0.5)
		(connect_pads
			(clearance 0)
		)
		(min_thickness 0.25)
		(keepout
			(tracks not_allowed)
			(vias allowed)
			(pads allowed)
			(copperpour not_allowed)
			(footprints allowed)
		)
		(placement
			(enabled no)
			(sheetname "")
		)
		(fill yes
			(thermal_gap 0.5)
			(thermal_bridge_width 0.5)
			(island_removal_mode 0)
		)
		(polygon
			(pts
				(arc
					(start 382.101852 -264.50036)
					(mid 381.449072 -264.50036)
					(end 382.101852 -264.50036)
				)
			)
		)
	)
	(zone
		(layers "B.Cu" "In4.Cu" "In6.Cu" "In11.Cu" "In13.Cu" "In15.Cu")
		(hatch none 0.5)
		(connect_pads
			(clearance 0)
		)
		(min_thickness 0.25)
		(keepout
			(tracks not_allowed)
			(vias allowed)
			(pads allowed)
			(copperpour not_allowed)
			(footprints allowed)
		)
		(placement
			(enabled no)
			(sheetname "")
		)
		(fill yes
			(thermal_gap 0.5)
			(thermal_bridge_width 0.5)
			(island_removal_mode 0)
		)
		(polygon
			(pts
				(arc
					(start 337.351624 -245.55069)
					(mid 336.698844 -245.55069)
					(end 337.351624 -245.55069)
				)
			)
		)
	)
	(zone
		(layers "B.Cu" "In4.Cu" "In6.Cu" "In11.Cu" "In13.Cu" "In15.Cu")
		(hatch none 0.5)
		(connect_pads
			(clearance 0)
		)
		(min_thickness 0.25)
		(keepout
			(tracks not_allowed)
			(vias allowed)
			(pads allowed)
			(copperpour not_allowed)
			(footprints allowed)
		)
		(placement
			(enabled no)
			(sheetname "")
		)
		(fill yes
			(thermal_gap 0.5)
			(thermal_bridge_width 0.5)
			(island_removal_mode 0)
		)
		(polygon
			(pts
				(arc
					(start 338.027518 -400.858228)
					(mid 337.323938 -400.858228)
					(end 338.027518 -400.858228)
				)
			)
		)
	)
	(zone
		(layers "B.Cu" "In4.Cu" "In6.Cu" "In11.Cu" "In13.Cu" "In15.Cu")
		(hatch none 0.5)
		(connect_pads
			(clearance 0)
		)
		(min_thickness 0.25)
		(keepout
			(tracks not_allowed)
			(vias allowed)
			(pads allowed)
			(copperpour not_allowed)
			(footprints allowed)
		)
		(placement
			(enabled no)
			(sheetname "")
		)
		(fill yes
			(thermal_gap 0.5)
			(thermal_bridge_width 0.5)
			(island_removal_mode 0)
		)
		(polygon
			(pts
				(arc
					(start 100.799138 -284.847538)
					(mid 100.146358 -284.847538)
					(end 100.799138 -284.847538)
				)
			)
		)
	)
	(zone
		(layers "B.Cu" "In4.Cu" "In6.Cu" "In11.Cu" "In13.Cu" "In15.Cu")
		(hatch none 0.5)
		(connect_pads
			(clearance 0)
		)
		(min_thickness 0.25)
		(keepout
			(tracks not_allowed)
			(vias allowed)
			(pads allowed)
			(copperpour not_allowed)
			(footprints allowed)
		)
		(placement
			(enabled no)
			(sheetname "")
		)
		(fill yes
			(thermal_gap 0.5)
			(thermal_bridge_width 0.5)
			(island_removal_mode 0)
		)
		(polygon
			(pts
				(arc
					(start 421.062404 -235.566712)
					(mid 420.409624 -235.566712)
					(end 421.062404 -235.566712)
				)
			)
		)
	)
	(zone
		(layers "B.Cu" "In4.Cu" "In6.Cu" "In11.Cu" "In13.Cu" "In15.Cu")
		(hatch none 0.5)
		(connect_pads
			(clearance 0)
		)
		(min_thickness 0.25)
		(keepout
			(tracks not_allowed)
			(vias allowed)
			(pads allowed)
			(copperpour not_allowed)
			(footprints allowed)
		)
		(placement
			(enabled no)
			(sheetname "")
		)
		(fill yes
			(thermal_gap 0.5)
			(thermal_bridge_width 0.5)
			(island_removal_mode 0)
		)
		(polygon
			(pts
				(arc
					(start 336.521552 -255.547622)
					(mid 335.868772 -255.547622)
					(end 336.521552 -255.547622)
				)
			)
		)
	)
	(zone
		(layers "B.Cu" "In4.Cu" "In6.Cu" "In11.Cu" "In13.Cu" "In15.Cu")
		(hatch none 0.5)
		(connect_pads
			(clearance 0)
		)
		(min_thickness 0.25)
		(keepout
			(tracks not_allowed)
			(vias allowed)
			(pads allowed)
			(copperpour not_allowed)
			(footprints allowed)
		)
		(placement
			(enabled no)
			(sheetname "")
		)
		(fill yes
			(thermal_gap 0.5)
			(thermal_bridge_width 0.5)
			(island_removal_mode 0)
		)
		(polygon
			(pts
				(arc
					(start 341.58047 -247.992138)
					(mid 340.92769 -247.992138)
					(end 341.58047 -247.992138)
				)
			)
		)
	)
	(zone
		(layers "B.Cu" "In4.Cu" "In6.Cu" "In11.Cu" "In13.Cu" "In15.Cu")
		(hatch none 0.5)
		(connect_pads
			(clearance 0)
		)
		(min_thickness 0.25)
		(keepout
			(tracks not_allowed)
			(vias allowed)
			(pads allowed)
			(copperpour not_allowed)
			(footprints allowed)
		)
		(placement
			(enabled no)
			(sheetname "")
		)
		(fill yes
			(thermal_gap 0.5)
			(thermal_bridge_width 0.5)
			(island_removal_mode 0)
		)
		(polygon
			(pts
				(arc
					(start 66.478404 -298.466764)
					(mid 65.825624 -298.466764)
					(end 66.478404 -298.466764)
				)
			)
		)
	)
	(zone
		(layers "B.Cu" "In4.Cu" "In6.Cu" "In11.Cu" "In13.Cu" "In15.Cu")
		(hatch none 0.5)
		(connect_pads
			(clearance 0)
		)
		(min_thickness 0.25)
		(keepout
			(tracks not_allowed)
			(vias allowed)
			(pads allowed)
			(copperpour not_allowed)
			(footprints allowed)
		)
		(placement
			(enabled no)
			(sheetname "")
		)
		(fill yes
			(thermal_gap 0.5)
			(thermal_bridge_width 0.5)
			(island_removal_mode 0)
		)
		(polygon
			(pts
				(arc
					(start 89.051384 -256.361438)
					(mid 88.398604 -256.361438)
					(end 89.051384 -256.361438)
				)
			)
		)
	)
	(zone
		(layers "B.Cu" "In4.Cu" "In6.Cu" "In11.Cu" "In13.Cu" "In15.Cu")
		(hatch none 0.5)
		(connect_pads
			(clearance 0)
		)
		(min_thickness 0.25)
		(keepout
			(tracks not_allowed)
			(vias allowed)
			(pads allowed)
			(copperpour not_allowed)
			(footprints allowed)
		)
		(placement
			(enabled no)
			(sheetname "")
		)
		(fill yes
			(thermal_gap 0.5)
			(thermal_bridge_width 0.5)
			(island_removal_mode 0)
		)
		(polygon
			(pts
				(arc
					(start 410.049472 -229.616762)
					(mid 409.396692 -229.616762)
					(end 410.049472 -229.616762)
				)
			)
		)
	)
	(zone
		(layers "B.Cu" "In4.Cu" "In6.Cu" "In11.Cu" "In13.Cu" "In15.Cu")
		(hatch none 0.5)
		(connect_pads
			(clearance 0)
		)
		(min_thickness 0.25)
		(keepout
			(tracks not_allowed)
			(vias allowed)
			(pads allowed)
			(copperpour not_allowed)
			(footprints allowed)
		)
		(placement
			(enabled no)
			(sheetname "")
		)
		(fill yes
			(thermal_gap 0.5)
			(thermal_bridge_width 0.5)
			(island_removal_mode 0)
		)
		(polygon
			(pts
				(arc
					(start 398.775174 -19.125438)
					(mid 398.071594 -19.125438)
					(end 398.775174 -19.125438)
				)
			)
		)
	)
	(zone
		(layers "B.Cu" "In4.Cu" "In6.Cu" "In11.Cu" "In13.Cu" "In15.Cu")
		(hatch none 0.5)
		(connect_pads
			(clearance 0)
		)
		(min_thickness 0.25)
		(keepout
			(tracks not_allowed)
			(vias allowed)
			(pads allowed)
			(copperpour not_allowed)
			(footprints allowed)
		)
		(placement
			(enabled no)
			(sheetname "")
		)
		(fill yes
			(thermal_gap 0.5)
			(thermal_bridge_width 0.5)
			(island_removal_mode 0)
		)
		(polygon
			(pts
				(arc
					(start 295.230804 -250.866656)
					(mid 294.578024 -250.866656)
					(end 295.230804 -250.866656)
				)
			)
		)
	)
	(zone
		(layers "B.Cu" "In4.Cu" "In6.Cu" "In11.Cu" "In13.Cu" "In15.Cu")
		(hatch none 0.5)
		(connect_pads
			(clearance 0)
		)
		(min_thickness 0.25)
		(keepout
			(tracks not_allowed)
			(vias allowed)
			(pads allowed)
			(copperpour not_allowed)
			(footprints allowed)
		)
		(placement
			(enabled no)
			(sheetname "")
		)
		(fill yes
			(thermal_gap 0.5)
			(thermal_bridge_width 0.5)
			(island_removal_mode 0)
		)
		(polygon
			(pts
				(arc
					(start 135.931656 -244.73662)
					(mid 135.278876 -244.73662)
					(end 135.931656 -244.73662)
				)
			)
		)
	)
	(zone
		(layers "B.Cu" "In4.Cu" "In6.Cu" "In11.Cu" "In13.Cu" "In15.Cu")
		(hatch none 0.5)
		(connect_pads
			(clearance 0)
		)
		(min_thickness 0.25)
		(keepout
			(tracks not_allowed)
			(vias allowed)
			(pads allowed)
			(copperpour not_allowed)
			(footprints allowed)
		)
		(placement
			(enabled no)
			(sheetname "")
		)
		(fill yes
			(thermal_gap 0.5)
			(thermal_bridge_width 0.5)
			(island_removal_mode 0)
		)
		(polygon
			(pts
				(arc
					(start 357.087424 -224.389442)
					(mid 356.434644 -224.389442)
					(end 357.087424 -224.389442)
				)
			)
		)
	)
	(zone
		(layers "B.Cu" "In4.Cu" "In6.Cu" "In11.Cu" "In13.Cu" "In15.Cu")
		(hatch none 0.5)
		(connect_pads
			(clearance 0)
		)
		(min_thickness 0.25)
		(keepout
			(tracks not_allowed)
			(vias allowed)
			(pads allowed)
			(copperpour not_allowed)
			(footprints allowed)
		)
		(placement
			(enabled no)
			(sheetname "")
		)
		(fill yes
			(thermal_gap 0.5)
			(thermal_bridge_width 0.5)
			(island_removal_mode 0)
		)
		(polygon
			(pts
				(arc
					(start 58.13552 -19.13636)
					(mid 57.43194 -19.13636)
					(end 58.13552 -19.13636)
				)
			)
		)
	)
	(zone
		(layers "B.Cu" "In4.Cu" "In6.Cu" "In11.Cu" "In13.Cu" "In15.Cu")
		(hatch none 0.5)
		(connect_pads
			(clearance 0)
		)
		(min_thickness 0.25)
		(keepout
			(tracks not_allowed)
			(vias allowed)
			(pads allowed)
			(copperpour not_allowed)
			(footprints allowed)
		)
		(placement
			(enabled no)
			(sheetname "")
		)
		(fill yes
			(thermal_gap 0.5)
			(thermal_bridge_width 0.5)
			(island_removal_mode 0)
		)
		(polygon
			(pts
				(arc
					(start 430.712626 -17.601438)
					(mid 430.009046 -17.601438)
					(end 430.712626 -17.601438)
				)
			)
		)
	)
	(zone
		(layers "B.Cu" "In4.Cu" "In6.Cu" "In11.Cu" "In13.Cu" "In15.Cu")
		(hatch none 0.5)
		(connect_pads
			(clearance 0)
		)
		(min_thickness 0.25)
		(keepout
			(tracks not_allowed)
			(vias allowed)
			(pads allowed)
			(copperpour not_allowed)
			(footprints allowed)
		)
		(placement
			(enabled no)
			(sheetname "")
		)
		(fill yes
			(thermal_gap 0.5)
			(thermal_bridge_width 0.5)
			(island_removal_mode 0)
		)
		(polygon
			(pts
				(arc
					(start 381.632206 -276.708616)
					(mid 380.979426 -276.708616)
					(end 381.632206 -276.708616)
				)
			)
		)
	)
	(zone
		(layers "B.Cu" "In4.Cu" "In6.Cu" "In11.Cu" "In13.Cu" "In15.Cu")
		(hatch none 0.5)
		(connect_pads
			(clearance 0)
		)
		(min_thickness 0.25)
		(keepout
			(tracks not_allowed)
			(vias allowed)
			(pads allowed)
			(copperpour not_allowed)
			(footprints allowed)
		)
		(placement
			(enabled no)
			(sheetname "")
		)
		(fill yes
			(thermal_gap 0.5)
			(thermal_bridge_width 0.5)
			(island_removal_mode 0)
		)
		(polygon
			(pts
				(arc
					(start 134.991602 -241.481102)
					(mid 134.338822 -241.481102)
					(end 134.991602 -241.481102)
				)
			)
		)
	)
	(zone
		(layers "B.Cu" "In4.Cu" "In6.Cu" "In11.Cu" "In13.Cu" "In15.Cu")
		(hatch none 0.5)
		(connect_pads
			(clearance 0)
		)
		(min_thickness 0.25)
		(keepout
			(tracks not_allowed)
			(vias allowed)
			(pads allowed)
			(copperpour not_allowed)
			(footprints allowed)
		)
		(placement
			(enabled no)
			(sheetname "")
		)
		(fill yes
			(thermal_gap 0.5)
			(thermal_bridge_width 0.5)
			(island_removal_mode 0)
		)
		(polygon
			(pts
				(arc
					(start 425.162472 -260.21665)
					(mid 424.509692 -260.21665)
					(end 425.162472 -260.21665)
				)
			)
		)
	)
	(zone
		(layers "B.Cu" "In4.Cu" "In6.Cu" "In11.Cu" "In13.Cu" "In15.Cu")
		(hatch none 0.5)
		(connect_pads
			(clearance 0)
		)
		(min_thickness 0.25)
		(keepout
			(tracks not_allowed)
			(vias allowed)
			(pads allowed)
			(copperpour not_allowed)
			(footprints allowed)
		)
		(placement
			(enabled no)
			(sheetname "")
		)
		(fill yes
			(thermal_gap 0.5)
			(thermal_bridge_width 0.5)
			(island_removal_mode 0)
		)
		(polygon
			(pts
				(arc
					(start 383.041652 -272.639282)
					(mid 382.388872 -272.639282)
					(end 383.041652 -272.639282)
				)
			)
		)
	)
	(zone
		(layers "B.Cu" "In4.Cu" "In6.Cu" "In11.Cu" "In13.Cu" "In15.Cu")
		(hatch none 0.5)
		(connect_pads
			(clearance 0)
		)
		(min_thickness 0.25)
		(keepout
			(tracks not_allowed)
			(vias allowed)
			(pads allowed)
			(copperpour not_allowed)
			(footprints allowed)
		)
		(placement
			(enabled no)
			(sheetname "")
		)
		(fill yes
			(thermal_gap 0.5)
			(thermal_bridge_width 0.5)
			(island_removal_mode 0)
		)
		(polygon
			(pts
				(arc
					(start 66.478404 -227.91674)
					(mid 65.825624 -227.91674)
					(end 66.478404 -227.91674)
				)
			)
		)
	)
	(zone
		(layers "B.Cu" "In4.Cu" "In6.Cu" "In11.Cu" "In13.Cu" "In15.Cu")
		(hatch none 0.5)
		(connect_pads
			(clearance 0)
		)
		(min_thickness 0.25)
		(keepout
			(tracks not_allowed)
			(vias allowed)
			(pads allowed)
			(copperpour not_allowed)
			(footprints allowed)
		)
		(placement
			(enabled no)
			(sheetname "")
		)
		(fill yes
			(thermal_gap 0.5)
			(thermal_bridge_width 0.5)
			(island_removal_mode 0)
		)
		(polygon
			(pts
				(arc
					(start 62.378336 -224.516696)
					(mid 61.725556 -224.516696)
					(end 62.378336 -224.516696)
				)
			)
		)
	)
	(zone
		(layers "B.Cu" "In4.Cu" "In6.Cu" "In11.Cu" "In13.Cu" "In15.Cu")
		(hatch none 0.5)
		(connect_pads
			(clearance 0)
		)
		(min_thickness 0.25)
		(keepout
			(tracks not_allowed)
			(vias allowed)
			(pads allowed)
			(copperpour not_allowed)
			(footprints allowed)
		)
		(placement
			(enabled no)
			(sheetname "")
		)
		(fill yes
			(thermal_gap 0.5)
			(thermal_bridge_width 0.5)
			(island_removal_mode 0)
		)
		(polygon
			(pts
				(arc
					(start 359.43667 -223.575626)
					(mid 358.78389 -223.575626)
					(end 359.43667 -223.575626)
				)
			)
		)
	)
	(zone
		(layers "B.Cu" "In4.Cu" "In6.Cu" "In11.Cu" "In13.Cu" "In15.Cu")
		(hatch none 0.5)
		(connect_pads
			(clearance 0)
		)
		(min_thickness 0.25)
		(keepout
			(tracks not_allowed)
			(vias allowed)
			(pads allowed)
			(copperpour not_allowed)
			(footprints allowed)
		)
		(placement
			(enabled no)
			(sheetname "")
		)
		(fill yes
			(thermal_gap 0.5)
			(thermal_bridge_width 0.5)
			(island_removal_mode 0)
		)
		(polygon
			(pts
				(arc
					(start 114.786156 -224.389442)
					(mid 114.133376 -224.389442)
					(end 114.786156 -224.389442)
				)
			)
		)
	)
	(zone
		(layers "B.Cu" "In4.Cu" "In6.Cu" "In11.Cu" "In13.Cu" "In15.Cu")
		(hatch none 0.5)
		(connect_pads
			(clearance 0)
		)
		(min_thickness 0.25)
		(keepout
			(tracks not_allowed)
			(vias allowed)
			(pads allowed)
			(copperpour not_allowed)
			(footprints allowed)
		)
		(placement
			(enabled no)
			(sheetname "")
		)
		(fill yes
			(thermal_gap 0.5)
			(thermal_bridge_width 0.5)
			(island_removal_mode 0)
		)
		(polygon
			(pts
				(arc
					(start 381.632206 -258.80314)
					(mid 380.979426 -258.80314)
					(end 381.632206 -258.80314)
				)
			)
		)
	)
	(zone
		(layers "B.Cu" "In4.Cu" "In6.Cu" "In11.Cu" "In13.Cu" "In15.Cu")
		(hatch none 0.5)
		(connect_pads
			(clearance 0)
		)
		(min_thickness 0.25)
		(keepout
			(tracks not_allowed)
			(vias allowed)
			(pads allowed)
			(copperpour not_allowed)
			(footprints allowed)
		)
		(placement
			(enabled no)
			(sheetname "")
		)
		(fill yes
			(thermal_gap 0.5)
			(thermal_bridge_width 0.5)
			(island_removal_mode 0)
		)
		(polygon
			(pts
				(arc
					(start 19.543268 -19.13636)
					(mid 18.839688 -19.13636)
					(end 19.543268 -19.13636)
				)
			)
		)
	)
	(zone
		(layers "B.Cu" "In4.Cu" "In6.Cu" "In11.Cu" "In13.Cu" "In15.Cu")
		(hatch none 0.5)
		(connect_pads
			(clearance 0)
		)
		(min_thickness 0.25)
		(keepout
			(tracks not_allowed)
			(vias allowed)
			(pads allowed)
			(copperpour not_allowed)
			(footprints allowed)
		)
		(placement
			(enabled no)
			(sheetname "")
		)
		(fill yes
			(thermal_gap 0.5)
			(thermal_bridge_width 0.5)
			(island_removal_mode 0)
		)
		(polygon
			(pts
				(arc
					(start 295.230804 -249.166634)
					(mid 294.578024 -249.166634)
					(end 295.230804 -249.166634)
				)
			)
		)
	)
	(zone
		(layers "B.Cu" "In4.Cu" "In6.Cu" "In11.Cu" "In13.Cu" "In15.Cu")
		(hatch none 0.5)
		(connect_pads
			(clearance 0)
		)
		(min_thickness 0.25)
		(keepout
			(tracks not_allowed)
			(vias allowed)
			(pads allowed)
			(copperpour not_allowed)
			(footprints allowed)
		)
		(placement
			(enabled no)
			(sheetname "")
		)
		(fill yes
			(thermal_gap 0.5)
			(thermal_bridge_width 0.5)
			(island_removal_mode 0)
		)
		(polygon
			(pts
				(arc
					(start 295.230804 -213.46668)
					(mid 294.578024 -213.46668)
					(end 295.230804 -213.46668)
				)
			)
		)
	)
	(zone
		(layers "B.Cu" "In4.Cu" "In6.Cu" "In11.Cu" "In13.Cu" "In15.Cu")
		(hatch none 0.5)
		(connect_pads
			(clearance 0)
		)
		(min_thickness 0.25)
		(keepout
			(tracks not_allowed)
			(vias allowed)
			(pads allowed)
			(copperpour not_allowed)
			(footprints allowed)
		)
		(placement
			(enabled no)
			(sheetname "")
		)
		(fill yes
			(thermal_gap 0.5)
			(thermal_bridge_width 0.5)
			(island_removal_mode 0)
		)
		(polygon
			(pts
				(arc
					(start 177.222404 -221.96679)
					(mid 176.569624 -221.96679)
					(end 177.222404 -221.96679)
				)
			)
		)
	)
	(zone
		(layers "B.Cu" "In4.Cu" "In6.Cu" "In11.Cu" "In13.Cu" "In15.Cu")
		(hatch none 0.5)
		(connect_pads
			(clearance 0)
		)
		(min_thickness 0.25)
		(keepout
			(tracks not_allowed)
			(vias allowed)
			(pads allowed)
			(copperpour not_allowed)
			(footprints allowed)
		)
		(placement
			(enabled no)
			(sheetname "")
		)
		(fill yes
			(thermal_gap 0.5)
			(thermal_bridge_width 0.5)
			(island_removal_mode 0)
		)
		(polygon
			(pts
				(arc
					(start 39.746936 -245.76659)
					(mid 39.094156 -245.76659)
					(end 39.746936 -245.76659)
				)
			)
		)
	)
	(zone
		(layers "B.Cu" "In4.Cu" "In6.Cu" "In11.Cu" "In13.Cu" "In15.Cu")
		(hatch none 0.5)
		(connect_pads
			(clearance 0)
		)
		(min_thickness 0.25)
		(keepout
			(tracks not_allowed)
			(vias allowed)
			(pads allowed)
			(copperpour not_allowed)
			(footprints allowed)
		)
		(placement
			(enabled no)
			(sheetname "")
		)
		(fill yes
			(thermal_gap 0.5)
			(thermal_bridge_width 0.5)
			(island_removal_mode 0)
		)
		(polygon
			(pts
				(arc
					(start 398.49044 -407.00452)
					(mid 397.78686 -407.00452)
					(end 398.49044 -407.00452)
				)
			)
		)
	)
	(zone
		(layers "B.Cu" "In4.Cu" "In6.Cu" "In11.Cu" "In13.Cu" "In15.Cu")
		(hatch none 0.5)
		(connect_pads
			(clearance 0)
		)
		(min_thickness 0.25)
		(keepout
			(tracks not_allowed)
			(vias allowed)
			(pads allowed)
			(copperpour not_allowed)
			(footprints allowed)
		)
		(placement
			(enabled no)
			(sheetname "")
		)
		(fill yes
			(thermal_gap 0.5)
			(thermal_bridge_width 0.5)
			(island_removal_mode 0)
		)
		(polygon
			(pts
				(arc
					(start 43.847004 -244.916706)
					(mid 43.194224 -244.916706)
					(end 43.847004 -244.916706)
				)
			)
		)
	)
	(zone
		(layers "B.Cu" "In4.Cu" "In6.Cu" "In11.Cu" "In13.Cu" "In15.Cu")
		(hatch none 0.5)
		(connect_pads
			(clearance 0)
		)
		(min_thickness 0.25)
		(keepout
			(tracks not_allowed)
			(vias allowed)
			(pads allowed)
			(copperpour not_allowed)
			(footprints allowed)
		)
		(placement
			(enabled no)
			(sheetname "")
		)
		(fill yes
			(thermal_gap 0.5)
			(thermal_bridge_width 0.5)
			(island_removal_mode 0)
		)
		(polygon
			(pts
				(arc
					(start 61.930788 -407.00452)
					(mid 61.227208 -407.00452)
					(end 61.930788 -407.00452)
				)
			)
		)
	)
	(zone
		(layers "B.Cu" "In4.Cu" "In6.Cu" "In11.Cu" "In13.Cu" "In15.Cu")
		(hatch none 0.5)
		(connect_pads
			(clearance 0)
		)
		(min_thickness 0.25)
		(keepout
			(tracks not_allowed)
			(vias allowed)
			(pads allowed)
			(copperpour not_allowed)
			(footprints allowed)
		)
		(placement
			(enabled no)
			(sheetname "")
		)
		(fill yes
			(thermal_gap 0.5)
			(thermal_bridge_width 0.5)
			(island_removal_mode 0)
		)
		(polygon
			(pts
				(arc
					(start 425.09059 -17.601438)
					(mid 424.38701 -17.601438)
					(end 425.09059 -17.601438)
				)
			)
		)
	)
	(zone
		(layers "B.Cu" "In4.Cu" "In6.Cu" "In11.Cu" "In13.Cu" "In15.Cu")
		(hatch none 0.5)
		(connect_pads
			(clearance 0)
		)
		(min_thickness 0.25)
		(keepout
			(tracks not_allowed)
			(vias allowed)
			(pads allowed)
			(copperpour not_allowed)
			(footprints allowed)
		)
		(placement
			(enabled no)
			(sheetname "")
		)
		(fill yes
			(thermal_gap 0.5)
			(thermal_bridge_width 0.5)
			(island_removal_mode 0)
		)
		(polygon
			(pts
				(arc
					(start 88.581484 -265.314176)
					(mid 87.928704 -265.314176)
					(end 88.581484 -265.314176)
				)
			)
		)
	)
	(zone
		(layers "B.Cu" "In4.Cu" "In6.Cu" "In11.Cu" "In13.Cu" "In15.Cu")
		(hatch none 0.5)
		(connect_pads
			(clearance 0)
		)
		(min_thickness 0.25)
		(keepout
			(tracks not_allowed)
			(vias allowed)
			(pads allowed)
			(copperpour not_allowed)
			(footprints allowed)
		)
		(placement
			(enabled no)
			(sheetname "")
		)
		(fill yes
			(thermal_gap 0.5)
			(thermal_bridge_width 0.5)
			(island_removal_mode 0)
		)
		(polygon
			(pts
				(arc
					(start 173.046136 -262.766556)
					(mid 172.393356 -262.766556)
					(end 173.046136 -262.766556)
				)
			)
		)
	)
	(zone
		(layers "B.Cu" "In4.Cu" "In6.Cu" "In11.Cu" "In13.Cu" "In15.Cu")
		(hatch none 0.5)
		(connect_pads
			(clearance 0)
		)
		(min_thickness 0.25)
		(keepout
			(tracks not_allowed)
			(vias allowed)
			(pads allowed)
			(copperpour not_allowed)
			(footprints allowed)
		)
		(placement
			(enabled no)
			(sheetname "")
		)
		(fill yes
			(thermal_gap 0.5)
			(thermal_bridge_width 0.5)
			(island_removal_mode 0)
		)
		(polygon
			(pts
				(arc
					(start 310.318404 -299.316648)
					(mid 309.665624 -299.316648)
					(end 310.318404 -299.316648)
				)
			)
		)
	)
	(zone
		(layers "B.Cu" "In4.Cu" "In6.Cu" "In11.Cu" "In13.Cu" "In15.Cu")
		(hatch none 0.5)
		(connect_pads
			(clearance 0)
		)
		(min_thickness 0.25)
		(keepout
			(tracks not_allowed)
			(vias allowed)
			(pads allowed)
			(copperpour not_allowed)
			(footprints allowed)
		)
		(placement
			(enabled no)
			(sheetname "")
		)
		(fill yes
			(thermal_gap 0.5)
			(thermal_bridge_width 0.5)
			(island_removal_mode 0)
		)
		(polygon
			(pts
				(arc
					(start 356.147624 -224.389442)
					(mid 355.494844 -224.389442)
					(end 356.147624 -224.389442)
				)
			)
		)
	)
	(zone
		(layers "B.Cu" "In4.Cu" "In6.Cu" "In11.Cu" "In13.Cu" "In15.Cu")
		(hatch none 0.5)
		(connect_pads
			(clearance 0)
		)
		(min_thickness 0.25)
		(keepout
			(tracks not_allowed)
			(vias allowed)
			(pads allowed)
			(copperpour not_allowed)
			(footprints allowed)
		)
		(placement
			(enabled no)
			(sheetname "")
		)
		(fill yes
			(thermal_gap 0.5)
			(thermal_bridge_width 0.5)
			(island_removal_mode 0)
		)
		(polygon
			(pts
				(arc
					(start 51.390804 -244.916706)
					(mid 50.738024 -244.916706)
					(end 51.390804 -244.916706)
				)
			)
		)
	)
	(zone
		(layers "B.Cu" "In4.Cu" "In6.Cu" "In11.Cu" "In13.Cu" "In15.Cu")
		(hatch none 0.5)
		(connect_pads
			(clearance 0)
		)
		(min_thickness 0.25)
		(keepout
			(tracks not_allowed)
			(vias allowed)
			(pads allowed)
			(copperpour not_allowed)
			(footprints allowed)
		)
		(placement
			(enabled no)
			(sheetname "")
		)
		(fill yes
			(thermal_gap 0.5)
			(thermal_bridge_width 0.5)
			(island_removal_mode 0)
		)
		(polygon
			(pts
				(arc
					(start 336.88147 -246.364506)
					(mid 336.22869 -246.364506)
					(end 336.88147 -246.364506)
				)
			)
		)
	)
	(zone
		(layers "B.Cu" "In4.Cu" "In6.Cu" "In11.Cu" "In13.Cu" "In15.Cu")
		(hatch none 0.5)
		(connect_pads
			(clearance 0)
		)
		(min_thickness 0.25)
		(keepout
			(tracks not_allowed)
			(vias allowed)
			(pads allowed)
			(copperpour not_allowed)
			(footprints allowed)
		)
		(placement
			(enabled no)
			(sheetname "")
		)
		(fill yes
			(thermal_gap 0.5)
			(thermal_bridge_width 0.5)
			(island_removal_mode 0)
		)
		(polygon
			(pts
				(arc
					(start 338.871052 -274.266914)
					(mid 338.218272 -274.266914)
					(end 338.871052 -274.266914)
				)
			)
		)
	)
	(zone
		(layers "B.Cu" "In4.Cu" "In6.Cu" "In11.Cu" "In13.Cu" "In15.Cu")
		(hatch none 0.5)
		(connect_pads
			(clearance 0)
		)
		(min_thickness 0.25)
		(keepout
			(tracks not_allowed)
			(vias allowed)
			(pads allowed)
			(copperpour not_allowed)
			(footprints allowed)
		)
		(placement
			(enabled no)
			(sheetname "")
		)
		(fill yes
			(thermal_gap 0.5)
			(thermal_bridge_width 0.5)
			(island_removal_mode 0)
		)
		(polygon
			(pts
				(arc
					(start 58.867548 -407.00452)
					(mid 58.163968 -407.00452)
					(end 58.867548 -407.00452)
				)
			)
		)
	)
	(zone
		(layers "B.Cu" "In4.Cu" "In6.Cu" "In11.Cu" "In13.Cu" "In15.Cu")
		(hatch none 0.5)
		(connect_pads
			(clearance 0)
		)
		(min_thickness 0.25)
		(keepout
			(tracks not_allowed)
			(vias allowed)
			(pads allowed)
			(copperpour not_allowed)
			(footprints allowed)
		)
		(placement
			(enabled no)
			(sheetname "")
		)
		(fill yes
			(thermal_gap 0.5)
			(thermal_bridge_width 0.5)
			(island_removal_mode 0)
		)
		(polygon
			(pts
				(arc
					(start 134.052056 -231.714548)
					(mid 133.399276 -231.714548)
					(end 134.052056 -231.714548)
				)
			)
		)
	)
	(zone
		(layers "B.Cu" "In4.Cu" "In6.Cu" "In11.Cu" "In13.Cu" "In15.Cu")
		(hatch none 0.5)
		(connect_pads
			(clearance 0)
		)
		(min_thickness 0.25)
		(keepout
			(tracks not_allowed)
			(vias allowed)
			(pads allowed)
			(copperpour not_allowed)
			(footprints allowed)
		)
		(placement
			(enabled no)
			(sheetname "")
		)
		(fill yes
			(thermal_gap 0.5)
			(thermal_bridge_width 0.5)
			(island_removal_mode 0)
		)
		(polygon
			(pts
				(arc
					(start 425.162472 -276.366732)
					(mid 424.509692 -276.366732)
					(end 425.162472 -276.366732)
				)
			)
		)
	)
	(zone
		(layers "B.Cu" "In4.Cu" "In6.Cu" "In11.Cu" "In13.Cu" "In15.Cu")
		(hatch none 0.5)
		(connect_pads
			(clearance 0)
		)
		(min_thickness 0.25)
		(keepout
			(tracks not_allowed)
			(vias allowed)
			(pads allowed)
			(copperpour not_allowed)
			(footprints allowed)
		)
		(placement
			(enabled no)
			(sheetname "")
		)
		(fill yes
			(thermal_gap 0.5)
			(thermal_bridge_width 0.5)
			(island_removal_mode 0)
		)
		(polygon
			(pts
				(arc
					(start 420.986204 -261.066788)
					(mid 420.333424 -261.066788)
					(end 420.986204 -261.066788)
				)
			)
		)
	)
	(zone
		(layers "B.Cu" "In4.Cu" "In6.Cu" "In11.Cu" "In13.Cu" "In15.Cu")
		(hatch none 0.5)
		(connect_pads
			(clearance 0)
		)
		(min_thickness 0.25)
		(keepout
			(tracks not_allowed)
			(vias allowed)
			(pads allowed)
			(copperpour not_allowed)
			(footprints allowed)
		)
		(placement
			(enabled no)
			(sheetname "")
		)
		(fill yes
			(thermal_gap 0.5)
			(thermal_bridge_width 0.5)
			(island_removal_mode 0)
		)
		(polygon
			(pts
				(arc
					(start 342.630252 -285.661354)
					(mid 341.977472 -285.661354)
					(end 342.630252 -285.661354)
				)
			)
		)
	)
	(zone
		(layers "B.Cu" "In4.Cu" "In6.Cu" "In11.Cu" "In13.Cu" "In15.Cu")
		(hatch none 0.5)
		(connect_pads
			(clearance 0)
		)
		(min_thickness 0.25)
		(keepout
			(tracks not_allowed)
			(vias allowed)
			(pads allowed)
			(copperpour not_allowed)
			(footprints allowed)
		)
		(placement
			(enabled no)
			(sheetname "")
		)
		(fill yes
			(thermal_gap 0.5)
			(thermal_bridge_width 0.5)
			(island_removal_mode 0)
		)
		(polygon
			(pts
				(arc
					(start 339.70087 -249.620024)
					(mid 339.04809 -249.620024)
					(end 339.70087 -249.620024)
				)
			)
		)
	)
	(zone
		(layers "B.Cu" "In4.Cu" "In6.Cu" "In11.Cu" "In13.Cu" "In15.Cu")
		(hatch none 0.5)
		(connect_pads
			(clearance 0)
		)
		(min_thickness 0.25)
		(keepout
			(tracks not_allowed)
			(vias allowed)
			(pads allowed)
			(copperpour not_allowed)
			(footprints allowed)
		)
		(placement
			(enabled no)
			(sheetname "")
		)
		(fill yes
			(thermal_gap 0.5)
			(thermal_bridge_width 0.5)
			(island_removal_mode 0)
		)
		(polygon
			(pts
				(arc
					(start 421.062404 -239.81664)
					(mid 420.409624 -239.81664)
					(end 421.062404 -239.81664)
				)
			)
		)
	)
	(zone
		(layers "B.Cu" "In4.Cu" "In6.Cu" "In11.Cu" "In13.Cu" "In15.Cu")
		(hatch none 0.5)
		(connect_pads
			(clearance 0)
		)
		(min_thickness 0.25)
		(keepout
			(tracks not_allowed)
			(vias allowed)
			(pads allowed)
			(copperpour not_allowed)
			(footprints allowed)
		)
		(placement
			(enabled no)
			(sheetname "")
		)
		(fill yes
			(thermal_gap 0.5)
			(thermal_bridge_width 0.5)
			(island_removal_mode 0)
		)
		(polygon
			(pts
				(arc
					(start 336.991452 -274.266914)
					(mid 336.338672 -274.266914)
					(end 336.991452 -274.266914)
				)
			)
		)
	)
	(zone
		(layers "B.Cu" "In4.Cu" "In6.Cu" "In11.Cu" "In13.Cu" "In15.Cu")
		(hatch none 0.5)
		(connect_pads
			(clearance 0)
		)
		(min_thickness 0.25)
		(keepout
			(tracks not_allowed)
			(vias allowed)
			(pads allowed)
			(copperpour not_allowed)
			(footprints allowed)
		)
		(placement
			(enabled no)
			(sheetname "")
		)
		(fill yes
			(thermal_gap 0.5)
			(thermal_bridge_width 0.5)
			(island_removal_mode 0)
		)
		(polygon
			(pts
				(arc
					(start 311.321958 -400.858228)
					(mid 310.618378 -400.858228)
					(end 311.321958 -400.858228)
				)
			)
		)
	)
	(zone
		(layers "B.Cu" "In4.Cu" "In6.Cu" "In11.Cu" "In13.Cu" "In15.Cu")
		(hatch none 0.5)
		(connect_pads
			(clearance 0)
		)
		(min_thickness 0.25)
		(keepout
			(tracks not_allowed)
			(vias allowed)
			(pads allowed)
			(copperpour not_allowed)
			(footprints allowed)
		)
		(placement
			(enabled no)
			(sheetname "")
		)
		(fill yes
			(thermal_gap 0.5)
			(thermal_bridge_width 0.5)
			(island_removal_mode 0)
		)
		(polygon
			(pts
				(arc
					(start 90.821002 -247.992138)
					(mid 90.168222 -247.992138)
					(end 90.821002 -247.992138)
				)
			)
		)
	)
	(zone
		(layers "B.Cu" "In4.Cu" "In6.Cu" "In11.Cu" "In13.Cu" "In15.Cu")
		(hatch none 0.5)
		(connect_pads
			(clearance 0)
		)
		(min_thickness 0.25)
		(keepout
			(tracks not_allowed)
			(vias allowed)
			(pads allowed)
			(copperpour not_allowed)
			(footprints allowed)
		)
		(placement
			(enabled no)
			(sheetname "")
		)
		(fill yes
			(thermal_gap 0.5)
			(thermal_bridge_width 0.5)
			(island_removal_mode 0)
		)
		(polygon
			(pts
				(arc
					(start 123.354338 -284.847538)
					(mid 122.701558 -284.847538)
					(end 123.354338 -284.847538)
				)
			)
		)
	)
	(zone
		(layers "B.Cu" "In4.Cu" "In6.Cu" "In11.Cu" "In13.Cu" "In15.Cu")
		(hatch none 0.5)
		(connect_pads
			(clearance 0)
		)
		(min_thickness 0.25)
		(keepout
			(tracks not_allowed)
			(vias allowed)
			(pads allowed)
			(copperpour not_allowed)
			(footprints allowed)
		)
		(placement
			(enabled no)
			(sheetname "")
		)
		(fill yes
			(thermal_gap 0.5)
			(thermal_bridge_width 0.5)
			(island_removal_mode 0)
		)
		(polygon
			(pts
				(arc
					(start 153.348944 -407.00452)
					(mid 152.645364 -407.00452)
					(end 153.348944 -407.00452)
				)
			)
		)
	)
	(zone
		(layers "B.Cu" "In4.Cu" "In6.Cu" "In11.Cu" "In13.Cu" "In15.Cu")
		(hatch none 0.5)
		(connect_pads
			(clearance 0)
		)
		(min_thickness 0.25)
		(keepout
			(tracks not_allowed)
			(vias allowed)
			(pads allowed)
			(copperpour not_allowed)
			(footprints allowed)
		)
		(placement
			(enabled no)
			(sheetname "")
		)
		(fill yes
			(thermal_gap 0.5)
			(thermal_bridge_width 0.5)
			(island_removal_mode 0)
		)
		(polygon
			(pts
				(arc
					(start 47.290736 -277.216616)
					(mid 46.637956 -277.216616)
					(end 47.290736 -277.216616)
				)
			)
		)
	)
	(zone
		(layers "B.Cu" "In4.Cu" "In6.Cu" "In11.Cu" "In13.Cu" "In15.Cu")
		(hatch none 0.5)
		(connect_pads
			(clearance 0)
		)
		(min_thickness 0.25)
		(keepout
			(tracks not_allowed)
			(vias allowed)
			(pads allowed)
			(copperpour not_allowed)
			(footprints allowed)
		)
		(placement
			(enabled no)
			(sheetname "")
		)
		(fill yes
			(thermal_gap 0.5)
			(thermal_bridge_width 0.5)
			(island_removal_mode 0)
		)
		(polygon
			(pts
				(arc
					(start 177.222404 -214.316564)
					(mid 176.569624 -214.316564)
					(end 177.222404 -214.316564)
				)
			)
		)
	)
	(zone
		(layers "B.Cu" "In4.Cu" "In6.Cu" "In11.Cu" "In13.Cu" "In15.Cu")
		(hatch none 0.5)
		(connect_pads
			(clearance 0)
		)
		(min_thickness 0.25)
		(keepout
			(tracks not_allowed)
			(vias allowed)
			(pads allowed)
			(copperpour not_allowed)
			(footprints allowed)
		)
		(placement
			(enabled no)
			(sheetname "")
		)
		(fill yes
			(thermal_gap 0.5)
			(thermal_bridge_width 0.5)
			(island_removal_mode 0)
		)
		(polygon
			(pts
				(arc
					(start 336.412078 -242.294918)
					(mid 335.759298 -242.294918)
					(end 336.412078 -242.294918)
				)
			)
		)
	)
	(zone
		(layers "B.Cu" "In4.Cu" "In6.Cu" "In11.Cu" "In13.Cu" "In15.Cu")
		(hatch none 0.5)
		(connect_pads
			(clearance 0)
		)
		(min_thickness 0.25)
		(keepout
			(tracks not_allowed)
			(vias allowed)
			(pads allowed)
			(copperpour not_allowed)
			(footprints allowed)
		)
		(placement
			(enabled no)
			(sheetname "")
		)
		(fill yes
			(thermal_gap 0.5)
			(thermal_bridge_width 0.5)
			(island_removal_mode 0)
		)
		(polygon
			(pts
				(arc
					(start 47.290736 -205.816708)
					(mid 46.637956 -205.816708)
					(end 47.290736 -205.816708)
				)
			)
		)
	)
	(zone
		(layers "B.Cu" "In4.Cu" "In6.Cu" "In11.Cu" "In13.Cu" "In15.Cu")
		(hatch none 0.5)
		(connect_pads
			(clearance 0)
		)
		(min_thickness 0.25)
		(keepout
			(tracks not_allowed)
			(vias allowed)
			(pads allowed)
			(copperpour not_allowed)
			(footprints allowed)
		)
		(placement
			(enabled no)
			(sheetname "")
		)
		(fill yes
			(thermal_gap 0.5)
			(thermal_bridge_width 0.5)
			(island_removal_mode 0)
		)
		(polygon
			(pts
				(arc
					(start 89.521538 -260.430772)
					(mid 88.868758 -260.430772)
					(end 89.521538 -260.430772)
				)
			)
		)
	)
	(zone
		(layers "B.Cu" "In4.Cu" "In6.Cu" "In11.Cu" "In13.Cu" "In15.Cu")
		(hatch none 0.5)
		(connect_pads
			(clearance 0)
		)
		(min_thickness 0.25)
		(keepout
			(tracks not_allowed)
			(vias allowed)
			(pads allowed)
			(copperpour not_allowed)
			(footprints allowed)
		)
		(placement
			(enabled no)
			(sheetname "")
		)
		(fill yes
			(thermal_gap 0.5)
			(thermal_bridge_width 0.5)
			(island_removal_mode 0)
		)
		(polygon
			(pts
				(arc
					(start 173.122336 -222.816674)
					(mid 172.469556 -222.816674)
					(end 173.122336 -222.816674)
				)
			)
		)
	)
	(zone
		(layers "B.Cu" "In4.Cu" "In6.Cu" "In11.Cu" "In13.Cu" "In15.Cu")
		(hatch none 0.5)
		(connect_pads
			(clearance 0)
		)
		(min_thickness 0.25)
		(keepout
			(tracks not_allowed)
			(vias allowed)
			(pads allowed)
			(copperpour not_allowed)
			(footprints allowed)
		)
		(placement
			(enabled no)
			(sheetname "")
		)
		(fill yes
			(thermal_gap 0.5)
			(thermal_bridge_width 0.5)
			(island_removal_mode 0)
		)
		(polygon
			(pts
				(arc
					(start 131.906264 -407.00452)
					(mid 131.202684 -407.00452)
					(end 131.906264 -407.00452)
				)
			)
		)
	)
	(zone
		(layers "B.Cu" "In4.Cu" "In6.Cu" "In11.Cu" "In13.Cu" "In15.Cu")
		(hatch none 0.5)
		(connect_pads
			(clearance 0)
		)
		(min_thickness 0.25)
		(keepout
			(tracks not_allowed)
			(vias allowed)
			(pads allowed)
			(copperpour not_allowed)
			(footprints allowed)
		)
		(placement
			(enabled no)
			(sheetname "")
		)
		(fill yes
			(thermal_gap 0.5)
			(thermal_bridge_width 0.5)
			(island_removal_mode 0)
		)
		(polygon
			(pts
				(arc
					(start 177.222404 -206.666592)
					(mid 176.569624 -206.666592)
					(end 177.222404 -206.666592)
				)
			)
		)
	)
	(zone
		(layers "B.Cu" "In4.Cu" "In6.Cu" "In11.Cu" "In13.Cu" "In15.Cu")
		(hatch none 0.5)
		(connect_pads
			(clearance 0)
		)
		(min_thickness 0.25)
		(keepout
			(tracks not_allowed)
			(vias allowed)
			(pads allowed)
			(copperpour not_allowed)
			(footprints allowed)
		)
		(placement
			(enabled no)
			(sheetname "")
		)
		(fill yes
			(thermal_gap 0.5)
			(thermal_bridge_width 0.5)
			(island_removal_mode 0)
		)
		(polygon
			(pts
				(arc
					(start 425.162472 -295.06672)
					(mid 424.509692 -295.06672)
					(end 425.162472 -295.06672)
				)
			)
		)
	)
	(zone
		(layers "B.Cu" "In4.Cu" "In6.Cu" "In11.Cu" "In13.Cu" "In15.Cu")
		(hatch none 0.5)
		(connect_pads
			(clearance 0)
		)
		(min_thickness 0.25)
		(keepout
			(tracks not_allowed)
			(vias allowed)
			(pads allowed)
			(copperpour not_allowed)
			(footprints allowed)
		)
		(placement
			(enabled no)
			(sheetname "")
		)
		(fill yes
			(thermal_gap 0.5)
			(thermal_bridge_width 0.5)
			(island_removal_mode 0)
		)
		(polygon
			(pts
				(arc
					(start 336.88147 -241.481102)
					(mid 336.22869 -241.481102)
					(end 336.88147 -241.481102)
				)
			)
		)
	)
	(zone
		(layers "B.Cu" "In4.Cu" "In6.Cu" "In11.Cu" "In13.Cu" "In15.Cu")
		(hatch none 0.5)
		(connect_pads
			(clearance 0)
		)
		(min_thickness 0.25)
		(keepout
			(tracks not_allowed)
			(vias allowed)
			(pads allowed)
			(copperpour not_allowed)
			(footprints allowed)
		)
		(placement
			(enabled no)
			(sheetname "")
		)
		(fill yes
			(thermal_gap 0.5)
			(thermal_bridge_width 0.5)
			(island_removal_mode 0)
		)
		(polygon
			(pts
				(arc
					(start 167.801544 -407.00452)
					(mid 167.097964 -407.00452)
					(end 167.801544 -407.00452)
				)
			)
		)
	)
	(zone
		(layers "B.Cu" "In4.Cu" "In6.Cu" "In11.Cu" "In13.Cu" "In15.Cu")
		(hatch none 0.5)
		(connect_pads
			(clearance 0)
		)
		(min_thickness 0.25)
		(keepout
			(tracks not_allowed)
			(vias allowed)
			(pads allowed)
			(copperpour not_allowed)
			(footprints allowed)
		)
		(placement
			(enabled no)
			(sheetname "")
		)
		(fill yes
			(thermal_gap 0.5)
			(thermal_bridge_width 0.5)
			(island_removal_mode 0)
		)
		(polygon
			(pts
				(arc
					(start 173.122336 -219.41663)
					(mid 172.469556 -219.41663)
					(end 173.122336 -219.41663)
				)
			)
		)
	)
	(zone
		(layers "B.Cu" "In4.Cu" "In6.Cu" "In11.Cu" "In13.Cu" "In15.Cu")
		(hatch none 0.5)
		(connect_pads
			(clearance 0)
		)
		(min_thickness 0.25)
		(keepout
			(tracks not_allowed)
			(vias allowed)
			(pads allowed)
			(copperpour not_allowed)
			(footprints allowed)
		)
		(placement
			(enabled no)
			(sheetname "")
		)
		(fill yes
			(thermal_gap 0.5)
			(thermal_bridge_width 0.5)
			(island_removal_mode 0)
		)
		(polygon
			(pts
				(arc
					(start 88.941656 -236.597952)
					(mid 88.288876 -236.597952)
					(end 88.941656 -236.597952)
				)
			)
		)
	)
	(zone
		(layers "B.Cu" "In4.Cu" "In6.Cu" "In11.Cu" "In13.Cu" "In15.Cu")
		(hatch none 0.5)
		(connect_pads
			(clearance 0)
		)
		(min_thickness 0.25)
		(keepout
			(tracks not_allowed)
			(vias allowed)
			(pads allowed)
			(copperpour not_allowed)
			(footprints allowed)
		)
		(placement
			(enabled no)
			(sheetname "")
		)
		(fill yes
			(thermal_gap 0.5)
			(thermal_bridge_width 0.5)
			(island_removal_mode 0)
		)
		(polygon
			(pts
				(arc
					(start 119.595138 -284.847538)
					(mid 118.942358 -284.847538)
					(end 119.595138 -284.847538)
				)
			)
		)
	)
	(zone
		(layers "B.Cu" "In4.Cu" "In6.Cu" "In11.Cu" "In13.Cu" "In15.Cu")
		(hatch none 0.5)
		(connect_pads
			(clearance 0)
		)
		(min_thickness 0.25)
		(keepout
			(tracks not_allowed)
			(vias allowed)
			(pads allowed)
			(copperpour not_allowed)
			(footprints allowed)
		)
		(placement
			(enabled no)
			(sheetname "")
		)
		(fill yes
			(thermal_gap 0.5)
			(thermal_bridge_width 0.5)
			(island_removal_mode 0)
		)
		(polygon
			(pts
				(arc
					(start 131.812538 -255.547622)
					(mid 131.159758 -255.547622)
					(end 131.812538 -255.547622)
				)
			)
		)
	)
	(zone
		(layers "B.Cu" "In4.Cu" "In6.Cu" "In11.Cu" "In13.Cu" "In15.Cu")
		(hatch none 0.5)
		(connect_pads
			(clearance 0)
		)
		(min_thickness 0.25)
		(keepout
			(tracks not_allowed)
			(vias allowed)
			(pads allowed)
			(copperpour not_allowed)
			(footprints allowed)
		)
		(placement
			(enabled no)
			(sheetname "")
		)
		(fill yes
			(thermal_gap 0.5)
			(thermal_bridge_width 0.5)
			(island_removal_mode 0)
		)
		(polygon
			(pts
				(arc
					(start 47.789084 -19.13636)
					(mid 47.085504 -19.13636)
					(end 47.789084 -19.13636)
				)
			)
		)
	)
	(zone
		(layers "B.Cu" "In4.Cu" "In6.Cu" "In11.Cu" "In13.Cu" "In15.Cu")
		(hatch none 0.5)
		(connect_pads
			(clearance 0)
		)
		(min_thickness 0.25)
		(keepout
			(tracks not_allowed)
			(vias allowed)
			(pads allowed)
			(copperpour not_allowed)
			(footprints allowed)
		)
		(placement
			(enabled no)
			(sheetname "")
		)
		(fill yes
			(thermal_gap 0.5)
			(thermal_bridge_width 0.5)
			(island_removal_mode 0)
		)
		(polygon
			(pts
				(arc
					(start 51.416204 -296.766742)
					(mid 50.763424 -296.766742)
					(end 51.416204 -296.766742)
				)
			)
		)
	)
	(zone
		(layers "B.Cu" "In4.Cu" "In6.Cu" "In11.Cu" "In13.Cu" "In15.Cu")
		(hatch none 0.5)
		(connect_pads
			(clearance 0)
		)
		(min_thickness 0.25)
		(keepout
			(tracks not_allowed)
			(vias allowed)
			(pads allowed)
			(copperpour not_allowed)
			(footprints allowed)
		)
		(placement
			(enabled no)
			(sheetname "")
		)
		(fill yes
			(thermal_gap 0.5)
			(thermal_bridge_width 0.5)
			(island_removal_mode 0)
		)
		(polygon
			(pts
				(arc
					(start 158.009336 -232.166668)
					(mid 157.356556 -232.166668)
					(end 158.009336 -232.166668)
				)
			)
		)
	)
	(zone
		(layers "B.Cu" "In4.Cu" "In6.Cu" "In11.Cu" "In13.Cu" "In15.Cu")
		(hatch none 0.5)
		(connect_pads
			(clearance 0)
		)
		(min_thickness 0.25)
		(keepout
			(tracks not_allowed)
			(vias allowed)
			(pads allowed)
			(copperpour not_allowed)
			(footprints allowed)
		)
		(placement
			(enabled no)
			(sheetname "")
		)
		(fill yes
			(thermal_gap 0.5)
			(thermal_bridge_width 0.5)
			(island_removal_mode 0)
		)
		(polygon
			(pts
				(arc
					(start 383.041652 -262.872474)
					(mid 382.388872 -262.872474)
					(end 383.041652 -262.872474)
				)
			)
		)
	)
	(zone
		(layers "B.Cu" "In4.Cu" "In6.Cu" "In11.Cu" "In13.Cu" "In15.Cu")
		(hatch none 0.5)
		(connect_pads
			(clearance 0)
		)
		(min_thickness 0.25)
		(keepout
			(tracks not_allowed)
			(vias allowed)
			(pads allowed)
			(copperpour not_allowed)
			(footprints allowed)
		)
		(placement
			(enabled no)
			(sheetname "")
		)
		(fill yes
			(thermal_gap 0.5)
			(thermal_bridge_width 0.5)
			(island_removal_mode 0)
		)
		(polygon
			(pts
				(arc
					(start 338.291424 -239.0394)
					(mid 337.638644 -239.0394)
					(end 338.291424 -239.0394)
				)
			)
		)
	)
	(zone
		(layers "B.Cu" "In4.Cu" "In6.Cu" "In11.Cu" "In13.Cu" "In15.Cu")
		(hatch none 0.5)
		(connect_pads
			(clearance 0)
		)
		(min_thickness 0.25)
		(keepout
			(tracks not_allowed)
			(vias allowed)
			(pads allowed)
			(copperpour not_allowed)
			(footprints allowed)
		)
		(placement
			(enabled no)
			(sheetname "")
		)
		(fill yes
			(thermal_gap 0.5)
			(thermal_bridge_width 0.5)
			(island_removal_mode 0)
		)
		(polygon
			(pts
				(arc
					(start 156.412184 -407.00452)
					(mid 155.708604 -407.00452)
					(end 156.412184 -407.00452)
				)
			)
		)
	)
	(zone
		(layers "B.Cu" "In4.Cu" "In6.Cu" "In11.Cu" "In13.Cu" "In15.Cu")
		(hatch none 0.5)
		(connect_pads
			(clearance 0)
		)
		(min_thickness 0.25)
		(keepout
			(tracks not_allowed)
			(vias allowed)
			(pads allowed)
			(copperpour not_allowed)
			(footprints allowed)
		)
		(placement
			(enabled no)
			(sheetname "")
		)
		(fill yes
			(thermal_gap 0.5)
			(thermal_bridge_width 0.5)
			(island_removal_mode 0)
		)
		(polygon
			(pts
				(arc
					(start 134.991856 -230.086662)
					(mid 134.339076 -230.086662)
					(end 134.991856 -230.086662)
				)
			)
		)
	)
	(zone
		(layers "B.Cu" "In4.Cu" "In6.Cu" "In11.Cu" "In13.Cu" "In15.Cu")
		(hatch none 0.5)
		(connect_pads
			(clearance 0)
		)
		(min_thickness 0.25)
		(keepout
			(tracks not_allowed)
			(vias allowed)
			(pads allowed)
			(copperpour not_allowed)
			(footprints allowed)
		)
		(placement
			(enabled no)
			(sheetname "")
		)
		(fill yes
			(thermal_gap 0.5)
			(thermal_bridge_width 0.5)
			(island_removal_mode 0)
		)
		(polygon
			(pts
				(arc
					(start 134.161784 -262.872474)
					(mid 133.509004 -262.872474)
					(end 134.161784 -262.872474)
				)
			)
		)
	)
	(zone
		(layers "B.Cu" "In4.Cu" "In6.Cu" "In11.Cu" "In13.Cu" "In15.Cu")
		(hatch none 0.5)
		(connect_pads
			(clearance 0)
		)
		(min_thickness 0.25)
		(keepout
			(tracks not_allowed)
			(vias allowed)
			(pads allowed)
			(copperpour not_allowed)
			(footprints allowed)
		)
		(placement
			(enabled no)
			(sheetname "")
		)
		(fill yes
			(thermal_gap 0.5)
			(thermal_bridge_width 0.5)
			(island_removal_mode 0)
		)
		(polygon
			(pts
				(arc
					(start 122.716544 -407.00452)
					(mid 122.012964 -407.00452)
					(end 122.716544 -407.00452)
				)
			)
		)
	)
	(zone
		(layers "B.Cu" "In4.Cu" "In6.Cu" "In11.Cu" "In13.Cu" "In15.Cu")
		(hatch none 0.5)
		(connect_pads
			(clearance 0)
		)
		(min_thickness 0.25)
		(keepout
			(tracks not_allowed)
			(vias allowed)
			(pads allowed)
			(copperpour not_allowed)
			(footprints allowed)
		)
		(placement
			(enabled no)
			(sheetname "")
		)
		(fill yes
			(thermal_gap 0.5)
			(thermal_bridge_width 0.5)
			(island_removal_mode 0)
		)
		(polygon
			(pts
				(arc
					(start 51.416204 -313.766708)
					(mid 50.763424 -313.766708)
					(end 51.416204 -313.766708)
				)
			)
		)
	)
	(zone
		(layers "B.Cu" "In4.Cu" "In6.Cu" "In11.Cu" "In13.Cu" "In15.Cu")
		(hatch none 0.5)
		(connect_pads
			(clearance 0)
		)
		(min_thickness 0.25)
		(keepout
			(tracks not_allowed)
			(vias allowed)
			(pads allowed)
			(copperpour not_allowed)
			(footprints allowed)
		)
		(placement
			(enabled no)
			(sheetname "")
		)
		(fill yes
			(thermal_gap 0.5)
			(thermal_bridge_width 0.5)
			(island_removal_mode 0)
		)
		(polygon
			(pts
				(arc
					(start 299.330872 -251.716794)
					(mid 298.678092 -251.716794)
					(end 299.330872 -251.716794)
				)
			)
		)
	)
	(zone
		(layers "B.Cu" "In4.Cu" "In6.Cu" "In11.Cu" "In13.Cu" "In15.Cu")
		(hatch none 0.5)
		(connect_pads
			(clearance 0)
		)
		(min_thickness 0.25)
		(keepout
			(tracks not_allowed)
			(vias allowed)
			(pads allowed)
			(copperpour not_allowed)
			(footprints allowed)
		)
		(placement
			(enabled no)
			(sheetname "")
		)
		(fill yes
			(thermal_gap 0.5)
			(thermal_bridge_width 0.5)
			(island_removal_mode 0)
		)
		(polygon
			(pts
				(arc
					(start 337.461352 -276.708616)
					(mid 336.808572 -276.708616)
					(end 337.461352 -276.708616)
				)
			)
		)
	)
	(zone
		(layers "B.Cu" "In4.Cu" "In6.Cu" "In11.Cu" "In13.Cu" "In15.Cu")
		(hatch none 0.5)
		(connect_pads
			(clearance 0)
		)
		(min_thickness 0.25)
		(keepout
			(tracks not_allowed)
			(vias allowed)
			(pads allowed)
			(copperpour not_allowed)
			(footprints allowed)
		)
		(placement
			(enabled no)
			(sheetname "")
		)
		(fill yes
			(thermal_gap 0.5)
			(thermal_bridge_width 0.5)
			(island_removal_mode 0)
		)
		(polygon
			(pts
				(arc
					(start 416.00628 -407.00452)
					(mid 415.3027 -407.00452)
					(end 416.00628 -407.00452)
				)
			)
		)
	)
	(zone
		(layers "B.Cu" "In4.Cu" "In6.Cu" "In11.Cu" "In13.Cu" "In15.Cu")
		(hatch none 0.5)
		(connect_pads
			(clearance 0)
		)
		(min_thickness 0.25)
		(keepout
			(tracks not_allowed)
			(vias allowed)
			(pads allowed)
			(copperpour not_allowed)
			(footprints allowed)
		)
		(placement
			(enabled no)
			(sheetname "")
		)
		(fill yes
			(thermal_gap 0.5)
			(thermal_bridge_width 0.5)
			(island_removal_mode 0)
		)
		(polygon
			(pts
				(arc
					(start 89.411556 -229.272846)
					(mid 88.758776 -229.272846)
					(end 89.411556 -229.272846)
				)
			)
		)
	)
	(zone
		(layers "B.Cu" "In4.Cu" "In6.Cu" "In11.Cu" "In13.Cu" "In15.Cu")
		(hatch none 0.5)
		(connect_pads
			(clearance 0)
		)
		(min_thickness 0.25)
		(keepout
			(tracks not_allowed)
			(vias allowed)
			(pads allowed)
			(copperpour not_allowed)
			(footprints allowed)
		)
		(placement
			(enabled no)
			(sheetname "")
		)
		(fill yes
			(thermal_gap 0.5)
			(thermal_bridge_width 0.5)
			(island_removal_mode 0)
		)
		(polygon
			(pts
				(arc
					(start 133.221984 -285.661354)
					(mid 132.569204 -285.661354)
					(end 133.221984 -285.661354)
				)
			)
		)
	)
	(zone
		(layers "B.Cu" "In4.Cu" "In6.Cu" "In11.Cu" "In13.Cu" "In15.Cu")
		(hatch none 0.5)
		(connect_pads
			(clearance 0)
		)
		(min_thickness 0.25)
		(keepout
			(tracks not_allowed)
			(vias allowed)
			(pads allowed)
			(copperpour not_allowed)
			(footprints allowed)
		)
		(placement
			(enabled no)
			(sheetname "")
		)
		(fill yes
			(thermal_gap 0.5)
			(thermal_bridge_width 0.5)
			(island_removal_mode 0)
		)
		(polygon
			(pts
				(arc
					(start 295.230804 -237.266734)
					(mid 294.578024 -237.266734)
					(end 295.230804 -237.266734)
				)
			)
		)
	)
	(zone
		(layers "B.Cu" "In4.Cu" "In6.Cu" "In11.Cu" "In13.Cu" "In15.Cu")
		(hatch none 0.5)
		(connect_pads
			(clearance 0)
		)
		(min_thickness 0.25)
		(keepout
			(tracks not_allowed)
			(vias allowed)
			(pads allowed)
			(copperpour not_allowed)
			(footprints allowed)
		)
		(placement
			(enabled no)
			(sheetname "")
		)
		(fill yes
			(thermal_gap 0.5)
			(thermal_bridge_width 0.5)
			(island_removal_mode 0)
		)
		(polygon
			(pts
				(arc
					(start 159.475424 -407.00452)
					(mid 158.771844 -407.00452)
					(end 159.475424 -407.00452)
				)
			)
		)
	)
	(zone
		(layers "B.Cu" "In4.Cu" "In6.Cu" "In11.Cu" "In13.Cu" "In15.Cu")
		(hatch none 0.5)
		(connect_pads
			(clearance 0)
		)
		(min_thickness 0.25)
		(keepout
			(tracks not_allowed)
			(vias allowed)
			(pads allowed)
			(copperpour not_allowed)
			(footprints allowed)
		)
		(placement
			(enabled no)
			(sheetname "")
		)
		(fill yes
			(thermal_gap 0.5)
			(thermal_bridge_width 0.5)
			(island_removal_mode 0)
		)
		(polygon
			(pts
				(arc
					(start 97.039938 -284.847538)
					(mid 96.387158 -284.847538)
					(end 97.039938 -284.847538)
				)
			)
		)
	)
	(zone
		(layers "B.Cu" "In4.Cu" "In6.Cu" "In11.Cu" "In13.Cu" "In15.Cu")
		(hatch none 0.5)
		(connect_pads
			(clearance 0)
		)
		(min_thickness 0.25)
		(keepout
			(tracks not_allowed)
			(vias allowed)
			(pads allowed)
			(copperpour not_allowed)
			(footprints allowed)
		)
		(placement
			(enabled no)
			(sheetname "")
		)
		(fill yes
			(thermal_gap 0.5)
			(thermal_bridge_width 0.5)
			(island_removal_mode 0)
		)
		(polygon
			(pts
				(arc
					(start 421.062404 -252.566678)
					(mid 420.409624 -252.566678)
					(end 421.062404 -252.566678)
				)
			)
		)
	)
	(zone
		(layers "B.Cu" "In4.Cu" "In6.Cu" "In11.Cu" "In13.Cu" "In15.Cu")
		(hatch none 0.5)
		(connect_pads
			(clearance 0)
		)
		(min_thickness 0.25)
		(keepout
			(tracks not_allowed)
			(vias allowed)
			(pads allowed)
			(copperpour not_allowed)
			(footprints allowed)
		)
		(placement
			(enabled no)
			(sheetname "")
		)
		(fill yes
			(thermal_gap 0.5)
			(thermal_bridge_width 0.5)
			(island_removal_mode 0)
		)
		(polygon
			(pts
				(arc
					(start 90.351356 -235.783882)
					(mid 89.698576 -235.783882)
					(end 90.351356 -235.783882)
				)
			)
		)
	)
	(zone
		(layers "B.Cu" "In4.Cu" "In6.Cu" "In11.Cu" "In13.Cu" "In15.Cu")
		(hatch none 0.5)
		(connect_pads
			(clearance 0)
		)
		(min_thickness 0.25)
		(keepout
			(tracks not_allowed)
			(vias allowed)
			(pads allowed)
			(copperpour not_allowed)
			(footprints allowed)
		)
		(placement
			(enabled no)
			(sheetname "")
		)
		(fill yes
			(thermal_gap 0.5)
			(thermal_bridge_width 0.5)
			(island_removal_mode 0)
		)
		(polygon
			(pts
				(arc
					(start 177.222404 -261.916672)
					(mid 176.569624 -261.916672)
					(end 177.222404 -261.916672)
				)
			)
		)
	)
	(zone
		(layers "B.Cu" "In4.Cu" "In6.Cu" "In11.Cu" "In13.Cu" "In15.Cu")
		(hatch none 0.5)
		(connect_pads
			(clearance 0)
		)
		(min_thickness 0.25)
		(keepout
			(tracks not_allowed)
			(vias allowed)
			(pads allowed)
			(copperpour not_allowed)
			(footprints allowed)
		)
		(placement
			(enabled no)
			(sheetname "")
		)
		(fill yes
			(thermal_gap 0.5)
			(thermal_bridge_width 0.5)
			(island_removal_mode 0)
		)
		(polygon
			(pts
				(arc
					(start 47.290736 -209.216752)
					(mid 46.637956 -209.216752)
					(end 47.290736 -209.216752)
				)
			)
		)
	)
	(zone
		(layers "B.Cu" "In4.Cu" "In6.Cu" "In11.Cu" "In13.Cu" "In15.Cu")
		(hatch none 0.5)
		(connect_pads
			(clearance 0)
		)
		(min_thickness 0.25)
		(keepout
			(tracks not_allowed)
			(vias allowed)
			(pads allowed)
			(copperpour not_allowed)
			(footprints allowed)
		)
		(placement
			(enabled no)
			(sheetname "")
		)
		(fill yes
			(thermal_gap 0.5)
			(thermal_bridge_width 0.5)
			(island_removal_mode 0)
		)
		(polygon
			(pts
				(arc
					(start 389.30072 -407.00452)
					(mid 388.59714 -407.00452)
					(end 389.30072 -407.00452)
				)
			)
		)
	)
	(zone
		(layers "B.Cu" "In4.Cu" "In6.Cu" "In11.Cu" "In13.Cu" "In15.Cu")
		(hatch none 0.5)
		(connect_pads
			(clearance 0)
		)
		(min_thickness 0.25)
		(keepout
			(tracks not_allowed)
			(vias allowed)
			(pads allowed)
			(copperpour not_allowed)
			(footprints allowed)
		)
		(placement
			(enabled no)
			(sheetname "")
		)
		(fill yes
			(thermal_gap 0.5)
			(thermal_bridge_width 0.5)
			(island_removal_mode 0)
		)
		(polygon
			(pts
				(arc
					(start 295.230804 -275.516594)
					(mid 294.578024 -275.516594)
					(end 295.230804 -275.516594)
				)
			)
		)
	)
	(zone
		(layers "B.Cu" "In4.Cu" "In6.Cu" "In11.Cu" "In13.Cu" "In15.Cu")
		(hatch none 0.5)
		(connect_pads
			(clearance 0)
		)
		(min_thickness 0.25)
		(keepout
			(tracks not_allowed)
			(vias allowed)
			(pads allowed)
			(copperpour not_allowed)
			(footprints allowed)
		)
		(placement
			(enabled no)
			(sheetname "")
		)
		(fill yes
			(thermal_gap 0.5)
			(thermal_bridge_width 0.5)
			(island_removal_mode 0)
		)
		(polygon
			(pts
				(arc
					(start 27.925268 -17.61236)
					(mid 27.221688 -17.61236)
					(end 27.925268 -17.61236)
				)
			)
		)
	)
	(zone
		(layers "B.Cu" "In4.Cu" "In6.Cu" "In11.Cu" "In13.Cu" "In15.Cu")
		(hatch none 0.5)
		(connect_pads
			(clearance 0)
		)
		(min_thickness 0.25)
		(keepout
			(tracks not_allowed)
			(vias allowed)
			(pads allowed)
			(copperpour not_allowed)
			(footprints allowed)
		)
		(placement
			(enabled no)
			(sheetname "")
		)
		(fill yes
			(thermal_gap 0.5)
			(thermal_bridge_width 0.5)
			(island_removal_mode 0)
		)
		(polygon
			(pts
				(arc
					(start 165.601904 -407.00452)
					(mid 164.898324 -407.00452)
					(end 165.601904 -407.00452)
				)
			)
		)
	)
	(zone
		(layers "B.Cu" "In4.Cu" "In6.Cu" "In11.Cu" "In13.Cu" "In15.Cu")
		(hatch none 0.5)
		(connect_pads
			(clearance 0)
		)
		(min_thickness 0.25)
		(keepout
			(tracks not_allowed)
			(vias allowed)
			(pads allowed)
			(copperpour not_allowed)
			(footprints allowed)
		)
		(placement
			(enabled no)
			(sheetname "")
		)
		(fill yes
			(thermal_gap 0.5)
			(thermal_bridge_width 0.5)
			(island_removal_mode 0)
		)
		(polygon
			(pts
				(arc
					(start 90.821002 -233.34218)
					(mid 90.168222 -233.34218)
					(end 90.821002 -233.34218)
				)
			)
		)
	)
	(zone
		(layers "B.Cu" "In4.Cu" "In6.Cu" "In11.Cu" "In13.Cu" "In15.Cu")
		(hatch none 0.5)
		(connect_pads
			(clearance 0)
		)
		(min_thickness 0.25)
		(keepout
			(tracks not_allowed)
			(vias allowed)
			(pads allowed)
			(copperpour not_allowed)
			(footprints allowed)
		)
		(placement
			(enabled no)
			(sheetname "")
		)
		(fill yes
			(thermal_gap 0.5)
			(thermal_bridge_width 0.5)
			(island_removal_mode 0)
		)
		(polygon
			(pts
				(arc
					(start 381.632206 -263.686544)
					(mid 380.979426 -263.686544)
					(end 381.632206 -263.686544)
				)
			)
		)
	)
	(zone
		(layers "B.Cu" "In4.Cu" "In6.Cu" "In11.Cu" "In13.Cu" "In15.Cu")
		(hatch none 0.5)
		(connect_pads
			(clearance 0)
		)
		(min_thickness 0.25)
		(keepout
			(tracks not_allowed)
			(vias allowed)
			(pads allowed)
			(copperpour not_allowed)
			(footprints allowed)
		)
		(placement
			(enabled no)
			(sheetname "")
		)
		(fill yes
			(thermal_gap 0.5)
			(thermal_bridge_width 0.5)
			(island_removal_mode 0)
		)
		(polygon
			(pts
				(arc
					(start 314.418472 -304.416714)
					(mid 313.765692 -304.416714)
					(end 314.418472 -304.416714)
				)
			)
		)
	)
	(zone
		(layers "B.Cu" "In4.Cu" "In6.Cu" "In11.Cu" "In13.Cu" "In15.Cu")
		(hatch none 0.5)
		(connect_pads
			(clearance 0)
		)
		(min_thickness 0.25)
		(keepout
			(tracks not_allowed)
			(vias allowed)
			(pads allowed)
			(copperpour not_allowed)
			(footprints allowed)
		)
		(placement
			(enabled no)
			(sheetname "")
		)
		(fill yes
			(thermal_gap 0.5)
			(thermal_bridge_width 0.5)
			(island_removal_mode 0)
		)
		(polygon
			(pts
				(arc
					(start 66.478404 -300.166786)
					(mid 65.825624 -300.166786)
					(end 66.478404 -300.166786)
				)
			)
		)
	)
	(zone
		(layers "B.Cu" "In4.Cu" "In6.Cu" "In11.Cu" "In13.Cu" "In15.Cu")
		(hatch none 0.5)
		(connect_pads
			(clearance 0)
		)
		(min_thickness 0.25)
		(keepout
			(tracks not_allowed)
			(vias allowed)
			(pads allowed)
			(copperpour not_allowed)
			(footprints allowed)
		)
		(placement
			(enabled no)
			(sheetname "")
		)
		(fill yes
			(thermal_gap 0.5)
			(thermal_bridge_width 0.5)
			(island_removal_mode 0)
		)
		(polygon
			(pts
				(arc
					(start 348.269052 -285.661354)
					(mid 347.616272 -285.661354)
					(end 348.269052 -285.661354)
				)
			)
		)
	)
	(zone
		(layers "B.Cu" "In4.Cu" "In6.Cu" "In11.Cu" "In13.Cu" "In15.Cu")
		(hatch none 0.5)
		(connect_pads
			(clearance 0)
		)
		(min_thickness 0.25)
		(keepout
			(tracks not_allowed)
			(vias allowed)
			(pads allowed)
			(copperpour not_allowed)
			(footprints allowed)
		)
		(placement
			(enabled no)
			(sheetname "")
		)
		(fill yes
			(thermal_gap 0.5)
			(thermal_bridge_width 0.5)
			(island_removal_mode 0)
		)
		(polygon
			(pts
				(arc
					(start 51.416204 -311.216802)
					(mid 50.763424 -311.216802)
					(end 51.416204 -311.216802)
				)
			)
		)
	)
	(zone
		(layers "B.Cu" "In4.Cu" "In6.Cu" "In11.Cu" "In13.Cu" "In15.Cu")
		(hatch none 0.5)
		(connect_pads
			(clearance 0)
		)
		(min_thickness 0.25)
		(keepout
			(tracks not_allowed)
			(vias allowed)
			(pads allowed)
			(copperpour not_allowed)
			(footprints allowed)
		)
		(placement
			(enabled no)
			(sheetname "")
		)
		(fill yes
			(thermal_gap 0.5)
			(thermal_bridge_width 0.5)
			(island_removal_mode 0)
		)
		(polygon
			(pts
				(arc
					(start 344.509852 -285.661354)
					(mid 343.857072 -285.661354)
					(end 344.509852 -285.661354)
				)
			)
		)
	)
	(zone
		(layers "B.Cu" "In4.Cu" "In6.Cu" "In11.Cu" "In13.Cu" "In15.Cu")
		(hatch none 0.5)
		(connect_pads
			(clearance 0)
		)
		(min_thickness 0.25)
		(keepout
			(tracks not_allowed)
			(vias allowed)
			(pads allowed)
			(copperpour not_allowed)
			(footprints allowed)
		)
		(placement
			(enabled no)
			(sheetname "")
		)
		(fill yes
			(thermal_gap 0.5)
			(thermal_bridge_width 0.5)
			(island_removal_mode 0)
		)
		(polygon
			(pts
				(arc
					(start 338.871052 -269.38351)
					(mid 338.218272 -269.38351)
					(end 338.871052 -269.38351)
				)
			)
		)
	)
	(zone
		(layers "B.Cu" "In4.Cu" "In6.Cu" "In11.Cu" "In13.Cu" "In15.Cu")
		(hatch none 0.5)
		(connect_pads
			(clearance 0)
		)
		(min_thickness 0.25)
		(keepout
			(tracks not_allowed)
			(vias allowed)
			(pads allowed)
			(copperpour not_allowed)
			(footprints allowed)
		)
		(placement
			(enabled no)
			(sheetname "")
		)
		(fill yes
			(thermal_gap 0.5)
			(thermal_bridge_width 0.5)
			(island_removal_mode 0)
		)
		(polygon
			(pts
				(arc
					(start 425.162472 -209.216752)
					(mid 424.509692 -209.216752)
					(end 425.162472 -209.216752)
				)
			)
		)
	)
	(zone
		(layers "B.Cu" "In4.Cu" "In6.Cu" "In11.Cu" "In13.Cu" "In15.Cu")
		(hatch none 0.5)
		(connect_pads
			(clearance 0)
		)
		(min_thickness 0.25)
		(keepout
			(tracks not_allowed)
			(vias allowed)
			(pads allowed)
			(copperpour not_allowed)
			(footprints allowed)
		)
		(placement
			(enabled no)
			(sheetname "")
		)
		(fill yes
			(thermal_gap 0.5)
			(thermal_bridge_width 0.5)
			(island_removal_mode 0)
		)
		(polygon
			(pts
				(arc
					(start 293.30777 -162.100768)
					(mid 292.60419 -162.100768)
					(end 293.30777 -162.100768)
				)
			)
		)
	)
	(zone
		(layers "B.Cu" "In4.Cu" "In6.Cu" "In11.Cu" "In13.Cu" "In15.Cu")
		(hatch none 0.5)
		(connect_pads
			(clearance 0)
		)
		(min_thickness 0.25)
		(keepout
			(tracks not_allowed)
			(vias allowed)
			(pads allowed)
			(copperpour not_allowed)
			(footprints allowed)
		)
		(placement
			(enabled no)
			(sheetname "")
		)
		(fill yes
			(thermal_gap 0.5)
			(thermal_bridge_width 0.5)
			(island_removal_mode 0)
		)
		(polygon
			(pts
				(arc
					(start 407.68016 -407.00452)
					(mid 406.97658 -407.00452)
					(end 407.68016 -407.00452)
				)
			)
		)
	)
	(zone
		(layers "B.Cu" "In4.Cu" "In6.Cu" "In11.Cu" "In13.Cu" "In15.Cu")
		(hatch none 0.5)
		(connect_pads
			(clearance 0)
		)
		(min_thickness 0.25)
		(keepout
			(tracks not_allowed)
			(vias allowed)
			(pads allowed)
			(copperpour not_allowed)
			(footprints allowed)
		)
		(placement
			(enabled no)
			(sheetname "")
		)
		(fill yes
			(thermal_gap 0.5)
			(thermal_bridge_width 0.5)
			(island_removal_mode 0)
		)
		(polygon
			(pts
				(arc
					(start 162.109404 -229.616762)
					(mid 161.456624 -229.616762)
					(end 162.109404 -229.616762)
				)
			)
		)
	)
	(zone
		(layers "B.Cu" "In4.Cu" "In6.Cu" "In11.Cu" "In13.Cu" "In15.Cu")
		(hatch none 0.5)
		(connect_pads
			(clearance 0)
		)
		(min_thickness 0.25)
		(keepout
			(tracks not_allowed)
			(vias allowed)
			(pads allowed)
			(copperpour not_allowed)
			(footprints allowed)
		)
		(placement
			(enabled no)
			(sheetname "")
		)
		(fill yes
			(thermal_gap 0.5)
			(thermal_bridge_width 0.5)
			(island_removal_mode 0)
		)
		(polygon
			(pts
				(arc
					(start 356.61727 -225.203258)
					(mid 355.96449 -225.203258)
					(end 356.61727 -225.203258)
				)
			)
		)
	)
	(zone
		(layers "B.Cu" "In4.Cu" "In6.Cu" "In11.Cu" "In13.Cu" "In15.Cu")
		(hatch none 0.5)
		(connect_pads
			(clearance 0)
		)
		(min_thickness 0.25)
		(keepout
			(tracks not_allowed)
			(vias allowed)
			(pads allowed)
			(copperpour not_allowed)
			(footprints allowed)
		)
		(placement
			(enabled no)
			(sheetname "")
		)
		(fill yes
			(thermal_gap 0.5)
			(thermal_bridge_width 0.5)
			(island_removal_mode 0)
		)
		(polygon
			(pts
				(arc
					(start 173.122336 -235.566712)
					(mid 172.469556 -235.566712)
					(end 173.122336 -235.566712)
				)
			)
		)
	)
	(zone
		(layers "B.Cu" "In4.Cu" "In6.Cu" "In11.Cu" "In13.Cu" "In15.Cu")
		(hatch none 0.5)
		(connect_pads
			(clearance 0)
		)
		(min_thickness 0.25)
		(keepout
			(tracks not_allowed)
			(vias allowed)
			(pads allowed)
			(copperpour not_allowed)
			(footprints allowed)
		)
		(placement
			(enabled no)
			(sheetname "")
		)
		(fill yes
			(thermal_gap 0.5)
			(thermal_bridge_width 0.5)
			(island_removal_mode 0)
		)
		(polygon
			(pts
				(arc
					(start 295.230804 -222.816674)
					(mid 294.578024 -222.816674)
					(end 295.230804 -222.816674)
				)
			)
		)
	)
	(zone
		(layers "B.Cu" "In4.Cu" "In6.Cu" "In11.Cu" "In13.Cu" "In15.Cu")
		(hatch none 0.5)
		(connect_pads
			(clearance 0)
		)
		(min_thickness 0.25)
		(keepout
			(tracks not_allowed)
			(vias allowed)
			(pads allowed)
			(copperpour not_allowed)
			(footprints allowed)
		)
		(placement
			(enabled no)
			(sheetname "")
		)
		(fill yes
			(thermal_gap 0.5)
			(thermal_bridge_width 0.5)
			(island_removal_mode 0)
		)
		(polygon
			(pts
				(arc
					(start 295.230804 -310.366664)
					(mid 294.578024 -310.366664)
					(end 295.230804 -310.366664)
				)
			)
		)
	)
	(zone
		(layers "B.Cu" "In4.Cu" "In6.Cu" "In11.Cu" "In13.Cu" "In15.Cu")
		(hatch none 0.5)
		(connect_pads
			(clearance 0)
		)
		(min_thickness 0.25)
		(keepout
			(tracks not_allowed)
			(vias allowed)
			(pads allowed)
			(copperpour not_allowed)
			(footprints allowed)
		)
		(placement
			(enabled no)
			(sheetname "")
		)
		(fill yes
			(thermal_gap 0.5)
			(thermal_bridge_width 0.5)
			(island_removal_mode 0)
		)
		(polygon
			(pts
				(arc
					(start 121.852944 -407.00452)
					(mid 121.149364 -407.00452)
					(end 121.852944 -407.00452)
				)
			)
		)
	)
	(zone
		(layers "B.Cu" "In4.Cu" "In6.Cu" "In11.Cu" "In13.Cu" "In15.Cu")
		(hatch none 0.5)
		(connect_pads
			(clearance 0)
		)
		(min_thickness 0.25)
		(keepout
			(tracks not_allowed)
			(vias allowed)
			(pads allowed)
			(copperpour not_allowed)
			(footprints allowed)
		)
		(placement
			(enabled no)
			(sheetname "")
		)
		(fill yes
			(thermal_gap 0.5)
			(thermal_bridge_width 0.5)
			(island_removal_mode 0)
		)
		(polygon
			(pts
				(arc
					(start 90.930984 -259.616956)
					(mid 90.278204 -259.616956)
					(end 90.930984 -259.616956)
				)
			)
		)
	)
	(zone
		(layers "B.Cu" "In4.Cu" "In6.Cu" "In11.Cu" "In13.Cu" "In15.Cu")
		(hatch none 0.5)
		(connect_pads
			(clearance 0)
		)
		(min_thickness 0.25)
		(keepout
			(tracks not_allowed)
			(vias allowed)
			(pads allowed)
			(copperpour not_allowed)
			(footprints allowed)
		)
		(placement
			(enabled no)
			(sheetname "")
		)
		(fill yes
			(thermal_gap 0.5)
			(thermal_bridge_width 0.5)
			(island_removal_mode 0)
		)
		(polygon
			(pts
				(arc
					(start 410.049472 -298.466764)
					(mid 409.396692 -298.466764)
					(end 410.049472 -298.466764)
				)
			)
		)
	)
	(zone
		(layers "B.Cu" "In4.Cu" "In6.Cu" "In11.Cu" "In13.Cu" "In15.Cu")
		(hatch none 0.5)
		(connect_pads
			(clearance 0)
		)
		(min_thickness 0.25)
		(keepout
			(tracks not_allowed)
			(vias allowed)
			(pads allowed)
			(copperpour not_allowed)
			(footprints allowed)
		)
		(placement
			(enabled no)
			(sheetname "")
		)
		(fill yes
			(thermal_gap 0.5)
			(thermal_bridge_width 0.5)
			(island_removal_mode 0)
		)
		(polygon
			(pts
				(arc
					(start 97.979738 -286.475424)
					(mid 97.326958 -286.475424)
					(end 97.979738 -286.475424)
				)
			)
		)
	)
	(zone
		(layers "B.Cu" "In4.Cu" "In6.Cu" "In11.Cu" "In13.Cu" "In15.Cu")
		(hatch none 0.5)
		(connect_pads
			(clearance 0)
		)
		(min_thickness 0.25)
		(keepout
			(tracks not_allowed)
			(vias allowed)
			(pads allowed)
			(copperpour not_allowed)
			(footprints allowed)
		)
		(placement
			(enabled no)
			(sheetname "")
		)
		(fill yes
			(thermal_gap 0.5)
			(thermal_bridge_width 0.5)
			(island_removal_mode 0)
		)
		(polygon
			(pts
				(arc
					(start 295.230804 -293.366698)
					(mid 294.578024 -293.366698)
					(end 295.230804 -293.366698)
				)
			)
		)
	)
	(zone
		(layers "B.Cu" "In4.Cu" "In6.Cu" "In11.Cu" "In13.Cu" "In15.Cu")
		(hatch none 0.5)
		(connect_pads
			(clearance 0)
		)
		(min_thickness 0.25)
		(keepout
			(tracks not_allowed)
			(vias allowed)
			(pads allowed)
			(copperpour not_allowed)
			(footprints allowed)
		)
		(placement
			(enabled no)
			(sheetname "")
		)
		(fill yes
			(thermal_gap 0.5)
			(thermal_bridge_width 0.5)
			(island_removal_mode 0)
		)
		(polygon
			(pts
				(arc
					(start 352.028252 -285.661354)
					(mid 351.375472 -285.661354)
					(end 352.028252 -285.661354)
				)
			)
		)
	)
	(zone
		(layers "B.Cu" "In4.Cu" "In6.Cu" "In11.Cu" "In13.Cu" "In15.Cu")
		(hatch none 0.5)
		(connect_pads
			(clearance 0)
		)
		(min_thickness 0.25)
		(keepout
			(tracks not_allowed)
			(vias allowed)
			(pads allowed)
			(copperpour not_allowed)
			(footprints allowed)
		)
		(placement
			(enabled no)
			(sheetname "")
		)
		(fill yes
			(thermal_gap 0.5)
			(thermal_bridge_width 0.5)
			(island_removal_mode 0)
		)
		(polygon
			(pts
				(arc
					(start 47.290736 -295.916604)
					(mid 46.637956 -295.916604)
					(end 47.290736 -295.916604)
				)
			)
		)
	)
	(zone
		(layers "B.Cu" "In4.Cu" "In6.Cu" "In11.Cu" "In13.Cu" "In15.Cu")
		(hatch none 0.5)
		(connect_pads
			(clearance 0)
		)
		(min_thickness 0.25)
		(keepout
			(tracks not_allowed)
			(vias allowed)
			(pads allowed)
			(copperpour not_allowed)
			(footprints allowed)
		)
		(placement
			(enabled no)
			(sheetname "")
		)
		(fill yes
			(thermal_gap 0.5)
			(thermal_bridge_width 0.5)
			(island_removal_mode 0)
		)
		(polygon
			(pts
				(arc
					(start 383.511806 -271.825212)
					(mid 382.859026 -271.825212)
					(end 383.511806 -271.825212)
				)
			)
		)
	)
	(zone
		(layers "B.Cu" "In4.Cu" "In6.Cu" "In11.Cu" "In13.Cu" "In15.Cu")
		(hatch none 0.5)
		(connect_pads
			(clearance 0)
		)
		(min_thickness 0.25)
		(keepout
			(tracks not_allowed)
			(vias allowed)
			(pads allowed)
			(copperpour not_allowed)
			(footprints allowed)
		)
		(placement
			(enabled no)
			(sheetname "")
		)
		(fill yes
			(thermal_gap 0.5)
			(thermal_bridge_width 0.5)
			(island_removal_mode 0)
		)
		(polygon
			(pts
				(arc
					(start 377.04776 -407.00452)
					(mid 376.34418 -407.00452)
					(end 377.04776 -407.00452)
				)
			)
		)
	)
	(zone
		(layers "B.Cu" "In4.Cu" "In6.Cu" "In11.Cu" "In13.Cu" "In15.Cu")
		(hatch none 0.5)
		(connect_pads
			(clearance 0)
		)
		(min_thickness 0.25)
		(keepout
			(tracks not_allowed)
			(vias allowed)
			(pads allowed)
			(copperpour not_allowed)
			(footprints allowed)
		)
		(placement
			(enabled no)
			(sheetname "")
		)
		(fill yes
			(thermal_gap 0.5)
			(thermal_bridge_width 0.5)
			(island_removal_mode 0)
		)
		(polygon
			(pts
				(arc
					(start 89.411556 -234.15625)
					(mid 88.758776 -234.15625)
					(end 89.411556 -234.15625)
				)
			)
		)
	)
	(zone
		(layers "B.Cu" "In4.Cu" "In6.Cu" "In11.Cu" "In13.Cu" "In15.Cu")
		(hatch none 0.5)
		(connect_pads
			(clearance 0)
		)
		(min_thickness 0.25)
		(keepout
			(tracks not_allowed)
			(vias allowed)
			(pads allowed)
			(copperpour not_allowed)
			(footprints allowed)
		)
		(placement
			(enabled no)
			(sheetname "")
		)
		(fill yes
			(thermal_gap 0.5)
			(thermal_bridge_width 0.5)
			(island_removal_mode 0)
		)
		(polygon
			(pts
				(arc
					(start 338.291424 -242.294918)
					(mid 337.638644 -242.294918)
					(end 338.291424 -242.294918)
				)
			)
		)
	)
	(zone
		(layers "B.Cu" "In4.Cu" "In6.Cu" "In11.Cu" "In13.Cu" "In15.Cu")
		(hatch none 0.5)
		(connect_pads
			(clearance 0)
		)
		(min_thickness 0.25)
		(keepout
			(tracks not_allowed)
			(vias allowed)
			(pads allowed)
			(copperpour not_allowed)
			(footprints allowed)
		)
		(placement
			(enabled no)
			(sheetname "")
		)
		(fill yes
			(thermal_gap 0.5)
			(thermal_bridge_width 0.5)
			(island_removal_mode 0)
		)
		(polygon
			(pts
				(arc
					(start 295.230804 -291.666676)
					(mid 294.578024 -291.666676)
					(end 295.230804 -291.666676)
				)
			)
		)
	)
	(zone
		(layers "B.Cu" "In4.Cu" "In6.Cu" "In11.Cu" "In13.Cu" "In15.Cu")
		(hatch none 0.5)
		(connect_pads
			(clearance 0)
		)
		(min_thickness 0.25)
		(keepout
			(tracks not_allowed)
			(vias allowed)
			(pads allowed)
			(copperpour not_allowed)
			(footprints allowed)
		)
		(placement
			(enabled no)
			(sheetname "")
		)
		(fill yes
			(thermal_gap 0.5)
			(thermal_bridge_width 0.5)
			(island_removal_mode 0)
		)
		(polygon
			(pts
				(arc
					(start 425.086272 -263.616694)
					(mid 424.433492 -263.616694)
					(end 425.086272 -263.616694)
				)
			)
		)
	)
	(zone
		(layers "B.Cu" "In4.Cu" "In6.Cu" "In11.Cu" "In13.Cu" "In15.Cu")
		(hatch none 0.5)
		(connect_pads
			(clearance 0)
		)
		(min_thickness 0.25)
		(keepout
			(tracks not_allowed)
			(vias allowed)
			(pads allowed)
			(copperpour not_allowed)
			(footprints allowed)
		)
		(placement
			(enabled no)
			(sheetname "")
		)
		(fill yes
			(thermal_gap 0.5)
			(thermal_bridge_width 0.5)
			(island_removal_mode 0)
		)
		(polygon
			(pts
				(arc
					(start 369.884452 -285.661354)
					(mid 369.231672 -285.661354)
					(end 369.884452 -285.661354)
				)
			)
		)
	)
	(zone
		(layers "B.Cu" "In4.Cu" "In6.Cu" "In11.Cu" "In13.Cu" "In15.Cu")
		(hatch none 0.5)
		(connect_pads
			(clearance 0)
		)
		(min_thickness 0.25)
		(keepout
			(tracks not_allowed)
			(vias allowed)
			(pads allowed)
			(copperpour not_allowed)
			(footprints allowed)
		)
		(placement
			(enabled no)
			(sheetname "")
		)
		(fill yes
			(thermal_gap 0.5)
			(thermal_bridge_width 0.5)
			(island_removal_mode 0)
		)
		(polygon
			(pts
				(arc
					(start 310.318404 -303.566576)
					(mid 309.665624 -303.566576)
					(end 310.318404 -303.566576)
				)
			)
		)
	)
	(zone
		(layers "B.Cu" "In4.Cu" "In6.Cu" "In11.Cu" "In13.Cu" "In15.Cu")
		(hatch none 0.5)
		(connect_pads
			(clearance 0)
		)
		(min_thickness 0.25)
		(keepout
			(tracks not_allowed)
			(vias allowed)
			(pads allowed)
			(copperpour not_allowed)
			(footprints allowed)
		)
		(placement
			(enabled no)
			(sheetname "")
		)
		(fill yes
			(thermal_gap 0.5)
			(thermal_bridge_width 0.5)
			(island_removal_mode 0)
		)
		(polygon
			(pts
				(arc
					(start 420.986204 -267.866622)
					(mid 420.333424 -267.866622)
					(end 420.986204 -267.866622)
				)
			)
		)
	)
	(zone
		(layers "B.Cu" "In4.Cu" "In6.Cu" "In11.Cu" "In13.Cu" "In15.Cu")
		(hatch none 0.5)
		(connect_pads
			(clearance 0)
		)
		(min_thickness 0.25)
		(keepout
			(tracks not_allowed)
			(vias allowed)
			(pads allowed)
			(copperpour not_allowed)
			(footprints allowed)
		)
		(placement
			(enabled no)
			(sheetname "")
		)
		(fill yes
			(thermal_gap 0.5)
			(thermal_bridge_width 0.5)
			(island_removal_mode 0)
		)
		(polygon
			(pts
				(arc
					(start 301.78883 -163.083748)
					(mid 301.08525 -163.083748)
					(end 301.78883 -163.083748)
				)
			)
		)
	)
	(zone
		(layers "B.Cu" "In4.Cu" "In6.Cu" "In11.Cu" "In13.Cu" "In15.Cu")
		(hatch none 0.5)
		(connect_pads
			(clearance 0)
		)
		(min_thickness 0.25)
		(keepout
			(tracks not_allowed)
			(vias allowed)
			(pads allowed)
			(copperpour not_allowed)
			(footprints allowed)
		)
		(placement
			(enabled no)
			(sheetname "")
		)
		(fill yes
			(thermal_gap 0.5)
			(thermal_bridge_width 0.5)
			(island_removal_mode 0)
		)
		(polygon
			(pts
				(arc
					(start 338.871052 -264.50036)
					(mid 338.218272 -264.50036)
					(end 338.871052 -264.50036)
				)
			)
		)
	)
	(zone
		(layers "B.Cu" "In4.Cu" "In6.Cu" "In11.Cu" "In13.Cu" "In15.Cu")
		(hatch none 0.5)
		(connect_pads
			(clearance 0)
		)
		(min_thickness 0.25)
		(keepout
			(tracks not_allowed)
			(vias allowed)
			(pads allowed)
			(copperpour not_allowed)
			(footprints allowed)
		)
		(placement
			(enabled no)
			(sheetname "")
		)
		(fill yes
			(thermal_gap 0.5)
			(thermal_bridge_width 0.5)
			(island_removal_mode 0)
		)
		(polygon
			(pts
				(arc
					(start 173.122336 -239.81664)
					(mid 172.469556 -239.81664)
					(end 173.122336 -239.81664)
				)
			)
		)
	)
	(zone
		(layers "B.Cu" "In4.Cu" "In6.Cu" "In11.Cu" "In13.Cu" "In15.Cu")
		(hatch none 0.5)
		(connect_pads
			(clearance 0)
		)
		(min_thickness 0.25)
		(keepout
			(tracks not_allowed)
			(vias allowed)
			(pads allowed)
			(copperpour not_allowed)
			(footprints allowed)
		)
		(placement
			(enabled no)
			(sheetname "")
		)
		(fill yes
			(thermal_gap 0.5)
			(thermal_bridge_width 0.5)
			(island_removal_mode 0)
		)
		(polygon
			(pts
				(arc
					(start 51.416204 -289.11677)
					(mid 50.763424 -289.11677)
					(end 51.416204 -289.11677)
				)
			)
		)
	)
	(zone
		(layers "B.Cu" "In4.Cu" "In6.Cu" "In11.Cu" "In13.Cu" "In15.Cu")
		(hatch none 0.5)
		(connect_pads
			(clearance 0)
		)
		(min_thickness 0.25)
		(keepout
			(tracks not_allowed)
			(vias allowed)
			(pads allowed)
			(copperpour not_allowed)
			(footprints allowed)
		)
		(placement
			(enabled no)
			(sheetname "")
		)
		(fill yes
			(thermal_gap 0.5)
			(thermal_bridge_width 0.5)
			(island_removal_mode 0)
		)
		(polygon
			(pts
				(arc
					(start 299.356272 -289.11677)
					(mid 298.703492 -289.11677)
					(end 299.356272 -289.11677)
				)
			)
		)
	)
	(zone
		(layers "B.Cu" "In4.Cu" "In6.Cu" "In11.Cu" "In13.Cu" "In15.Cu")
		(hatch none 0.5)
		(connect_pads
			(clearance 0)
		)
		(min_thickness 0.25)
		(keepout
			(tracks not_allowed)
			(vias allowed)
			(pads allowed)
			(copperpour not_allowed)
			(footprints allowed)
		)
		(placement
			(enabled no)
			(sheetname "")
		)
		(fill yes
			(thermal_gap 0.5)
			(thermal_bridge_width 0.5)
			(island_removal_mode 0)
		)
		(polygon
			(pts
				(arc
					(start 96.569784 -285.661354)
					(mid 95.917004 -285.661354)
					(end 96.569784 -285.661354)
				)
			)
		)
	)
	(zone
		(layers "B.Cu" "In4.Cu" "In6.Cu" "In11.Cu" "In13.Cu" "In15.Cu")
		(hatch none 0.5)
		(connect_pads
			(clearance 0)
		)
		(min_thickness 0.25)
		(keepout
			(tracks not_allowed)
			(vias allowed)
			(pads allowed)
			(copperpour not_allowed)
			(footprints allowed)
		)
		(placement
			(enabled no)
			(sheetname "")
		)
		(fill yes
			(thermal_gap 0.5)
			(thermal_bridge_width 0.5)
			(island_removal_mode 0)
		)
		(polygon
			(pts
				(arc
					(start 47.290736 -310.366664)
					(mid 46.637956 -310.366664)
					(end 47.290736 -310.366664)
				)
			)
		)
	)
	(zone
		(layers "B.Cu" "In4.Cu" "In6.Cu" "In11.Cu" "In13.Cu" "In15.Cu")
		(hatch none 0.5)
		(connect_pads
			(clearance 0)
		)
		(min_thickness 0.25)
		(keepout
			(tracks not_allowed)
			(vias allowed)
			(pads allowed)
			(copperpour not_allowed)
			(footprints allowed)
		)
		(placement
			(enabled no)
			(sheetname "")
		)
		(fill yes
			(thermal_gap 0.5)
			(thermal_bridge_width 0.5)
			(island_removal_mode 0)
		)
		(polygon
			(pts
				(arc
					(start 90.351356 -227.64496)
					(mid 89.698576 -227.64496)
					(end 90.351356 -227.64496)
				)
			)
		)
	)
	(zone
		(layers "B.Cu" "In4.Cu" "In6.Cu" "In11.Cu" "In13.Cu" "In15.Cu")
		(hatch none 0.5)
		(connect_pads
			(clearance 0)
		)
		(min_thickness 0.25)
		(keepout
			(tracks not_allowed)
			(vias allowed)
			(pads allowed)
			(copperpour not_allowed)
			(footprints allowed)
		)
		(placement
			(enabled no)
			(sheetname "")
		)
		(fill yes
			(thermal_gap 0.5)
			(thermal_bridge_width 0.5)
			(island_removal_mode 0)
		)
		(polygon
			(pts
				(arc
					(start 132.752338 -255.547622)
					(mid 132.099558 -255.547622)
					(end 132.752338 -255.547622)
				)
			)
		)
	)
	(zone
		(layers "B.Cu" "In4.Cu" "In6.Cu" "In11.Cu" "In13.Cu" "In15.Cu")
		(hatch none 0.5)
		(connect_pads
			(clearance 0)
		)
		(min_thickness 0.25)
		(keepout
			(tracks not_allowed)
			(vias allowed)
			(pads allowed)
			(copperpour not_allowed)
			(footprints allowed)
		)
		(placement
			(enabled no)
			(sheetname "")
		)
		(fill yes
			(thermal_gap 0.5)
			(thermal_bridge_width 0.5)
			(island_removal_mode 0)
		)
		(polygon
			(pts
				(arc
					(start 136.401556 -222.761556)
					(mid 135.748776 -222.761556)
					(end 136.401556 -222.761556)
				)
			)
		)
	)
	(zone
		(layers "B.Cu" "In4.Cu" "In6.Cu" "In11.Cu" "In13.Cu" "In15.Cu")
		(hatch none 0.5)
		(connect_pads
			(clearance 0)
		)
		(min_thickness 0.25)
		(keepout
			(tracks not_allowed)
			(vias allowed)
			(pads allowed)
			(copperpour not_allowed)
			(footprints allowed)
		)
		(placement
			(enabled no)
			(sheetname "")
		)
		(fill yes
			(thermal_gap 0.5)
			(thermal_bridge_width 0.5)
			(island_removal_mode 0)
		)
		(polygon
			(pts
				(arc
					(start 382.101852 -266.128246)
					(mid 381.449072 -266.128246)
					(end 382.101852 -266.128246)
				)
			)
		)
	)
	(zone
		(layers "B.Cu" "In4.Cu" "In6.Cu" "In11.Cu" "In13.Cu" "In15.Cu")
		(hatch none 0.5)
		(connect_pads
			(clearance 0)
		)
		(min_thickness 0.25)
		(keepout
			(tracks not_allowed)
			(vias allowed)
			(pads allowed)
			(copperpour not_allowed)
			(footprints allowed)
		)
		(placement
			(enabled no)
			(sheetname "")
		)
		(fill yes
			(thermal_gap 0.5)
			(thermal_bridge_width 0.5)
			(island_removal_mode 0)
		)
		(polygon
			(pts
				(arc
					(start 419.93312 -407.00452)
					(mid 419.22954 -407.00452)
					(end 419.93312 -407.00452)
				)
			)
		)
	)
	(zone
		(layers "B.Cu" "In4.Cu" "In6.Cu" "In11.Cu" "In13.Cu" "In15.Cu")
		(hatch none 0.5)
		(connect_pads
			(clearance 0)
		)
		(min_thickness 0.25)
		(keepout
			(tracks not_allowed)
			(vias allowed)
			(pads allowed)
			(copperpour not_allowed)
			(footprints allowed)
		)
		(placement
			(enabled no)
			(sheetname "")
		)
		(fill yes
			(thermal_gap 0.5)
			(thermal_bridge_width 0.5)
			(island_removal_mode 0)
		)
		(polygon
			(pts
				(arc
					(start 337.461352 -268.569694)
					(mid 336.808572 -268.569694)
					(end 337.461352 -268.569694)
				)
			)
		)
	)
	(zone
		(layers "B.Cu" "In4.Cu" "In6.Cu" "In11.Cu" "In13.Cu" "In15.Cu")
		(hatch none 0.5)
		(connect_pads
			(clearance 0)
		)
		(min_thickness 0.25)
		(keepout
			(tracks not_allowed)
			(vias allowed)
			(pads allowed)
			(copperpour not_allowed)
			(footprints allowed)
		)
		(placement
			(enabled no)
			(sheetname "")
		)
		(fill yes
			(thermal_gap 0.5)
			(thermal_bridge_width 0.5)
			(island_removal_mode 0)
		)
		(polygon
			(pts
				(arc
					(start 381.632206 -286.475424)
					(mid 380.979426 -286.475424)
					(end 381.632206 -286.475424)
				)
			)
		)
	)
	(zone
		(layers "B.Cu" "In4.Cu" "In6.Cu" "In11.Cu" "In13.Cu" "In15.Cu")
		(hatch none 0.5)
		(connect_pads
			(clearance 0)
		)
		(min_thickness 0.25)
		(keepout
			(tracks not_allowed)
			(vias allowed)
			(pads allowed)
			(copperpour not_allowed)
			(footprints allowed)
		)
		(placement
			(enabled no)
			(sheetname "")
		)
		(fill yes
			(thermal_gap 0.5)
			(thermal_bridge_width 0.5)
			(island_removal_mode 0)
		)
		(polygon
			(pts
				(arc
					(start 89.521284 -270.19758)
					(mid 88.868504 -270.19758)
					(end 89.521284 -270.19758)
				)
			)
		)
	)
	(zone
		(layers "B.Cu" "In4.Cu" "In6.Cu" "In11.Cu" "In13.Cu" "In15.Cu")
		(hatch none 0.5)
		(connect_pads
			(clearance 0)
		)
		(min_thickness 0.25)
		(keepout
			(tracks not_allowed)
			(vias allowed)
			(pads allowed)
			(copperpour not_allowed)
			(footprints allowed)
		)
		(placement
			(enabled no)
			(sheetname "")
		)
		(fill yes
			(thermal_gap 0.5)
			(thermal_bridge_width 0.5)
			(island_removal_mode 0)
		)
		(polygon
			(pts
				(arc
					(start 130.402584 -285.661354)
					(mid 129.749804 -285.661354)
					(end 130.402584 -285.661354)
				)
			)
		)
	)
	(zone
		(layers "B.Cu" "In4.Cu" "In6.Cu" "In11.Cu" "In13.Cu" "In15.Cu")
		(hatch none 0.5)
		(connect_pads
			(clearance 0)
		)
		(min_thickness 0.25)
		(keepout
			(tracks not_allowed)
			(vias allowed)
			(pads allowed)
			(copperpour not_allowed)
			(footprints allowed)
		)
		(placement
			(enabled no)
			(sheetname "")
		)
		(fill yes
			(thermal_gap 0.5)
			(thermal_bridge_width 0.5)
			(island_removal_mode 0)
		)
		(polygon
			(pts
				(arc
					(start 88.581484 -260.430772)
					(mid 87.928704 -260.430772)
					(end 88.581484 -260.430772)
				)
			)
		)
	)
	(zone
		(layers "B.Cu" "In4.Cu" "In6.Cu" "In11.Cu" "In13.Cu" "In15.Cu")
		(hatch none 0.5)
		(connect_pads
			(clearance 0)
		)
		(min_thickness 0.25)
		(keepout
			(tracks not_allowed)
			(vias allowed)
			(pads allowed)
			(copperpour not_allowed)
			(footprints allowed)
		)
		(placement
			(enabled no)
			(sheetname "")
		)
		(fill yes
			(thermal_gap 0.5)
			(thermal_bridge_width 0.5)
			(island_removal_mode 0)
		)
		(polygon
			(pts
				(arc
					(start 135.461756 -229.272846)
					(mid 134.808976 -229.272846)
					(end 135.461756 -229.272846)
				)
			)
		)
	)
	(zone
		(layers "B.Cu" "In4.Cu" "In6.Cu" "In11.Cu" "In13.Cu" "In15.Cu")
		(hatch none 0.5)
		(connect_pads
			(clearance 0)
		)
		(min_thickness 0.25)
		(keepout
			(tracks not_allowed)
			(vias allowed)
			(pads allowed)
			(copperpour not_allowed)
			(footprints allowed)
		)
		(placement
			(enabled no)
			(sheetname "")
		)
		(fill yes
			(thermal_gap 0.5)
			(thermal_bridge_width 0.5)
			(island_removal_mode 0)
		)
		(polygon
			(pts
				(arc
					(start 304.331878 -400.858228)
					(mid 303.628298 -400.858228)
					(end 304.331878 -400.858228)
				)
			)
		)
	)
	(zone
		(layers "B.Cu" "In4.Cu" "In6.Cu" "In11.Cu" "In13.Cu" "In15.Cu")
		(hatch none 0.5)
		(connect_pads
			(clearance 0)
		)
		(min_thickness 0.25)
		(keepout
			(tracks not_allowed)
			(vias allowed)
			(pads allowed)
			(copperpour not_allowed)
			(footprints allowed)
		)
		(placement
			(enabled no)
			(sheetname "")
		)
		(fill yes
			(thermal_gap 0.5)
			(thermal_bridge_width 0.5)
			(island_removal_mode 0)
		)
		(polygon
			(pts
				(arc
					(start 130.872738 -257.175254)
					(mid 130.219958 -257.175254)
					(end 130.872738 -257.175254)
				)
			)
		)
	)
	(zone
		(layers "B.Cu" "In4.Cu" "In6.Cu" "In11.Cu" "In13.Cu" "In15.Cu")
		(hatch none 0.5)
		(connect_pads
			(clearance 0)
		)
		(min_thickness 0.25)
		(keepout
			(tracks not_allowed)
			(vias allowed)
			(pads allowed)
			(copperpour not_allowed)
			(footprints allowed)
		)
		(placement
			(enabled no)
			(sheetname "")
		)
		(fill yes
			(thermal_gap 0.5)
			(thermal_bridge_width 0.5)
			(island_removal_mode 0)
		)
		(polygon
			(pts
				(arc
					(start 295.230804 -297.616626)
					(mid 294.578024 -297.616626)
					(end 295.230804 -297.616626)
				)
			)
		)
	)
	(zone
		(layers "B.Cu" "In4.Cu" "In6.Cu" "In11.Cu" "In13.Cu" "In15.Cu")
		(hatch none 0.5)
		(connect_pads
			(clearance 0)
		)
		(min_thickness 0.25)
		(keepout
			(tracks not_allowed)
			(vias allowed)
			(pads allowed)
			(copperpour not_allowed)
			(footprints allowed)
		)
		(placement
			(enabled no)
			(sheetname "")
		)
		(fill yes
			(thermal_gap 0.5)
			(thermal_bridge_width 0.5)
			(island_removal_mode 0)
		)
		(polygon
			(pts
				(arc
					(start 299.330872 -238.966756)
					(mid 298.678092 -238.966756)
					(end 299.330872 -238.966756)
				)
			)
		)
	)
	(zone
		(layers "B.Cu" "In4.Cu" "In6.Cu" "In11.Cu" "In13.Cu" "In15.Cu")
		(hatch none 0.5)
		(connect_pads
			(clearance 0)
		)
		(min_thickness 0.25)
		(keepout
			(tracks not_allowed)
			(vias allowed)
			(pads allowed)
			(copperpour not_allowed)
			(footprints allowed)
		)
		(placement
			(enabled no)
			(sheetname "")
		)
		(fill yes
			(thermal_gap 0.5)
			(thermal_bridge_width 0.5)
			(island_removal_mode 0)
		)
		(polygon
			(pts
				(arc
					(start 133.221984 -267.755878)
					(mid 132.569204 -267.755878)
					(end 133.221984 -267.755878)
				)
			)
		)
	)
	(zone
		(layers "B.Cu" "In4.Cu" "In6.Cu" "In11.Cu" "In13.Cu" "In15.Cu")
		(hatch none 0.5)
		(connect_pads
			(clearance 0)
		)
		(min_thickness 0.25)
		(keepout
			(tracks not_allowed)
			(vias allowed)
			(pads allowed)
			(copperpour not_allowed)
			(footprints allowed)
		)
		(placement
			(enabled no)
			(sheetname "")
		)
		(fill yes
			(thermal_gap 0.5)
			(thermal_bridge_width 0.5)
			(island_removal_mode 0)
		)
		(polygon
			(pts
				(arc
					(start 424.22699 -17.601438)
					(mid 423.52341 -17.601438)
					(end 424.22699 -17.601438)
				)
			)
		)
	)
	(zone
		(layers "B.Cu" "In4.Cu" "In6.Cu" "In11.Cu" "In13.Cu" "In15.Cu")
		(hatch none 0.5)
		(connect_pads
			(clearance 0)
		)
		(min_thickness 0.25)
		(keepout
			(tracks not_allowed)
			(vias allowed)
			(pads allowed)
			(copperpour not_allowed)
			(footprints allowed)
		)
		(placement
			(enabled no)
			(sheetname "")
		)
		(fill yes
			(thermal_gap 0.5)
			(thermal_bridge_width 0.5)
			(island_removal_mode 0)
		)
		(polygon
			(pts
				(arc
					(start 299.330872 -237.266734)
					(mid 298.678092 -237.266734)
					(end 299.330872 -237.266734)
				)
			)
		)
	)
	(zone
		(layers "B.Cu" "In4.Cu" "In6.Cu" "In11.Cu" "In13.Cu" "In15.Cu")
		(hatch none 0.5)
		(connect_pads
			(clearance 0)
		)
		(min_thickness 0.25)
		(keepout
			(tracks not_allowed)
			(vias allowed)
			(pads allowed)
			(copperpour not_allowed)
			(footprints allowed)
		)
		(placement
			(enabled no)
			(sheetname "")
		)
		(fill yes
			(thermal_gap 0.5)
			(thermal_bridge_width 0.5)
			(island_removal_mode 0)
		)
		(polygon
			(pts
				(arc
					(start 39.101268 -17.61236)
					(mid 38.397688 -17.61236)
					(end 39.101268 -17.61236)
				)
			)
		)
	)
	(zone
		(layers "B.Cu" "In4.Cu" "In6.Cu" "In11.Cu" "In13.Cu" "In15.Cu")
		(hatch none 0.5)
		(connect_pads
			(clearance 0)
		)
		(min_thickness 0.25)
		(keepout
			(tracks not_allowed)
			(vias allowed)
			(pads allowed)
			(copperpour not_allowed)
			(footprints allowed)
		)
		(placement
			(enabled no)
			(sheetname "")
		)
		(fill yes
			(thermal_gap 0.5)
			(thermal_bridge_width 0.5)
			(island_removal_mode 0)
		)
		(polygon
			(pts
				(arc
					(start 47.290736 -312.066686)
					(mid 46.637956 -312.066686)
					(end 47.290736 -312.066686)
				)
			)
		)
	)
	(zone
		(layers "B.Cu" "In4.Cu" "In6.Cu" "In11.Cu" "In13.Cu" "In15.Cu")
		(hatch none 0.5)
		(connect_pads
			(clearance 0)
		)
		(min_thickness 0.25)
		(keepout
			(tracks not_allowed)
			(vias allowed)
			(pads allowed)
			(copperpour not_allowed)
			(footprints allowed)
		)
		(placement
			(enabled no)
			(sheetname "")
		)
		(fill yes
			(thermal_gap 0.5)
			(thermal_bridge_width 0.5)
			(island_removal_mode 0)
		)
		(polygon
			(pts
				(arc
					(start 134.969504 -407.00452)
					(mid 134.265924 -407.00452)
					(end 134.969504 -407.00452)
				)
			)
		)
	)
	(zone
		(layers "B.Cu" "In4.Cu" "In6.Cu" "In11.Cu" "In13.Cu" "In15.Cu")
		(hatch none 0.5)
		(connect_pads
			(clearance 0)
		)
		(min_thickness 0.25)
		(keepout
			(tracks not_allowed)
			(vias allowed)
			(pads allowed)
			(copperpour not_allowed)
			(footprints allowed)
		)
		(placement
			(enabled no)
			(sheetname "")
		)
		(fill yes
			(thermal_gap 0.5)
			(thermal_bridge_width 0.5)
			(island_removal_mode 0)
		)
		(polygon
			(pts
				(arc
					(start 51.416204 -261.916672)
					(mid 50.763424 -261.916672)
					(end 51.416204 -261.916672)
				)
			)
		)
	)
	(zone
		(layers "B.Cu" "In4.Cu" "In6.Cu" "In11.Cu" "In13.Cu" "In15.Cu")
		(hatch none 0.5)
		(connect_pads
			(clearance 0)
		)
		(min_thickness 0.25)
		(keepout
			(tracks not_allowed)
			(vias allowed)
			(pads allowed)
			(copperpour not_allowed)
			(footprints allowed)
		)
		(placement
			(enabled no)
			(sheetname "")
		)
		(fill yes
			(thermal_gap 0.5)
			(thermal_bridge_width 0.5)
			(island_removal_mode 0)
		)
		(polygon
			(pts
				(arc
					(start 125.233938 -284.847538)
					(mid 124.581158 -284.847538)
					(end 125.233938 -284.847538)
				)
			)
		)
	)
	(zone
		(layers "B.Cu" "In4.Cu" "In6.Cu" "In11.Cu" "In13.Cu" "In15.Cu")
		(hatch none 0.5)
		(connect_pads
			(clearance 0)
		)
		(min_thickness 0.25)
		(keepout
			(tracks not_allowed)
			(vias allowed)
			(pads allowed)
			(copperpour not_allowed)
			(footprints allowed)
		)
		(placement
			(enabled no)
			(sheetname "")
		)
		(fill yes
			(thermal_gap 0.5)
			(thermal_bridge_width 0.5)
			(island_removal_mode 0)
		)
		(polygon
			(pts
				(arc
					(start 383.041652 -277.522432)
					(mid 382.388872 -277.522432)
					(end 383.041652 -277.522432)
				)
			)
		)
	)
	(zone
		(layers "B.Cu" "In4.Cu" "In6.Cu" "In11.Cu" "In13.Cu" "In15.Cu")
		(hatch none 0.5)
		(connect_pads
			(clearance 0)
		)
		(min_thickness 0.25)
		(keepout
			(tracks not_allowed)
			(vias allowed)
			(pads allowed)
			(copperpour not_allowed)
			(footprints allowed)
		)
		(placement
			(enabled no)
			(sheetname "")
		)
		(fill yes
			(thermal_gap 0.5)
			(thermal_bridge_width 0.5)
			(island_removal_mode 0)
		)
		(polygon
			(pts
				(arc
					(start 382.101852 -274.266914)
					(mid 381.449072 -274.266914)
					(end 382.101852 -274.266914)
				)
			)
		)
	)
	(zone
		(layers "B.Cu" "In4.Cu" "In6.Cu" "In11.Cu" "In13.Cu" "In15.Cu")
		(hatch none 0.5)
		(connect_pads
			(clearance 0)
		)
		(min_thickness 0.25)
		(keepout
			(tracks not_allowed)
			(vias allowed)
			(pads allowed)
			(copperpour not_allowed)
			(footprints allowed)
		)
		(placement
			(enabled no)
			(sheetname "")
		)
		(fill yes
			(thermal_gap 0.5)
			(thermal_bridge_width 0.5)
			(island_removal_mode 0)
		)
		(polygon
			(pts
				(arc
					(start 138.032744 -407.00452)
					(mid 137.329164 -407.00452)
					(end 138.032744 -407.00452)
				)
			)
		)
	)
	(zone
		(layers "B.Cu" "In4.Cu" "In6.Cu" "In11.Cu" "In13.Cu" "In15.Cu")
		(hatch none 0.5)
		(connect_pads
			(clearance 0)
		)
		(min_thickness 0.25)
		(keepout
			(tracks not_allowed)
			(vias allowed)
			(pads allowed)
			(copperpour not_allowed)
			(footprints allowed)
		)
		(placement
			(enabled no)
			(sheetname "")
		)
		(fill yes
			(thermal_gap 0.5)
			(thermal_bridge_width 0.5)
			(island_removal_mode 0)
		)
		(polygon
			(pts
				(arc
					(start 353.79787 -223.575626)
					(mid 353.14509 -223.575626)
					(end 353.79787 -223.575626)
				)
			)
		)
	)
	(zone
		(layers "B.Cu" "In4.Cu" "In6.Cu" "In11.Cu" "In13.Cu" "In15.Cu")
		(hatch none 0.5)
		(connect_pads
			(clearance 0)
		)
		(min_thickness 0.25)
		(keepout
			(tracks not_allowed)
			(vias allowed)
			(pads allowed)
			(copperpour not_allowed)
			(footprints allowed)
		)
		(placement
			(enabled no)
			(sheetname "")
		)
		(fill yes
			(thermal_gap 0.5)
			(thermal_bridge_width 0.5)
			(island_removal_mode 0)
		)
		(polygon
			(pts
				(arc
					(start 47.290736 -235.566712)
					(mid 46.637956 -235.566712)
					(end 47.290736 -235.566712)
				)
			)
		)
	)
	(zone
		(layers "B.Cu" "In4.Cu" "In6.Cu" "In11.Cu" "In13.Cu" "In15.Cu")
		(hatch none 0.5)
		(connect_pads
			(clearance 0)
		)
		(min_thickness 0.25)
		(keepout
			(tracks not_allowed)
			(vias allowed)
			(pads allowed)
			(copperpour not_allowed)
			(footprints allowed)
		)
		(placement
			(enabled no)
			(sheetname "")
		)
		(fill yes
			(thermal_gap 0.5)
			(thermal_bridge_width 0.5)
			(island_removal_mode 0)
		)
		(polygon
			(pts
				(arc
					(start 299.330872 -234.716574)
					(mid 298.678092 -234.716574)
					(end 299.330872 -234.716574)
				)
			)
		)
	)
	(zone
		(layers "B.Cu" "In4.Cu" "In6.Cu" "In11.Cu" "In13.Cu" "In15.Cu")
		(hatch none 0.5)
		(connect_pads
			(clearance 0)
		)
		(min_thickness 0.25)
		(keepout
			(tracks not_allowed)
			(vias allowed)
			(pads allowed)
			(copperpour not_allowed)
			(footprints allowed)
		)
		(placement
			(enabled no)
			(sheetname "")
		)
		(fill yes
			(thermal_gap 0.5)
			(thermal_bridge_width 0.5)
			(island_removal_mode 0)
		)
		(polygon
			(pts
				(arc
					(start 136.04113 -277.522432)
					(mid 135.38835 -277.522432)
					(end 136.04113 -277.522432)
				)
			)
		)
	)
	(zone
		(layers "B.Cu" "In4.Cu" "In6.Cu" "In11.Cu" "In13.Cu" "In15.Cu")
		(hatch none 0.5)
		(connect_pads
			(clearance 0)
		)
		(min_thickness 0.25)
		(keepout
			(tracks not_allowed)
			(vias allowed)
			(pads allowed)
			(copperpour not_allowed)
			(footprints allowed)
		)
		(placement
			(enabled no)
			(sheetname "")
		)
		(fill yes
			(thermal_gap 0.5)
			(thermal_bridge_width 0.5)
			(island_removal_mode 0)
		)
		(polygon
			(pts
				(arc
					(start 379.752606 -257.175254)
					(mid 379.099826 -257.175254)
					(end 379.752606 -257.175254)
				)
			)
		)
	)
	(zone
		(layers "B.Cu" "In4.Cu" "In6.Cu" "In11.Cu" "In13.Cu" "In15.Cu")
		(hatch none 0.5)
		(connect_pads
			(clearance 0)
		)
		(min_thickness 0.25)
		(keepout
			(tracks not_allowed)
			(vias allowed)
			(pads allowed)
			(copperpour not_allowed)
			(footprints allowed)
		)
		(placement
			(enabled no)
			(sheetname "")
		)
		(fill yes
			(thermal_gap 0.5)
			(thermal_bridge_width 0.5)
			(island_removal_mode 0)
		)
		(polygon
			(pts
				(arc
					(start 375.053606 -284.847538)
					(mid 374.400826 -284.847538)
					(end 375.053606 -284.847538)
				)
			)
		)
	)
	(zone
		(layers "B.Cu" "In4.Cu" "In6.Cu" "In11.Cu" "In13.Cu" "In15.Cu")
		(hatch none 0.5)
		(connect_pads
			(clearance 0)
		)
		(min_thickness 0.25)
		(keepout
			(tracks not_allowed)
			(vias allowed)
			(pads allowed)
			(copperpour not_allowed)
			(footprints allowed)
		)
		(placement
			(enabled no)
			(sheetname "")
		)
		(fill yes
			(thermal_gap 0.5)
			(thermal_bridge_width 0.5)
			(island_removal_mode 0)
		)
		(polygon
			(pts
				(arc
					(start 51.416204 -312.066686)
					(mid 50.763424 -312.066686)
					(end 51.416204 -312.066686)
				)
			)
		)
	)
	(zone
		(layers "B.Cu" "In4.Cu" "In6.Cu" "In11.Cu" "In13.Cu" "In15.Cu")
		(hatch none 0.5)
		(connect_pads
			(clearance 0)
		)
		(min_thickness 0.25)
		(keepout
			(tracks not_allowed)
			(vias allowed)
			(pads allowed)
			(copperpour not_allowed)
			(footprints allowed)
		)
		(placement
			(enabled no)
			(sheetname "")
		)
		(fill yes
			(thermal_gap 0.5)
			(thermal_bridge_width 0.5)
			(island_removal_mode 0)
		)
		(polygon
			(pts
				(arc
					(start 299.356272 -278.067008)
					(mid 298.703492 -278.067008)
					(end 299.356272 -278.067008)
				)
			)
		)
	)
	(zone
		(layers "B.Cu" "In4.Cu" "In6.Cu" "In11.Cu" "In13.Cu" "In15.Cu")
		(hatch none 0.5)
		(connect_pads
			(clearance 0)
		)
		(min_thickness 0.25)
		(keepout
			(tracks not_allowed)
			(vias allowed)
			(pads allowed)
			(copperpour not_allowed)
			(footprints allowed)
		)
		(placement
			(enabled no)
			(sheetname "")
		)
		(fill yes
			(thermal_gap 0.5)
			(thermal_bridge_width 0.5)
			(island_removal_mode 0)
		)
		(polygon
			(pts
				(arc
					(start 339.341206 -275.08073)
					(mid 338.688426 -275.08073)
					(end 339.341206 -275.08073)
				)
			)
		)
	)
	(zone
		(layers "B.Cu" "In4.Cu" "In6.Cu" "In11.Cu" "In13.Cu" "In15.Cu")
		(hatch none 0.5)
		(connect_pads
			(clearance 0)
		)
		(min_thickness 0.25)
		(keepout
			(tracks not_allowed)
			(vias allowed)
			(pads allowed)
			(copperpour not_allowed)
			(footprints allowed)
		)
		(placement
			(enabled no)
			(sheetname "")
		)
		(fill yes
			(thermal_gap 0.5)
			(thermal_bridge_width 0.5)
			(island_removal_mode 0)
		)
		(polygon
			(pts
				(arc
					(start 90.461084 -271.825212)
					(mid 89.808304 -271.825212)
					(end 90.461084 -271.825212)
				)
			)
		)
	)
	(zone
		(layers "B.Cu" "In4.Cu" "In6.Cu" "In11.Cu" "In13.Cu" "In15.Cu")
		(hatch none 0.5)
		(connect_pads
			(clearance 0)
		)
		(min_thickness 0.25)
		(keepout
			(tracks not_allowed)
			(vias allowed)
			(pads allowed)
			(copperpour not_allowed)
			(footprints allowed)
		)
		(placement
			(enabled no)
			(sheetname "")
		)
		(fill yes
			(thermal_gap 0.5)
			(thermal_bridge_width 0.5)
			(island_removal_mode 0)
		)
		(polygon
			(pts
				(arc
					(start 133.692138 -278.336502)
					(mid 133.039358 -278.336502)
					(end 133.692138 -278.336502)
				)
			)
		)
	)
	(zone
		(layers "B.Cu" "In4.Cu" "In6.Cu" "In11.Cu" "In13.Cu" "In15.Cu")
		(hatch none 0.5)
		(connect_pads
			(clearance 0)
		)
		(min_thickness 0.25)
		(keepout
			(tracks not_allowed)
			(vias allowed)
			(pads allowed)
			(copperpour not_allowed)
			(footprints allowed)
		)
		(placement
			(enabled no)
			(sheetname "")
		)
		(fill yes
			(thermal_gap 0.5)
			(thermal_bridge_width 0.5)
			(island_removal_mode 0)
		)
		(polygon
			(pts
				(arc
					(start 177.222404 -234.716574)
					(mid 176.569624 -234.716574)
					(end 177.222404 -234.716574)
				)
			)
		)
	)
	(zone
		(layers "B.Cu" "In4.Cu" "In6.Cu" "In11.Cu" "In13.Cu" "In15.Cu")
		(hatch none 0.5)
		(connect_pads
			(clearance 0)
		)
		(min_thickness 0.25)
		(keepout
			(tracks not_allowed)
			(vias allowed)
			(pads allowed)
			(copperpour not_allowed)
			(footprints allowed)
		)
		(placement
			(enabled no)
			(sheetname "")
		)
		(fill yes
			(thermal_gap 0.5)
			(thermal_bridge_width 0.5)
			(island_removal_mode 0)
		)
		(polygon
			(pts
				(arc
					(start 262.589772 -0.048006)
					(mid 261.886192 -0.048006)
					(end 262.589772 -0.048006)
				)
			)
		)
	)
	(zone
		(layers "B.Cu" "In4.Cu" "In6.Cu" "In11.Cu" "In13.Cu" "In15.Cu")
		(hatch none 0.5)
		(connect_pads
			(clearance 0)
		)
		(min_thickness 0.25)
		(keepout
			(tracks not_allowed)
			(vias allowed)
			(pads allowed)
			(copperpour not_allowed)
			(footprints allowed)
		)
		(placement
			(enabled no)
			(sheetname "")
		)
		(fill yes
			(thermal_gap 0.5)
			(thermal_bridge_width 0.5)
			(island_removal_mode 0)
		)
		(polygon
			(pts
				(arc
					(start 421.062404 -295.916604)
					(mid 420.409624 -295.916604)
					(end 421.062404 -295.916604)
				)
			)
		)
	)
	(zone
		(layers "B.Cu" "In4.Cu" "In6.Cu" "In11.Cu" "In13.Cu" "In15.Cu")
		(hatch none 0.5)
		(connect_pads
			(clearance 0)
		)
		(min_thickness 0.25)
		(keepout
			(tracks not_allowed)
			(vias allowed)
			(pads allowed)
			(copperpour not_allowed)
			(footprints allowed)
		)
		(placement
			(enabled no)
			(sheetname "")
		)
		(fill yes
			(thermal_gap 0.5)
			(thermal_bridge_width 0.5)
			(island_removal_mode 0)
		)
		(polygon
			(pts
				(arc
					(start 177.222404 -251.716794)
					(mid 176.569624 -251.716794)
					(end 177.222404 -251.716794)
				)
			)
		)
	)
	(zone
		(layers "B.Cu" "In4.Cu" "In6.Cu" "In11.Cu" "In13.Cu" "In15.Cu")
		(hatch none 0.5)
		(connect_pads
			(clearance 0)
		)
		(min_thickness 0.25)
		(keepout
			(tracks not_allowed)
			(vias allowed)
			(pads allowed)
			(copperpour not_allowed)
			(footprints allowed)
		)
		(placement
			(enabled no)
			(sheetname "")
		)
		(fill yes
			(thermal_gap 0.5)
			(thermal_bridge_width 0.5)
			(island_removal_mode 0)
		)
		(polygon
			(pts
				(arc
					(start 133.692138 -276.708616)
					(mid 133.039358 -276.708616)
					(end 133.692138 -276.708616)
				)
			)
		)
	)
	(zone
		(layers "B.Cu" "In4.Cu" "In6.Cu" "In11.Cu" "In13.Cu" "In15.Cu")
		(hatch none 0.5)
		(connect_pads
			(clearance 0)
		)
		(min_thickness 0.25)
		(keepout
			(tracks not_allowed)
			(vias allowed)
			(pads allowed)
			(copperpour not_allowed)
			(footprints allowed)
		)
		(placement
			(enabled no)
			(sheetname "")
		)
		(fill yes
			(thermal_gap 0.5)
			(thermal_bridge_width 0.5)
			(island_removal_mode 0)
		)
		(polygon
			(pts
				(arc
					(start 119.954802 -225.203258)
					(mid 119.302022 -225.203258)
					(end 119.954802 -225.203258)
				)
			)
		)
	)
	(zone
		(layers "B.Cu" "In4.Cu" "In6.Cu" "In11.Cu" "In13.Cu" "In15.Cu")
		(hatch none 0.5)
		(connect_pads
			(clearance 0)
		)
		(min_thickness 0.25)
		(keepout
			(tracks not_allowed)
			(vias allowed)
			(pads allowed)
			(copperpour not_allowed)
			(footprints allowed)
		)
		(placement
			(enabled no)
			(sheetname "")
		)
		(fill yes
			(thermal_gap 0.5)
			(thermal_bridge_width 0.5)
			(island_removal_mode 0)
		)
		(polygon
			(pts
				(arc
					(start 86.436708 -407.00452)
					(mid 85.733128 -407.00452)
					(end 86.436708 -407.00452)
				)
			)
		)
	)
	(zone
		(layers "B.Cu" "In4.Cu" "In6.Cu" "In11.Cu" "In13.Cu" "In15.Cu")
		(hatch none 0.5)
		(connect_pads
			(clearance 0)
		)
		(min_thickness 0.25)
		(keepout
			(tracks not_allowed)
			(vias allowed)
			(pads allowed)
			(copperpour not_allowed)
			(footprints allowed)
		)
		(placement
			(enabled no)
			(sheetname "")
		)
		(fill yes
			(thermal_gap 0.5)
			(thermal_bridge_width 0.5)
			(island_removal_mode 0)
		)
		(polygon
			(pts
				(arc
					(start 133.221984 -277.522432)
					(mid 132.569204 -277.522432)
					(end 133.221984 -277.522432)
				)
			)
		)
	)
	(zone
		(layers "B.Cu" "In4.Cu" "In6.Cu" "In11.Cu" "In13.Cu" "In15.Cu")
		(hatch none 0.5)
		(connect_pads
			(clearance 0)
		)
		(min_thickness 0.25)
		(keepout
			(tracks not_allowed)
			(vias allowed)
			(pads allowed)
			(copperpour not_allowed)
			(footprints allowed)
		)
		(placement
			(enabled no)
			(sheetname "")
		)
		(fill yes
			(thermal_gap 0.5)
			(thermal_bridge_width 0.5)
			(island_removal_mode 0)
		)
		(polygon
			(pts
				(arc
					(start 382.931924 -233.34218)
					(mid 382.279144 -233.34218)
					(end 382.931924 -233.34218)
				)
			)
		)
	)
	(zone
		(layers "B.Cu" "In4.Cu" "In6.Cu" "In11.Cu" "In13.Cu" "In15.Cu")
		(hatch none 0.5)
		(connect_pads
			(clearance 0)
		)
		(min_thickness 0.25)
		(keepout
			(tracks not_allowed)
			(vias allowed)
			(pads allowed)
			(copperpour not_allowed)
			(footprints allowed)
		)
		(placement
			(enabled no)
			(sheetname "")
		)
		(fill yes
			(thermal_gap 0.5)
			(thermal_bridge_width 0.5)
			(island_removal_mode 0)
		)
		(polygon
			(pts
				(arc
					(start 177.222404 -238.966756)
					(mid 176.569624 -238.966756)
					(end 177.222404 -238.966756)
				)
			)
		)
	)
	(zone
		(layers "B.Cu" "In4.Cu" "In6.Cu" "In11.Cu" "In13.Cu" "In15.Cu")
		(hatch none 0.5)
		(connect_pads
			(clearance 0)
		)
		(min_thickness 0.25)
		(keepout
			(tracks not_allowed)
			(vias allowed)
			(pads allowed)
			(copperpour not_allowed)
			(footprints allowed)
		)
		(placement
			(enabled no)
			(sheetname "")
		)
		(fill yes
			(thermal_gap 0.5)
			(thermal_bridge_width 0.5)
			(island_removal_mode 0)
		)
		(polygon
			(pts
				(arc
					(start 383.511552 -258.80314)
					(mid 382.858772 -258.80314)
					(end 383.511552 -258.80314)
				)
			)
		)
	)
	(zone
		(layers "B.Cu" "In4.Cu" "In6.Cu" "In11.Cu" "In13.Cu" "In15.Cu")
		(hatch none 0.5)
		(connect_pads
			(clearance 0)
		)
		(min_thickness 0.25)
		(keepout
			(tracks not_allowed)
			(vias allowed)
			(pads allowed)
			(copperpour not_allowed)
			(footprints allowed)
		)
		(placement
			(enabled no)
			(sheetname "")
		)
		(fill yes
			(thermal_gap 0.5)
			(thermal_bridge_width 0.5)
			(island_removal_mode 0)
		)
		(polygon
			(pts
				(arc
					(start 47.290736 -239.81664)
					(mid 46.637956 -239.81664)
					(end 47.290736 -239.81664)
				)
			)
		)
	)
	(zone
		(layers "B.Cu" "In4.Cu" "In6.Cu" "In11.Cu" "In13.Cu" "In15.Cu")
		(hatch none 0.5)
		(connect_pads
			(clearance 0)
		)
		(min_thickness 0.25)
		(keepout
			(tracks not_allowed)
			(vias allowed)
			(pads allowed)
			(copperpour not_allowed)
			(footprints allowed)
		)
		(placement
			(enabled no)
			(sheetname "")
		)
		(fill yes
			(thermal_gap 0.5)
			(thermal_bridge_width 0.5)
			(island_removal_mode 0)
		)
		(polygon
			(pts
				(arc
					(start 340.64067 -247.992138)
					(mid 339.98789 -247.992138)
					(end 340.64067 -247.992138)
				)
			)
		)
	)
	(zone
		(layers "B.Cu" "In4.Cu" "In6.Cu" "In11.Cu" "In13.Cu" "In15.Cu")
		(hatch none 0.5)
		(connect_pads
			(clearance 0)
		)
		(min_thickness 0.25)
		(keepout
			(tracks not_allowed)
			(vias allowed)
			(pads allowed)
			(copperpour not_allowed)
			(footprints allowed)
		)
		(placement
			(enabled no)
			(sheetname "")
		)
		(fill yes
			(thermal_gap 0.5)
			(thermal_bridge_width 0.5)
			(island_removal_mode 0)
		)
		(polygon
			(pts
				(arc
					(start 383.511806 -273.453098)
					(mid 382.859026 -273.453098)
					(end 383.511806 -273.453098)
				)
			)
		)
	)
	(zone
		(layers "B.Cu" "In4.Cu" "In6.Cu" "In11.Cu" "In13.Cu" "In15.Cu")
		(hatch none 0.5)
		(connect_pads
			(clearance 0)
		)
		(min_thickness 0.25)
		(keepout
			(tracks not_allowed)
			(vias allowed)
			(pads allowed)
			(copperpour not_allowed)
			(footprints allowed)
		)
		(placement
			(enabled no)
			(sheetname "")
		)
		(fill yes
			(thermal_gap 0.5)
			(thermal_bridge_width 0.5)
			(island_removal_mode 0)
		)
		(polygon
			(pts
				(arc
					(start 385.28117 -222.761556)
					(mid 384.62839 -222.761556)
					(end 385.28117 -222.761556)
				)
			)
		)
	)
	(zone
		(layers "B.Cu" "In4.Cu" "In6.Cu" "In11.Cu" "In13.Cu" "In15.Cu")
		(hatch none 0.5)
		(connect_pads
			(clearance 0)
		)
		(min_thickness 0.25)
		(keepout
			(tracks not_allowed)
			(vias allowed)
			(pads allowed)
			(copperpour not_allowed)
			(footprints allowed)
		)
		(placement
			(enabled no)
			(sheetname "")
		)
		(fill yes
			(thermal_gap 0.5)
			(thermal_bridge_width 0.5)
			(island_removal_mode 0)
		)
		(polygon
			(pts
				(arc
					(start 307.395118 -400.858228)
					(mid 306.691538 -400.858228)
					(end 307.395118 -400.858228)
				)
			)
		)
	)
	(zone
		(layers "B.Cu" "In4.Cu" "In6.Cu" "In11.Cu" "In13.Cu" "In15.Cu")
		(hatch none 0.5)
		(connect_pads
			(clearance 0)
		)
		(min_thickness 0.25)
		(keepout
			(tracks not_allowed)
			(vias allowed)
			(pads allowed)
			(copperpour not_allowed)
			(footprints allowed)
		)
		(placement
			(enabled no)
			(sheetname "")
		)
		(fill yes
			(thermal_gap 0.5)
			(thermal_bridge_width 0.5)
			(island_removal_mode 0)
		)
		(polygon
			(pts
				(arc
					(start 381.05207 -234.970066)
					(mid 380.39929 -234.970066)
					(end 381.05207 -234.970066)
				)
			)
		)
	)
	(zone
		(layers "B.Cu" "In4.Cu" "In6.Cu" "In11.Cu" "In13.Cu" "In15.Cu")
		(hatch none 0.5)
		(connect_pads
			(clearance 0)
		)
		(min_thickness 0.25)
		(keepout
			(tracks not_allowed)
			(vias allowed)
			(pads allowed)
			(copperpour not_allowed)
			(footprints allowed)
		)
		(placement
			(enabled no)
			(sheetname "")
		)
		(fill yes
			(thermal_gap 0.5)
			(thermal_bridge_width 0.5)
			(island_removal_mode 0)
		)
		(polygon
			(pts
				(arc
					(start 348.080838 -400.858228)
					(mid 347.377258 -400.858228)
					(end 348.080838 -400.858228)
				)
			)
		)
	)
	(zone
		(layers "B.Cu" "In4.Cu" "In6.Cu" "In11.Cu" "In13.Cu" "In15.Cu")
		(hatch none 0.5)
		(connect_pads
			(clearance 0)
		)
		(min_thickness 0.25)
		(keepout
			(tracks not_allowed)
			(vias allowed)
			(pads allowed)
			(copperpour not_allowed)
			(footprints allowed)
		)
		(placement
			(enabled no)
			(sheetname "")
		)
		(fill yes
			(thermal_gap 0.5)
			(thermal_bridge_width 0.5)
			(island_removal_mode 0)
		)
		(polygon
			(pts
				(arc
					(start 89.521284 -268.569694)
					(mid 88.868504 -268.569694)
					(end 89.521284 -268.569694)
				)
			)
		)
	)
	(zone
		(layers "B.Cu" "In4.Cu" "In6.Cu" "In11.Cu" "In13.Cu" "In15.Cu")
		(hatch none 0.5)
		(connect_pads
			(clearance 0)
		)
		(min_thickness 0.25)
		(keepout
			(tracks not_allowed)
			(vias allowed)
			(pads allowed)
			(copperpour not_allowed)
			(footprints allowed)
		)
		(placement
			(enabled no)
			(sheetname "")
		)
		(fill yes
			(thermal_gap 0.5)
			(thermal_bridge_width 0.5)
			(island_removal_mode 0)
		)
		(polygon
			(pts
				(arc
					(start 94.220538 -286.475424)
					(mid 93.567758 -286.475424)
					(end 94.220538 -286.475424)
				)
			)
		)
	)
	(zone
		(layers "B.Cu" "In4.Cu" "In6.Cu" "In11.Cu" "In13.Cu" "In15.Cu")
		(hatch none 0.5)
		(connect_pads
			(clearance 0)
		)
		(min_thickness 0.25)
		(keepout
			(tracks not_allowed)
			(vias allowed)
			(pads allowed)
			(copperpour not_allowed)
			(footprints allowed)
		)
		(placement
			(enabled no)
			(sheetname "")
		)
		(fill yes
			(thermal_gap 0.5)
			(thermal_bridge_width 0.5)
			(island_removal_mode 0)
		)
		(polygon
			(pts
				(arc
					(start 420.986204 -264.466578)
					(mid 420.333424 -264.466578)
					(end 420.986204 -264.466578)
				)
			)
		)
	)
	(zone
		(layers "B.Cu" "In4.Cu" "In6.Cu" "In11.Cu" "In13.Cu" "In15.Cu")
		(hatch none 0.5)
		(connect_pads
			(clearance 0)
		)
		(min_thickness 0.25)
		(keepout
			(tracks not_allowed)
			(vias allowed)
			(pads allowed)
			(copperpour not_allowed)
			(footprints allowed)
		)
		(placement
			(enabled no)
			(sheetname "")
		)
		(fill yes
			(thermal_gap 0.5)
			(thermal_bridge_width 0.5)
			(island_removal_mode 0)
		)
		(polygon
			(pts
				(arc
					(start 47.290736 -271.266666)
					(mid 46.637956 -271.266666)
					(end 47.290736 -271.266666)
				)
			)
		)
	)
	(zone
		(layers "B.Cu" "In4.Cu" "In6.Cu" "In11.Cu" "In13.Cu" "In15.Cu")
		(hatch none 0.5)
		(connect_pads
			(clearance 0)
		)
		(min_thickness 0.25)
		(keepout
			(tracks not_allowed)
			(vias allowed)
			(pads allowed)
			(copperpour not_allowed)
			(footprints allowed)
		)
		(placement
			(enabled no)
			(sheetname "")
		)
		(fill yes
			(thermal_gap 0.5)
			(thermal_bridge_width 0.5)
			(island_removal_mode 0)
		)
		(polygon
			(pts
				(arc
					(start 135.571738 -276.708616)
					(mid 134.918958 -276.708616)
					(end 135.571738 -276.708616)
				)
			)
		)
	)
	(zone
		(layers "B.Cu" "In4.Cu" "In6.Cu" "In11.Cu" "In13.Cu" "In15.Cu")
		(hatch none 0.5)
		(connect_pads
			(clearance 0)
		)
		(min_thickness 0.25)
		(keepout
			(tracks not_allowed)
			(vias allowed)
			(pads allowed)
			(copperpour not_allowed)
			(footprints allowed)
		)
		(placement
			(enabled no)
			(sheetname "")
		)
		(fill yes
			(thermal_gap 0.5)
			(thermal_bridge_width 0.5)
			(island_removal_mode 0)
		)
		(polygon
			(pts
				(arc
					(start 133.221984 -257.98907)
					(mid 132.569204 -257.98907)
					(end 133.221984 -257.98907)
				)
			)
		)
	)
	(zone
		(layers "B.Cu" "In4.Cu" "In6.Cu" "In11.Cu" "In13.Cu" "In15.Cu")
		(hatch none 0.5)
		(connect_pads
			(clearance 0)
		)
		(min_thickness 0.25)
		(keepout
			(tracks not_allowed)
			(vias allowed)
			(pads allowed)
			(copperpour not_allowed)
			(footprints allowed)
		)
		(placement
			(enabled no)
			(sheetname "")
		)
		(fill yes
			(thermal_gap 0.5)
			(thermal_bridge_width 0.5)
			(island_removal_mode 0)
		)
		(polygon
			(pts
				(arc
					(start 337.351624 -234.15625)
					(mid 336.698844 -234.15625)
					(end 337.351624 -234.15625)
				)
			)
		)
	)
	(zone
		(layers "B.Cu" "In4.Cu" "In6.Cu" "In11.Cu" "In13.Cu" "In15.Cu")
		(hatch none 0.5)
		(connect_pads
			(clearance 0)
		)
		(min_thickness 0.25)
		(keepout
			(tracks not_allowed)
			(vias allowed)
			(pads allowed)
			(copperpour not_allowed)
			(footprints allowed)
		)
		(placement
			(enabled no)
			(sheetname "")
		)
		(fill yes
			(thermal_gap 0.5)
			(thermal_bridge_width 0.5)
			(island_removal_mode 0)
		)
		(polygon
			(pts
				(arc
					(start 383.511552 -278.336502)
					(mid 382.858772 -278.336502)
					(end 383.511552 -278.336502)
				)
			)
		)
	)
	(zone
		(layers "B.Cu" "In4.Cu" "In6.Cu" "In11.Cu" "In13.Cu" "In15.Cu")
		(hatch none 0.5)
		(connect_pads
			(clearance 0)
		)
		(min_thickness 0.25)
		(keepout
			(tracks not_allowed)
			(vias allowed)
			(pads allowed)
			(copperpour not_allowed)
			(footprints allowed)
		)
		(placement
			(enabled no)
			(sheetname "")
		)
		(fill yes
			(thermal_gap 0.5)
			(thermal_bridge_width 0.5)
			(island_removal_mode 0)
		)
		(polygon
			(pts
				(arc
					(start 339.341206 -270.19758)
					(mid 338.688426 -270.19758)
					(end 339.341206 -270.19758)
				)
			)
		)
	)
	(zone
		(layers "B.Cu" "In4.Cu" "In6.Cu" "In11.Cu" "In13.Cu" "In15.Cu")
		(hatch none 0.5)
		(connect_pads
			(clearance 0)
		)
		(min_thickness 0.25)
		(keepout
			(tracks not_allowed)
			(vias allowed)
			(pads allowed)
			(copperpour not_allowed)
			(footprints allowed)
		)
		(placement
			(enabled no)
			(sheetname "")
		)
		(fill yes
			(thermal_gap 0.5)
			(thermal_bridge_width 0.5)
			(island_removal_mode 0)
		)
		(polygon
			(pts
				(arc
					(start 338.401152 -258.80314)
					(mid 337.748372 -258.80314)
					(end 338.401152 -258.80314)
				)
			)
		)
	)
	(zone
		(layers "B.Cu" "In4.Cu" "In6.Cu" "In11.Cu" "In13.Cu" "In15.Cu")
		(hatch none 0.5)
		(connect_pads
			(clearance 0)
		)
		(min_thickness 0.25)
		(keepout
			(tracks not_allowed)
			(vias allowed)
			(pads allowed)
			(copperpour not_allowed)
			(footprints allowed)
		)
		(placement
			(enabled no)
			(sheetname "")
		)
		(fill yes
			(thermal_gap 0.5)
			(thermal_bridge_width 0.5)
			(island_removal_mode 0)
		)
		(polygon
			(pts
				(arc
					(start 299.356272 -263.616694)
					(mid 298.703492 -263.616694)
					(end 299.356272 -263.616694)
				)
			)
		)
	)
	(zone
		(layers "B.Cu" "In4.Cu" "In6.Cu" "In11.Cu" "In13.Cu" "In15.Cu")
		(hatch none 0.5)
		(connect_pads
			(clearance 0)
		)
		(min_thickness 0.25)
		(keepout
			(tracks not_allowed)
			(vias allowed)
			(pads allowed)
			(copperpour not_allowed)
			(footprints allowed)
		)
		(placement
			(enabled no)
			(sheetname "")
		)
		(fill yes
			(thermal_gap 0.5)
			(thermal_bridge_width 0.5)
			(island_removal_mode 0)
		)
		(polygon
			(pts
				(arc
					(start 47.290736 -216.866724)
					(mid 46.637956 -216.866724)
					(end 47.290736 -216.866724)
				)
			)
		)
	)
	(zone
		(layers "B.Cu" "In4.Cu" "In6.Cu" "In11.Cu" "In13.Cu" "In15.Cu")
		(hatch none 0.5)
		(connect_pads
			(clearance 0)
		)
		(min_thickness 0.25)
		(keepout
			(tracks not_allowed)
			(vias allowed)
			(pads allowed)
			(copperpour not_allowed)
			(footprints allowed)
		)
		(placement
			(enabled no)
			(sheetname "")
		)
		(fill yes
			(thermal_gap 0.5)
			(thermal_bridge_width 0.5)
			(island_removal_mode 0)
		)
		(polygon
			(pts
				(arc
					(start 380.692406 -284.847538)
					(mid 380.039626 -284.847538)
					(end 380.692406 -284.847538)
				)
			)
		)
	)
	(zone
		(layers "B.Cu" "In4.Cu" "In6.Cu" "In11.Cu" "In13.Cu" "In15.Cu")
		(hatch none 0.5)
		(connect_pads
			(clearance 0)
		)
		(min_thickness 0.25)
		(keepout
			(tracks not_allowed)
			(vias allowed)
			(pads allowed)
			(copperpour not_allowed)
			(footprints allowed)
		)
		(placement
			(enabled no)
			(sheetname "")
		)
		(fill yes
			(thermal_gap 0.5)
			(thermal_bridge_width 0.5)
			(island_removal_mode 0)
		)
		(polygon
			(pts
				(arc
					(start 173.046136 -267.866622)
					(mid 172.393356 -267.866622)
					(end 173.046136 -267.866622)
				)
			)
		)
	)
	(zone
		(layers "B.Cu" "In4.Cu" "In6.Cu" "In11.Cu" "In13.Cu" "In15.Cu")
		(hatch none 0.5)
		(connect_pads
			(clearance 0)
		)
		(min_thickness 0.25)
		(keepout
			(tracks not_allowed)
			(vias allowed)
			(pads allowed)
			(copperpour not_allowed)
			(footprints allowed)
		)
		(placement
			(enabled no)
			(sheetname "")
		)
		(fill yes
			(thermal_gap 0.5)
			(thermal_bridge_width 0.5)
			(island_removal_mode 0)
		)
		(polygon
			(pts
				(arc
					(start 134.052056 -228.45903)
					(mid 133.399276 -228.45903)
					(end 134.052056 -228.45903)
				)
			)
		)
	)
	(zone
		(layers "B.Cu" "In4.Cu" "In6.Cu" "In11.Cu" "In13.Cu" "In15.Cu")
		(hatch none 0.5)
		(connect_pads
			(clearance 0)
		)
		(min_thickness 0.25)
		(keepout
			(tracks not_allowed)
			(vias allowed)
			(pads allowed)
			(copperpour not_allowed)
			(footprints allowed)
		)
		(placement
			(enabled no)
			(sheetname "")
		)
		(fill yes
			(thermal_gap 0.5)
			(thermal_bridge_width 0.5)
			(island_removal_mode 0)
		)
		(polygon
			(pts
				(arc
					(start 135.461756 -230.900478)
					(mid 134.808976 -230.900478)
					(end 135.461756 -230.900478)
				)
			)
		)
	)
	(zone
		(layers "B.Cu" "In4.Cu" "In6.Cu" "In11.Cu" "In13.Cu" "In15.Cu")
		(hatch none 0.5)
		(connect_pads
			(clearance 0)
		)
		(min_thickness 0.25)
		(keepout
			(tracks not_allowed)
			(vias allowed)
			(pads allowed)
			(copperpour not_allowed)
			(footprints allowed)
		)
		(placement
			(enabled no)
			(sheetname "")
		)
		(fill yes
			(thermal_gap 0.5)
			(thermal_bridge_width 0.5)
			(island_removal_mode 0)
		)
		(polygon
			(pts
				(arc
					(start 295.230804 -259.366766)
					(mid 294.578024 -259.366766)
					(end 295.230804 -259.366766)
				)
			)
		)
	)
	(zone
		(layers "B.Cu" "In4.Cu" "In6.Cu" "In11.Cu" "In13.Cu" "In15.Cu")
		(hatch none 0.5)
		(connect_pads
			(clearance 0)
		)
		(min_thickness 0.25)
		(keepout
			(tracks not_allowed)
			(vias allowed)
			(pads allowed)
			(copperpour not_allowed)
			(footprints allowed)
		)
		(placement
			(enabled no)
			(sheetname "")
		)
		(fill yes
			(thermal_gap 0.5)
			(thermal_bridge_width 0.5)
			(island_removal_mode 0)
		)
		(polygon
			(pts
				(arc
					(start 89.051384 -264.50036)
					(mid 88.398604 -264.50036)
					(end 89.051384 -264.50036)
				)
			)
		)
	)
	(zone
		(layers "B.Cu" "In4.Cu" "In6.Cu" "In11.Cu" "In13.Cu" "In15.Cu")
		(hatch none 0.5)
		(connect_pads
			(clearance 0)
		)
		(min_thickness 0.25)
		(keepout
			(tracks not_allowed)
			(vias allowed)
			(pads allowed)
			(copperpour not_allowed)
			(footprints allowed)
		)
		(placement
			(enabled no)
			(sheetname "")
		)
		(fill yes
			(thermal_gap 0.5)
			(thermal_bridge_width 0.5)
			(island_removal_mode 0)
		)
		(polygon
			(pts
				(arc
					(start 394.5636 -407.00452)
					(mid 393.86002 -407.00452)
					(end 394.5636 -407.00452)
				)
			)
		)
	)
	(zone
		(layers "B.Cu" "In4.Cu" "In6.Cu" "In11.Cu" "In13.Cu" "In15.Cu")
		(hatch none 0.5)
		(connect_pads
			(clearance 0)
		)
		(min_thickness 0.25)
		(keepout
			(tracks not_allowed)
			(vias allowed)
			(pads allowed)
			(copperpour not_allowed)
			(footprints allowed)
		)
		(placement
			(enabled no)
			(sheetname "")
		)
		(fill yes
			(thermal_gap 0.5)
			(thermal_bridge_width 0.5)
			(island_removal_mode 0)
		)
		(polygon
			(pts
				(arc
					(start 132.752338 -284.847538)
					(mid 132.099558 -284.847538)
					(end 132.752338 -284.847538)
				)
			)
		)
	)
	(zone
		(layers "B.Cu" "In4.Cu" "In6.Cu" "In11.Cu" "In13.Cu" "In15.Cu")
		(hatch none 0.5)
		(connect_pads
			(clearance 0)
		)
		(min_thickness 0.25)
		(keepout
			(tracks not_allowed)
			(vias allowed)
			(pads allowed)
			(copperpour not_allowed)
			(footprints allowed)
		)
		(placement
			(enabled no)
			(sheetname "")
		)
		(fill yes
			(thermal_gap 0.5)
			(thermal_bridge_width 0.5)
			(island_removal_mode 0)
		)
		(polygon
			(pts
				(arc
					(start 77.246988 -407.00452)
					(mid 76.543408 -407.00452)
					(end 77.246988 -407.00452)
				)
			)
		)
	)
	(zone
		(layers "B.Cu" "In4.Cu" "In6.Cu" "In11.Cu" "In13.Cu" "In15.Cu")
		(hatch none 0.5)
		(connect_pads
			(clearance 0)
		)
		(min_thickness 0.25)
		(keepout
			(tracks not_allowed)
			(vias allowed)
			(pads allowed)
			(copperpour not_allowed)
			(footprints allowed)
		)
		(placement
			(enabled no)
			(sheetname "")
		)
		(fill yes
			(thermal_gap 0.5)
			(thermal_bridge_width 0.5)
			(island_removal_mode 0)
		)
		(polygon
			(pts
				(arc
					(start 383.511552 -257.175254)
					(mid 382.858772 -257.175254)
					(end 383.511552 -257.175254)
				)
			)
		)
	)
	(zone
		(layers "B.Cu" "In4.Cu" "In6.Cu" "In11.Cu" "In13.Cu" "In15.Cu")
		(hatch none 0.5)
		(connect_pads
			(clearance 0)
		)
		(min_thickness 0.25)
		(keepout
			(tracks not_allowed)
			(vias allowed)
			(pads allowed)
			(copperpour not_allowed)
			(footprints allowed)
		)
		(placement
			(enabled no)
			(sheetname "")
		)
		(fill yes
			(thermal_gap 0.5)
			(thermal_bridge_width 0.5)
			(island_removal_mode 0)
		)
		(polygon
			(pts
				(arc
					(start 382.93167 -228.45903)
					(mid 382.27889 -228.45903)
					(end 382.93167 -228.45903)
				)
			)
		)
	)
	(zone
		(layers "B.Cu" "In4.Cu" "In6.Cu" "In11.Cu" "In13.Cu" "In15.Cu")
		(hatch none 0.5)
		(connect_pads
			(clearance 0)
		)
		(min_thickness 0.25)
		(keepout
			(tracks not_allowed)
			(vias allowed)
			(pads allowed)
			(copperpour not_allowed)
			(footprints allowed)
		)
		(placement
			(enabled no)
			(sheetname "")
		)
		(fill yes
			(thermal_gap 0.5)
			(thermal_bridge_width 0.5)
			(island_removal_mode 0)
		)
		(polygon
			(pts
				(arc
					(start 90.461084 -268.569694)
					(mid 89.808304 -268.569694)
					(end 90.461084 -268.569694)
				)
			)
		)
	)
	(zone
		(layers "B.Cu" "In4.Cu" "In6.Cu" "In11.Cu" "In13.Cu" "In15.Cu")
		(hatch none 0.5)
		(connect_pads
			(clearance 0)
		)
		(min_thickness 0.25)
		(keepout
			(tracks not_allowed)
			(vias allowed)
			(pads allowed)
			(copperpour not_allowed)
			(footprints allowed)
		)
		(placement
			(enabled no)
			(sheetname "")
		)
		(fill yes
			(thermal_gap 0.5)
			(thermal_bridge_width 0.5)
			(island_removal_mode 0)
		)
		(polygon
			(pts
				(arc
					(start 295.230804 -252.566678)
					(mid 294.578024 -252.566678)
					(end 295.230804 -252.566678)
				)
			)
		)
	)
	(zone
		(layers "B.Cu" "In4.Cu" "In6.Cu" "In11.Cu" "In13.Cu" "In15.Cu")
		(hatch none 0.5)
		(connect_pads
			(clearance 0)
		)
		(min_thickness 0.25)
		(keepout
			(tracks not_allowed)
			(vias allowed)
			(pads allowed)
			(copperpour not_allowed)
			(footprints allowed)
		)
		(placement
			(enabled no)
			(sheetname "")
		)
		(fill yes
			(thermal_gap 0.5)
			(thermal_bridge_width 0.5)
			(island_removal_mode 0)
		)
		(polygon
			(pts
				(arc
					(start 381.05207 -244.73662)
					(mid 380.39929 -244.73662)
					(end 381.05207 -244.73662)
				)
			)
		)
	)
	(zone
		(layers "B.Cu" "In4.Cu" "In6.Cu" "In11.Cu" "In13.Cu" "In15.Cu")
		(hatch none 0.5)
		(connect_pads
			(clearance 0)
		)
		(min_thickness 0.25)
		(keepout
			(tracks not_allowed)
			(vias allowed)
			(pads allowed)
			(copperpour not_allowed)
			(footprints allowed)
		)
		(placement
			(enabled no)
			(sheetname "")
		)
		(fill yes
			(thermal_gap 0.5)
			(thermal_bridge_width 0.5)
			(island_removal_mode 0)
		)
		(polygon
			(pts
				(arc
					(start 295.230804 -205.816708)
					(mid 294.578024 -205.816708)
					(end 295.230804 -205.816708)
				)
			)
		)
	)
	(zone
		(layers "B.Cu" "In4.Cu" "In6.Cu" "In11.Cu" "In13.Cu" "In15.Cu")
		(hatch none 0.5)
		(connect_pads
			(clearance 0)
		)
		(min_thickness 0.25)
		(keepout
			(tracks not_allowed)
			(vias allowed)
			(pads allowed)
			(copperpour not_allowed)
			(footprints allowed)
		)
		(placement
			(enabled no)
			(sheetname "")
		)
		(fill yes
			(thermal_gap 0.5)
			(thermal_bridge_width 0.5)
			(island_removal_mode 0)
		)
		(polygon
			(pts
				(arc
					(start 95.160338 -284.847538)
					(mid 94.507558 -284.847538)
					(end 95.160338 -284.847538)
				)
			)
		)
	)
	(zone
		(layers "B.Cu" "In4.Cu" "In6.Cu" "In11.Cu" "In13.Cu" "In15.Cu")
		(hatch none 0.5)
		(connect_pads
			(clearance 0)
		)
		(min_thickness 0.25)
		(keepout
			(tracks not_allowed)
			(vias allowed)
			(pads allowed)
			(copperpour not_allowed)
			(footprints allowed)
		)
		(placement
			(enabled no)
			(sheetname "")
		)
		(fill yes
			(thermal_gap 0.5)
			(thermal_bridge_width 0.5)
			(island_removal_mode 0)
		)
		(polygon
			(pts
				(arc
					(start 131.342384 -285.661354)
					(mid 130.689604 -285.661354)
					(end 131.342384 -285.661354)
				)
			)
		)
	)
	(zone
		(layers "B.Cu" "In4.Cu" "In6.Cu" "In11.Cu" "In13.Cu" "In15.Cu")
		(hatch none 0.5)
		(connect_pads
			(clearance 0)
		)
		(min_thickness 0.25)
		(keepout
			(tracks not_allowed)
			(vias allowed)
			(pads allowed)
			(copperpour not_allowed)
			(footprints allowed)
		)
		(placement
			(enabled no)
			(sheetname "")
		)
		(fill yes
			(thermal_gap 0.5)
			(thermal_bridge_width 0.5)
			(island_removal_mode 0)
		)
		(polygon
			(pts
				(arc
					(start 47.290736 -278.916638)
					(mid 46.637956 -278.916638)
					(end 47.290736 -278.916638)
				)
			)
		)
	)
	(zone
		(layers "B.Cu" "In4.Cu" "In6.Cu" "In11.Cu" "In13.Cu" "In15.Cu")
		(hatch none 0.5)
		(connect_pads
			(clearance 0)
		)
		(min_thickness 0.25)
		(keepout
			(tracks not_allowed)
			(vias allowed)
			(pads allowed)
			(copperpour not_allowed)
			(footprints allowed)
		)
		(placement
			(enabled no)
			(sheetname "")
		)
		(fill yes
			(thermal_gap 0.5)
			(thermal_bridge_width 0.5)
			(island_removal_mode 0)
		)
		(polygon
			(pts
				(arc
					(start 421.062404 -205.816708)
					(mid 420.409624 -205.816708)
					(end 421.062404 -205.816708)
				)
			)
		)
	)
	(zone
		(layers "B.Cu" "In4.Cu" "In6.Cu" "In11.Cu" "In13.Cu" "In15.Cu")
		(hatch none 0.5)
		(connect_pads
			(clearance 0)
		)
		(min_thickness 0.25)
		(keepout
			(tracks not_allowed)
			(vias allowed)
			(pads allowed)
			(copperpour not_allowed)
			(footprints allowed)
		)
		(placement
			(enabled no)
			(sheetname "")
		)
		(fill yes
			(thermal_gap 0.5)
			(thermal_bridge_width 0.5)
			(island_removal_mode 0)
		)
		(polygon
			(pts
				(arc
					(start 421.062404 -250.866656)
					(mid 420.409624 -250.866656)
					(end 421.062404 -250.866656)
				)
			)
		)
	)
	(zone
		(layers "B.Cu" "In4.Cu" "In6.Cu" "In11.Cu" "In13.Cu" "In15.Cu")
		(hatch none 0.5)
		(connect_pads
			(clearance 0)
		)
		(min_thickness 0.25)
		(keepout
			(tracks not_allowed)
			(vias allowed)
			(pads allowed)
			(copperpour not_allowed)
			(footprints allowed)
		)
		(placement
			(enabled no)
			(sheetname "")
		)
		(fill yes
			(thermal_gap 0.5)
			(thermal_bridge_width 0.5)
			(island_removal_mode 0)
		)
		(polygon
			(pts
				(arc
					(start 158.009336 -306.96662)
					(mid 157.356556 -306.96662)
					(end 158.009336 -306.96662)
				)
			)
		)
	)
	(zone
		(layers "B.Cu" "In4.Cu" "In6.Cu" "In11.Cu" "In13.Cu" "In15.Cu")
		(hatch none 0.5)
		(connect_pads
			(clearance 0)
		)
		(min_thickness 0.25)
		(keepout
			(tracks not_allowed)
			(vias allowed)
			(pads allowed)
			(copperpour not_allowed)
			(footprints allowed)
		)
		(placement
			(enabled no)
			(sheetname "")
		)
		(fill yes
			(thermal_gap 0.5)
			(thermal_bridge_width 0.5)
			(island_removal_mode 0)
		)
		(polygon
			(pts
				(arc
					(start 378.812806 -284.847538)
					(mid 378.160026 -284.847538)
					(end 378.812806 -284.847538)
				)
			)
		)
	)
	(zone
		(layers "B.Cu" "In4.Cu" "In6.Cu" "In11.Cu" "In13.Cu" "In15.Cu")
		(hatch none 0.5)
		(connect_pads
			(clearance 0)
		)
		(min_thickness 0.25)
		(keepout
			(tracks not_allowed)
			(vias allowed)
			(pads allowed)
			(copperpour not_allowed)
			(footprints allowed)
		)
		(placement
			(enabled no)
			(sheetname "")
		)
		(fill yes
			(thermal_gap 0.5)
			(thermal_bridge_width 0.5)
			(island_removal_mode 0)
		)
		(polygon
			(pts
				(arc
					(start 410.814774 -19.125438)
					(mid 410.111194 -19.125438)
					(end 410.814774 -19.125438)
				)
			)
		)
	)
	(zone
		(layers "B.Cu" "In4.Cu" "In6.Cu" "In11.Cu" "In13.Cu" "In15.Cu")
		(hatch none 0.5)
		(connect_pads
			(clearance 0)
		)
		(min_thickness 0.25)
		(keepout
			(tracks not_allowed)
			(vias allowed)
			(pads allowed)
			(copperpour not_allowed)
			(footprints allowed)
		)
		(placement
			(enabled no)
			(sheetname "")
		)
		(fill yes
			(thermal_gap 0.5)
			(thermal_bridge_width 0.5)
			(island_removal_mode 0)
		)
		(polygon
			(pts
				(arc
					(start 383.401824 -234.15625)
					(mid 382.749044 -234.15625)
					(end 383.401824 -234.15625)
				)
			)
		)
	)
	(zone
		(layers "B.Cu" "In4.Cu" "In6.Cu" "In11.Cu" "In13.Cu" "In15.Cu")
		(hatch none 0.5)
		(connect_pads
			(clearance 0)
		)
		(min_thickness 0.25)
		(keepout
			(tracks not_allowed)
			(vias allowed)
			(pads allowed)
			(copperpour not_allowed)
			(footprints allowed)
		)
		(placement
			(enabled no)
			(sheetname "")
		)
		(fill yes
			(thermal_gap 0.5)
			(thermal_bridge_width 0.5)
			(island_removal_mode 0)
		)
		(polygon
			(pts
				(arc
					(start 173.122336 -308.666642)
					(mid 172.469556 -308.666642)
					(end 173.122336 -308.666642)
				)
			)
		)
	)
	(zone
		(layers "B.Cu" "In4.Cu" "In6.Cu" "In11.Cu" "In13.Cu" "In15.Cu")
		(hatch none 0.5)
		(connect_pads
			(clearance 0)
		)
		(min_thickness 0.25)
		(keepout
			(tracks not_allowed)
			(vias allowed)
			(pads allowed)
			(copperpour not_allowed)
			(footprints allowed)
		)
		(placement
			(enabled no)
			(sheetname "")
		)
		(fill yes
			(thermal_gap 0.5)
			(thermal_bridge_width 0.5)
			(island_removal_mode 0)
		)
		(polygon
			(pts
				(arc
					(start 51.390804 -216.016586)
					(mid 50.738024 -216.016586)
					(end 51.390804 -216.016586)
				)
			)
		)
	)
	(zone
		(layers "B.Cu" "In4.Cu" "In6.Cu" "In11.Cu" "In13.Cu" "In15.Cu")
		(hatch none 0.5)
		(connect_pads
			(clearance 0)
		)
		(min_thickness 0.25)
		(keepout
			(tracks not_allowed)
			(vias allowed)
			(pads allowed)
			(copperpour not_allowed)
			(footprints allowed)
		)
		(placement
			(enabled no)
			(sheetname "")
		)
		(fill yes
			(thermal_gap 0.5)
			(thermal_bridge_width 0.5)
			(island_removal_mode 0)
		)
		(polygon
			(pts
				(arc
					(start 133.582156 -239.0394)
					(mid 132.929376 -239.0394)
					(end 133.582156 -239.0394)
				)
			)
		)
	)
	(zone
		(layers "B.Cu" "In4.Cu" "In6.Cu" "In11.Cu" "In13.Cu" "In15.Cu")
		(hatch none 0.5)
		(connect_pads
			(clearance 0)
		)
		(min_thickness 0.25)
		(keepout
			(tracks not_allowed)
			(vias allowed)
			(pads allowed)
			(copperpour not_allowed)
			(footprints allowed)
		)
		(placement
			(enabled no)
			(sheetname "")
		)
		(fill yes
			(thermal_gap 0.5)
			(thermal_bridge_width 0.5)
			(island_removal_mode 0)
		)
		(polygon
			(pts
				(arc
					(start 62.378336 -299.316648)
					(mid 61.725556 -299.316648)
					(end 62.378336 -299.316648)
				)
			)
		)
	)
	(zone
		(layers "B.Cu" "In4.Cu" "In6.Cu" "In11.Cu" "In13.Cu" "In15.Cu")
		(hatch none 0.5)
		(connect_pads
			(clearance 0)
		)
		(min_thickness 0.25)
		(keepout
			(tracks not_allowed)
			(vias allowed)
			(pads allowed)
			(copperpour not_allowed)
			(footprints allowed)
		)
		(placement
			(enabled no)
			(sheetname "")
		)
		(fill yes
			(thermal_gap 0.5)
			(thermal_bridge_width 0.5)
			(island_removal_mode 0)
		)
		(polygon
			(pts
				(arc
					(start 88.941402 -238.225584)
					(mid 88.288622 -238.225584)
					(end 88.941402 -238.225584)
				)
			)
		)
	)
	(zone
		(layers "B.Cu" "In4.Cu" "In6.Cu" "In11.Cu" "In13.Cu" "In15.Cu")
		(hatch none 0.5)
		(connect_pads
			(clearance 0)
		)
		(min_thickness 0.25)
		(keepout
			(tracks not_allowed)
			(vias allowed)
			(pads allowed)
			(copperpour not_allowed)
			(footprints allowed)
		)
		(placement
			(enabled no)
			(sheetname "")
		)
		(fill yes
			(thermal_gap 0.5)
			(thermal_bridge_width 0.5)
			(island_removal_mode 0)
		)
		(polygon
			(pts
				(arc
					(start 295.230804 -245.76659)
					(mid 294.578024 -245.76659)
					(end 295.230804 -245.76659)
				)
			)
		)
	)
	(zone
		(layers "B.Cu" "In4.Cu" "In6.Cu" "In11.Cu" "In13.Cu" "In15.Cu")
		(hatch none 0.5)
		(connect_pads
			(clearance 0)
		)
		(min_thickness 0.25)
		(keepout
			(tracks not_allowed)
			(vias allowed)
			(pads allowed)
			(copperpour not_allowed)
			(footprints allowed)
		)
		(placement
			(enabled no)
			(sheetname "")
		)
		(fill yes
			(thermal_gap 0.5)
			(thermal_bridge_width 0.5)
			(island_removal_mode 0)
		)
		(polygon
			(pts
				(arc
					(start 388.43712 -407.00452)
					(mid 387.73354 -407.00452)
					(end 388.43712 -407.00452)
				)
			)
		)
	)
	(zone
		(layers "B.Cu" "In4.Cu" "In6.Cu" "In11.Cu" "In13.Cu" "In15.Cu")
		(hatch none 0.5)
		(connect_pads
			(clearance 0)
		)
		(min_thickness 0.25)
		(keepout
			(tracks not_allowed)
			(vias allowed)
			(pads allowed)
			(copperpour not_allowed)
			(footprints allowed)
		)
		(placement
			(enabled no)
			(sheetname "")
		)
		(fill yes
			(thermal_gap 0.5)
			(thermal_bridge_width 0.5)
			(island_removal_mode 0)
		)
		(polygon
			(pts
				(arc
					(start 66.478404 -302.716692)
					(mid 65.825624 -302.716692)
					(end 66.478404 -302.716692)
				)
			)
		)
	)
	(zone
		(layers "B.Cu" "In4.Cu" "In6.Cu" "In11.Cu" "In13.Cu" "In15.Cu")
		(hatch none 0.5)
		(connect_pads
			(clearance 0)
		)
		(min_thickness 0.25)
		(keepout
			(tracks not_allowed)
			(vias allowed)
			(pads allowed)
			(copperpour not_allowed)
			(footprints allowed)
		)
		(placement
			(enabled no)
			(sheetname "")
		)
		(fill yes
			(thermal_gap 0.5)
			(thermal_bridge_width 0.5)
			(island_removal_mode 0)
		)
		(polygon
			(pts
				(arc
					(start 294.17137 -162.100768)
					(mid 293.46779 -162.100768)
					(end 294.17137 -162.100768)
				)
			)
		)
	)
	(zone
		(layers "B.Cu" "In4.Cu" "In6.Cu" "In11.Cu" "In13.Cu" "In15.Cu")
		(hatch none 0.5)
		(connect_pads
			(clearance 0)
		)
		(min_thickness 0.25)
		(keepout
			(tracks not_allowed)
			(vias allowed)
			(pads allowed)
			(copperpour not_allowed)
			(footprints allowed)
		)
		(placement
			(enabled no)
			(sheetname "")
		)
		(fill yes
			(thermal_gap 0.5)
			(thermal_bridge_width 0.5)
			(island_removal_mode 0)
		)
		(polygon
			(pts
				(arc
					(start 47.290736 -250.866656)
					(mid 46.637956 -250.866656)
					(end 47.290736 -250.866656)
				)
			)
		)
	)
	(zone
		(layers "B.Cu" "In4.Cu" "In6.Cu" "In11.Cu" "In13.Cu" "In15.Cu")
		(hatch none 0.5)
		(connect_pads
			(clearance 0)
		)
		(min_thickness 0.25)
		(keepout
			(tracks not_allowed)
			(vias allowed)
			(pads allowed)
			(copperpour not_allowed)
			(footprints allowed)
		)
		(placement
			(enabled no)
			(sheetname "")
		)
		(fill yes
			(thermal_gap 0.5)
			(thermal_bridge_width 0.5)
			(island_removal_mode 0)
		)
		(polygon
			(pts
				(arc
					(start 336.521552 -270.19758)
					(mid 335.868772 -270.19758)
					(end 336.521552 -270.19758)
				)
			)
		)
	)
	(zone
		(layers "B.Cu" "In4.Cu" "In6.Cu" "In11.Cu" "In13.Cu" "In15.Cu")
		(hatch none 0.5)
		(connect_pads
			(clearance 0)
		)
		(min_thickness 0.25)
		(keepout
			(tracks not_allowed)
			(vias allowed)
			(pads allowed)
			(copperpour not_allowed)
			(footprints allowed)
		)
		(placement
			(enabled no)
			(sheetname "")
		)
		(fill yes
			(thermal_gap 0.5)
			(thermal_bridge_width 0.5)
			(island_removal_mode 0)
		)
		(polygon
			(pts
				(arc
					(start 162.109404 -231.316784)
					(mid 161.456624 -231.316784)
					(end 162.109404 -231.316784)
				)
			)
		)
	)
	(zone
		(layers "B.Cu" "In4.Cu" "In6.Cu" "In11.Cu" "In13.Cu" "In15.Cu")
		(hatch none 0.5)
		(connect_pads
			(clearance 0)
		)
		(min_thickness 0.25)
		(keepout
			(tracks not_allowed)
			(vias allowed)
			(pads allowed)
			(copperpour not_allowed)
			(footprints allowed)
		)
		(placement
			(enabled no)
			(sheetname "")
		)
		(fill yes
			(thermal_gap 0.5)
			(thermal_bridge_width 0.5)
			(island_removal_mode 0)
		)
		(polygon
			(pts
				(arc
					(start 336.991452 -269.38351)
					(mid 336.338672 -269.38351)
					(end 336.991452 -269.38351)
				)
			)
		)
	)
	(zone
		(layers "B.Cu" "In4.Cu" "In6.Cu" "In11.Cu" "In13.Cu" "In15.Cu")
		(hatch none 0.5)
		(connect_pads
			(clearance 0)
		)
		(min_thickness 0.25)
		(keepout
			(tracks not_allowed)
			(vias allowed)
			(pads allowed)
			(copperpour not_allowed)
			(footprints allowed)
		)
		(placement
			(enabled no)
			(sheetname "")
		)
		(fill yes
			(thermal_gap 0.5)
			(thermal_bridge_width 0.5)
			(island_removal_mode 0)
		)
		(polygon
			(pts
				(arc
					(start 338.401152 -262.058658)
					(mid 337.748372 -262.058658)
					(end 338.401152 -262.058658)
				)
			)
		)
	)
	(zone
		(layers "B.Cu" "In4.Cu" "In6.Cu" "In11.Cu" "In13.Cu" "In15.Cu")
		(hatch none 0.5)
		(connect_pads
			(clearance 0)
		)
		(min_thickness 0.25)
		(keepout
			(tracks not_allowed)
			(vias allowed)
			(pads allowed)
			(copperpour not_allowed)
			(footprints allowed)
		)
		(placement
			(enabled no)
			(sheetname "")
		)
		(fill yes
			(thermal_gap 0.5)
			(thermal_bridge_width 0.5)
			(island_removal_mode 0)
		)
		(polygon
			(pts
				(arc
					(start 134.991856 -246.364506)
					(mid 134.339076 -246.364506)
					(end 134.991856 -246.364506)
				)
			)
		)
	)
	(zone
		(layers "B.Cu" "In4.Cu" "In6.Cu" "In11.Cu" "In13.Cu" "In15.Cu")
		(hatch none 0.5)
		(connect_pads
			(clearance 0)
		)
		(min_thickness 0.25)
		(keepout
			(tracks not_allowed)
			(vias allowed)
			(pads allowed)
			(copperpour not_allowed)
			(footprints allowed)
		)
		(placement
			(enabled no)
			(sheetname "")
		)
		(fill yes
			(thermal_gap 0.5)
			(thermal_bridge_width 0.5)
			(island_removal_mode 0)
		)
		(polygon
			(pts
				(arc
					(start 362.25607 -225.203258)
					(mid 361.60329 -225.203258)
					(end 362.25607 -225.203258)
				)
			)
		)
	)
	(zone
		(layers "B.Cu" "In4.Cu" "In6.Cu" "In11.Cu" "In13.Cu" "In15.Cu")
		(hatch none 0.5)
		(connect_pads
			(clearance 0)
		)
		(min_thickness 0.25)
		(keepout
			(tracks not_allowed)
			(vias allowed)
			(pads allowed)
			(copperpour not_allowed)
			(footprints allowed)
		)
		(placement
			(enabled no)
			(sheetname "")
		)
		(fill yes
			(thermal_gap 0.5)
			(thermal_bridge_width 0.5)
			(island_removal_mode 0)
		)
		(polygon
			(pts
				(arc
					(start 88.941402 -228.45903)
					(mid 88.288622 -228.45903)
					(end 88.941402 -228.45903)
				)
			)
		)
	)
	(zone
		(layers "B.Cu" "In4.Cu" "In6.Cu" "In11.Cu" "In13.Cu" "In15.Cu")
		(hatch none 0.5)
		(connect_pads
			(clearance 0)
		)
		(min_thickness 0.25)
		(keepout
			(tracks not_allowed)
			(vias allowed)
			(pads allowed)
			(copperpour not_allowed)
			(footprints allowed)
		)
		(placement
			(enabled no)
			(sheetname "")
		)
		(fill yes
			(thermal_gap 0.5)
			(thermal_bridge_width 0.5)
			(island_removal_mode 0)
		)
		(polygon
			(pts
				(arc
					(start 319.648078 -400.858228)
					(mid 318.944498 -400.858228)
					(end 319.648078 -400.858228)
				)
			)
		)
	)
	(zone
		(layers "B.Cu" "In4.Cu" "In6.Cu" "In11.Cu" "In13.Cu" "In15.Cu")
		(hatch none 0.5)
		(connect_pads
			(clearance 0)
		)
		(min_thickness 0.25)
		(keepout
			(tracks not_allowed)
			(vias allowed)
			(pads allowed)
			(copperpour not_allowed)
			(footprints allowed)
		)
		(placement
			(enabled no)
			(sheetname "")
		)
		(fill yes
			(thermal_gap 0.5)
			(thermal_bridge_width 0.5)
			(island_removal_mode 0)
		)
		(polygon
			(pts
				(arc
					(start 102.678738 -284.847538)
					(mid 102.025958 -284.847538)
					(end 102.678738 -284.847538)
				)
			)
		)
	)
	(zone
		(layers "B.Cu" "In4.Cu" "In6.Cu" "In11.Cu" "In13.Cu" "In15.Cu")
		(hatch none 0.5)
		(connect_pads
			(clearance 0)
		)
		(min_thickness 0.25)
		(keepout
			(tracks not_allowed)
			(vias allowed)
			(pads allowed)
			(copperpour not_allowed)
			(footprints allowed)
		)
		(placement
			(enabled no)
			(sheetname "")
		)
		(fill yes
			(thermal_gap 0.5)
			(thermal_bridge_width 0.5)
			(island_removal_mode 0)
		)
		(polygon
			(pts
				(arc
					(start 338.291424 -230.900478)
					(mid 337.638644 -230.900478)
					(end 338.291424 -230.900478)
				)
			)
		)
	)
	(zone
		(layers "B.Cu" "In4.Cu" "In6.Cu" "In11.Cu" "In13.Cu" "In15.Cu")
		(hatch none 0.5)
		(connect_pads
			(clearance 0)
		)
		(min_thickness 0.25)
		(keepout
			(tracks not_allowed)
			(vias allowed)
			(pads allowed)
			(copperpour not_allowed)
			(footprints allowed)
		)
		(placement
			(enabled no)
			(sheetname "")
		)
		(fill yes
			(thermal_gap 0.5)
			(thermal_bridge_width 0.5)
			(island_removal_mode 0)
		)
		(polygon
			(pts
				(arc
					(start 326.638158 -400.858228)
					(mid 325.934578 -400.858228)
					(end 326.638158 -400.858228)
				)
			)
		)
	)
	(zone
		(layers "B.Cu" "In4.Cu" "In6.Cu" "In11.Cu" "In13.Cu" "In15.Cu")
		(hatch none 0.5)
		(connect_pads
			(clearance 0)
		)
		(min_thickness 0.25)
		(keepout
			(tracks not_allowed)
			(vias allowed)
			(pads allowed)
			(copperpour not_allowed)
			(footprints allowed)
		)
		(placement
			(enabled no)
			(sheetname "")
		)
		(fill yes
			(thermal_gap 0.5)
			(thermal_bridge_width 0.5)
			(island_removal_mode 0)
		)
		(polygon
			(pts
				(arc
					(start 350.618806 -284.847538)
					(mid 349.966026 -284.847538)
					(end 350.618806 -284.847538)
				)
			)
		)
	)
	(zone
		(layers "B.Cu" "In4.Cu" "In6.Cu" "In11.Cu" "In13.Cu" "In15.Cu")
		(hatch none 0.5)
		(connect_pads
			(clearance 0)
		)
		(min_thickness 0.25)
		(keepout
			(tracks not_allowed)
			(vias allowed)
			(pads allowed)
			(copperpour not_allowed)
			(footprints allowed)
		)
		(placement
			(enabled no)
			(sheetname "")
		)
		(fill yes
			(thermal_gap 0.5)
			(thermal_bridge_width 0.5)
			(island_removal_mode 0)
		)
		(polygon
			(pts
				(arc
					(start 410.049472 -300.166786)
					(mid 409.396692 -300.166786)
					(end 410.049472 -300.166786)
				)
			)
		)
	)
	(zone
		(layers "B.Cu" "In4.Cu" "In6.Cu" "In11.Cu" "In13.Cu" "In15.Cu")
		(hatch none 0.5)
		(connect_pads
			(clearance 0)
		)
		(min_thickness 0.25)
		(keepout
			(tracks not_allowed)
			(vias allowed)
			(pads allowed)
			(copperpour not_allowed)
			(footprints allowed)
		)
		(placement
			(enabled no)
			(sheetname "")
		)
		(fill yes
			(thermal_gap 0.5)
			(thermal_bridge_width 0.5)
			(island_removal_mode 0)
		)
		(polygon
			(pts
				(arc
					(start 90.351356 -232.528364)
					(mid 89.698576 -232.528364)
					(end 90.351356 -232.528364)
				)
			)
		)
	)
	(zone
		(layers "B.Cu" "In4.Cu" "In6.Cu" "In11.Cu" "In13.Cu" "In15.Cu")
		(hatch none 0.5)
		(connect_pads
			(clearance 0)
		)
		(min_thickness 0.25)
		(keepout
			(tracks not_allowed)
			(vias allowed)
			(pads allowed)
			(copperpour not_allowed)
			(footprints allowed)
		)
		(placement
			(enabled no)
			(sheetname "")
		)
		(fill yes
			(thermal_gap 0.5)
			(thermal_bridge_width 0.5)
			(island_removal_mode 0)
		)
		(polygon
			(pts
				(arc
					(start 121.474738 -284.847538)
					(mid 120.821958 -284.847538)
					(end 121.474738 -284.847538)
				)
			)
		)
	)
	(zone
		(layers "B.Cu" "In4.Cu" "In6.Cu" "In11.Cu" "In13.Cu" "In15.Cu")
		(hatch none 0.5)
		(connect_pads
			(clearance 0)
		)
		(min_thickness 0.25)
		(keepout
			(tracks not_allowed)
			(vias allowed)
			(pads allowed)
			(copperpour not_allowed)
			(footprints allowed)
		)
		(placement
			(enabled no)
			(sheetname "")
		)
		(fill yes
			(thermal_gap 0.5)
			(thermal_bridge_width 0.5)
			(island_removal_mode 0)
		)
		(polygon
			(pts
				(arc
					(start 146.358864 -407.00452)
					(mid 145.655284 -407.00452)
					(end 146.358864 -407.00452)
				)
			)
		)
	)
	(zone
		(layers "B.Cu" "In4.Cu" "In6.Cu" "In11.Cu" "In13.Cu" "In15.Cu")
		(hatch none 0.5)
		(connect_pads
			(clearance 0)
		)
		(min_thickness 0.25)
		(keepout
			(tracks not_allowed)
			(vias allowed)
			(pads allowed)
			(copperpour not_allowed)
			(footprints allowed)
		)
		(placement
			(enabled no)
			(sheetname "")
		)
		(fill yes
			(thermal_gap 0.5)
			(thermal_bridge_width 0.5)
			(island_removal_mode 0)
		)
		(polygon
			(pts
				(arc
					(start 386.691124 -221.94774)
					(mid 386.038344 -221.94774)
					(end 386.691124 -221.94774)
				)
			)
		)
	)
	(zone
		(layers "B.Cu" "In4.Cu" "In6.Cu" "In11.Cu" "In13.Cu" "In15.Cu")
		(hatch none 0.5)
		(connect_pads
			(clearance 0)
		)
		(min_thickness 0.25)
		(keepout
			(tracks not_allowed)
			(vias allowed)
			(pads allowed)
			(copperpour not_allowed)
			(footprints allowed)
		)
		(placement
			(enabled no)
			(sheetname "")
		)
		(fill yes
			(thermal_gap 0.5)
			(thermal_bridge_width 0.5)
			(island_removal_mode 0)
		)
		(polygon
			(pts
				(arc
					(start 89.521284 -263.686544)
					(mid 88.868504 -263.686544)
					(end 89.521284 -263.686544)
				)
			)
		)
	)
	(zone
		(layers "B.Cu" "In4.Cu" "In6.Cu" "In11.Cu" "In13.Cu" "In15.Cu")
		(hatch none 0.5)
		(connect_pads
			(clearance 0)
		)
		(min_thickness 0.25)
		(keepout
			(tracks not_allowed)
			(vias allowed)
			(pads allowed)
			(copperpour not_allowed)
			(footprints allowed)
		)
		(placement
			(enabled no)
			(sheetname "")
		)
		(fill yes
			(thermal_gap 0.5)
			(thermal_bridge_width 0.5)
			(island_removal_mode 0)
		)
		(polygon
			(pts
				(arc
					(start 173.122336 -274.66671)
					(mid 172.469556 -274.66671)
					(end 173.122336 -274.66671)
				)
			)
		)
	)
	(zone
		(layers "B.Cu" "In4.Cu" "In6.Cu" "In11.Cu" "In13.Cu" "In15.Cu")
		(hatch none 0.5)
		(connect_pads
			(clearance 0)
		)
		(min_thickness 0.25)
		(keepout
			(tracks not_allowed)
			(vias allowed)
			(pads allowed)
			(copperpour not_allowed)
			(footprints allowed)
		)
		(placement
			(enabled no)
			(sheetname "")
		)
		(fill yes
			(thermal_gap 0.5)
			(thermal_bridge_width 0.5)
			(island_removal_mode 0)
		)
		(polygon
			(pts
				(arc
					(start 133.692138 -263.686544)
					(mid 133.039358 -263.686544)
					(end 133.692138 -263.686544)
				)
			)
		)
	)
	(zone
		(layers "B.Cu" "In4.Cu" "In6.Cu" "In11.Cu" "In13.Cu" "In15.Cu")
		(hatch none 0.5)
		(connect_pads
			(clearance 0)
		)
		(min_thickness 0.25)
		(keepout
			(tracks not_allowed)
			(vias allowed)
			(pads allowed)
			(copperpour not_allowed)
			(footprints allowed)
		)
		(placement
			(enabled no)
			(sheetname "")
		)
		(fill yes
			(thermal_gap 0.5)
			(thermal_bridge_width 0.5)
			(island_removal_mode 0)
		)
		(polygon
			(pts
				(arc
					(start 359.906824 -224.389442)
					(mid 359.254044 -224.389442)
					(end 359.906824 -224.389442)
				)
			)
		)
	)
	(zone
		(layers "B.Cu" "In4.Cu" "In6.Cu" "In11.Cu" "In13.Cu" "In15.Cu")
		(hatch none 0.5)
		(connect_pads
			(clearance 0)
		)
		(min_thickness 0.25)
		(keepout
			(tracks not_allowed)
			(vias allowed)
			(pads allowed)
			(copperpour not_allowed)
			(footprints allowed)
		)
		(placement
			(enabled no)
			(sheetname "")
		)
		(fill yes
			(thermal_gap 0.5)
			(thermal_bridge_width 0.5)
			(island_removal_mode 0)
		)
		(polygon
			(pts
				(arc
					(start 338.291424 -235.783882)
					(mid 337.638644 -235.783882)
					(end 338.291424 -235.783882)
				)
			)
		)
	)
	(zone
		(layers "B.Cu" "In4.Cu" "In6.Cu" "In11.Cu" "In13.Cu" "In15.Cu")
		(hatch none 0.5)
		(connect_pads
			(clearance 0)
		)
		(min_thickness 0.25)
		(keepout
			(tracks not_allowed)
			(vias allowed)
			(pads allowed)
			(copperpour not_allowed)
			(footprints allowed)
		)
		(placement
			(enabled no)
			(sheetname "")
		)
		(fill yes
			(thermal_gap 0.5)
			(thermal_bridge_width 0.5)
			(island_removal_mode 0)
		)
		(polygon
			(pts
				(arc
					(start 358.70007 -55.884572)
					(mid 357.99649 -55.884572)
					(end 358.70007 -55.884572)
				)
			)
		)
	)
	(zone
		(layers "B.Cu" "In4.Cu" "In6.Cu" "In11.Cu" "In13.Cu" "In15.Cu")
		(hatch none 0.5)
		(connect_pads
			(clearance 0)
		)
		(min_thickness 0.25)
		(keepout
			(tracks not_allowed)
			(vias allowed)
			(pads allowed)
			(copperpour not_allowed)
			(footprints allowed)
		)
		(placement
			(enabled no)
			(sheetname "")
		)
		(fill yes
			(thermal_gap 0.5)
			(thermal_bridge_width 0.5)
			(island_removal_mode 0)
		)
		(polygon
			(pts
				(arc
					(start 340.281006 -286.475424)
					(mid 339.628226 -286.475424)
					(end 340.281006 -286.475424)
				)
			)
		)
	)
	(zone
		(layers "B.Cu" "In4.Cu" "In6.Cu" "In11.Cu" "In13.Cu" "In15.Cu")
		(hatch none 0.5)
		(connect_pads
			(clearance 0)
		)
		(min_thickness 0.25)
		(keepout
			(tracks not_allowed)
			(vias allowed)
			(pads allowed)
			(copperpour not_allowed)
			(footprints allowed)
		)
		(placement
			(enabled no)
			(sheetname "")
		)
		(fill yes
			(thermal_gap 0.5)
			(thermal_bridge_width 0.5)
			(island_removal_mode 0)
		)
		(polygon
			(pts
				(arc
					(start 177.222404 -311.216548)
					(mid 176.569624 -311.216548)
					(end 177.222404 -311.216548)
				)
			)
		)
	)
	(zone
		(layers "B.Cu" "In4.Cu" "In6.Cu" "In11.Cu" "In13.Cu" "In15.Cu")
		(hatch none 0.5)
		(connect_pads
			(clearance 0)
		)
		(min_thickness 0.25)
		(keepout
			(tracks not_allowed)
			(vias allowed)
			(pads allowed)
			(copperpour not_allowed)
			(footprints allowed)
		)
		(placement
			(enabled no)
			(sheetname "")
		)
		(fill yes
			(thermal_gap 0.5)
			(thermal_bridge_width 0.5)
			(island_removal_mode 0)
		)
		(polygon
			(pts
				(arc
					(start 51.390804 -214.316564)
					(mid 50.738024 -214.316564)
					(end 51.390804 -214.316564)
				)
			)
		)
	)
	(zone
		(layers "B.Cu" "In4.Cu" "In6.Cu" "In11.Cu" "In13.Cu" "In15.Cu")
		(hatch none 0.5)
		(connect_pads
			(clearance 0)
		)
		(min_thickness 0.25)
		(keepout
			(tracks not_allowed)
			(vias allowed)
			(pads allowed)
			(copperpour not_allowed)
			(footprints allowed)
		)
		(placement
			(enabled no)
			(sheetname "")
		)
		(fill yes
			(thermal_gap 0.5)
			(thermal_bridge_width 0.5)
			(island_removal_mode 0)
		)
		(polygon
			(pts
				(arc
					(start 180.666136 -245.76659)
					(mid 180.013356 -245.76659)
					(end 180.666136 -245.76659)
				)
			)
		)
	)
	(zone
		(layers "B.Cu" "In4.Cu" "In6.Cu" "In11.Cu" "In13.Cu" "In15.Cu")
		(hatch none 0.5)
		(connect_pads
			(clearance 0)
		)
		(min_thickness 0.25)
		(keepout
			(tracks not_allowed)
			(vias allowed)
			(pads allowed)
			(copperpour not_allowed)
			(footprints allowed)
		)
		(placement
			(enabled no)
			(sheetname "")
		)
		(fill yes
			(thermal_gap 0.5)
			(thermal_bridge_width 0.5)
			(island_removal_mode 0)
		)
		(polygon
			(pts
				(arc
					(start 177.222404 -307.816758)
					(mid 176.569624 -307.816758)
					(end 177.222404 -307.816758)
				)
			)
		)
	)
	(zone
		(layers "B.Cu" "In4.Cu" "In6.Cu" "In11.Cu" "In13.Cu" "In15.Cu")
		(hatch none 0.5)
		(connect_pads
			(clearance 0)
		)
		(min_thickness 0.25)
		(keepout
			(tracks not_allowed)
			(vias allowed)
			(pads allowed)
			(copperpour not_allowed)
			(footprints allowed)
		)
		(placement
			(enabled no)
			(sheetname "")
		)
		(fill yes
			(thermal_gap 0.5)
			(thermal_bridge_width 0.5)
			(island_removal_mode 0)
		)
		(polygon
			(pts
				(arc
					(start 338.871052 -259.616956)
					(mid 338.218272 -259.616956)
					(end 338.871052 -259.616956)
				)
			)
		)
	)
	(zone
		(layers "B.Cu" "In4.Cu" "In6.Cu" "In11.Cu" "In13.Cu" "In15.Cu")
		(hatch none 0.5)
		(connect_pads
			(clearance 0)
		)
		(min_thickness 0.25)
		(keepout
			(tracks not_allowed)
			(vias allowed)
			(pads allowed)
			(copperpour not_allowed)
			(footprints allowed)
		)
		(placement
			(enabled no)
			(sheetname "")
		)
		(fill yes
			(thermal_gap 0.5)
			(thermal_bridge_width 0.5)
			(island_removal_mode 0)
		)
		(polygon
			(pts
				(arc
					(start 397.62684 -407.00452)
					(mid 396.92326 -407.00452)
					(end 397.62684 -407.00452)
				)
			)
		)
	)
	(zone
		(layers "B.Cu" "In4.Cu" "In6.Cu" "In11.Cu" "In13.Cu" "In15.Cu")
		(hatch none 0.5)
		(connect_pads
			(clearance 0)
		)
		(min_thickness 0.25)
		(keepout
			(tracks not_allowed)
			(vias allowed)
			(pads allowed)
			(copperpour not_allowed)
			(footprints allowed)
		)
		(placement
			(enabled no)
			(sheetname "")
		)
		(fill yes
			(thermal_gap 0.5)
			(thermal_bridge_width 0.5)
			(island_removal_mode 0)
		)
		(polygon
			(pts
				(arc
					(start 295.230804 -266.1666)
					(mid 294.578024 -266.1666)
					(end 295.230804 -266.1666)
				)
			)
		)
	)
	(zone
		(layers "B.Cu" "In4.Cu" "In6.Cu" "In11.Cu" "In13.Cu" "In15.Cu")
		(hatch none 0.5)
		(connect_pads
			(clearance 0)
		)
		(min_thickness 0.25)
		(keepout
			(tracks not_allowed)
			(vias allowed)
			(pads allowed)
			(copperpour not_allowed)
			(footprints allowed)
		)
		(placement
			(enabled no)
			(sheetname "")
		)
		(fill yes
			(thermal_gap 0.5)
			(thermal_bridge_width 0.5)
			(island_removal_mode 0)
		)
		(polygon
			(pts
				(arc
					(start 177.222404 -272.11655)
					(mid 176.569624 -272.11655)
					(end 177.222404 -272.11655)
				)
			)
		)
	)
	(zone
		(layers "B.Cu" "In4.Cu" "In6.Cu" "In11.Cu" "In13.Cu" "In15.Cu")
		(hatch none 0.5)
		(connect_pads
			(clearance 0)
		)
		(min_thickness 0.25)
		(keepout
			(tracks not_allowed)
			(vias allowed)
			(pads allowed)
			(copperpour not_allowed)
			(footprints allowed)
		)
		(placement
			(enabled no)
			(sheetname "")
		)
		(fill yes
			(thermal_gap 0.5)
			(thermal_bridge_width 0.5)
			(island_removal_mode 0)
		)
		(polygon
			(pts
				(arc
					(start 134.991856 -238.225584)
					(mid 134.339076 -238.225584)
					(end 134.991856 -238.225584)
				)
			)
		)
	)
	(zone
		(layers "B.Cu" "In4.Cu" "In6.Cu" "In11.Cu" "In13.Cu" "In15.Cu")
		(hatch none 0.5)
		(connect_pads
			(clearance 0)
		)
		(min_thickness 0.25)
		(keepout
			(tracks not_allowed)
			(vias allowed)
			(pads allowed)
			(copperpour not_allowed)
			(footprints allowed)
		)
		(placement
			(enabled no)
			(sheetname "")
		)
		(fill yes
			(thermal_gap 0.5)
			(thermal_bridge_width 0.5)
			(island_removal_mode 0)
		)
		(polygon
			(pts
				(arc
					(start 410.049472 -227.91674)
					(mid 409.396692 -227.91674)
					(end 410.049472 -227.91674)
				)
			)
		)
	)
	(zone
		(layers "B.Cu" "In4.Cu" "In6.Cu" "In11.Cu" "In13.Cu" "In15.Cu")
		(hatch none 0.5)
		(connect_pads
			(clearance 0)
		)
		(min_thickness 0.25)
		(keepout
			(tracks not_allowed)
			(vias allowed)
			(pads allowed)
			(copperpour not_allowed)
			(footprints allowed)
		)
		(placement
			(enabled no)
			(sheetname "")
		)
		(fill yes
			(thermal_gap 0.5)
			(thermal_bridge_width 0.5)
			(island_removal_mode 0)
		)
		(polygon
			(pts
				(arc
					(start 314.418472 -300.166786)
					(mid 313.765692 -300.166786)
					(end 314.418472 -300.166786)
				)
			)
		)
	)
	(zone
		(layers "B.Cu" "In4.Cu" "In6.Cu" "In11.Cu" "In13.Cu" "In15.Cu")
		(hatch none 0.5)
		(connect_pads
			(clearance 0)
		)
		(min_thickness 0.25)
		(keepout
			(tracks not_allowed)
			(vias allowed)
			(pads allowed)
			(copperpour not_allowed)
			(footprints allowed)
		)
		(placement
			(enabled no)
			(sheetname "")
		)
		(fill yes
			(thermal_gap 0.5)
			(thermal_bridge_width 0.5)
			(island_removal_mode 0)
		)
		(polygon
			(pts
				(arc
					(start 336.88147 -238.225584)
					(mid 336.22869 -238.225584)
					(end 336.88147 -238.225584)
				)
			)
		)
	)
	(zone
		(layers "B.Cu" "In4.Cu" "In6.Cu" "In11.Cu" "In13.Cu" "In15.Cu")
		(hatch none 0.5)
		(connect_pads
			(clearance 0)
		)
		(min_thickness 0.25)
		(keepout
			(tracks not_allowed)
			(vias allowed)
			(pads allowed)
			(copperpour not_allowed)
			(footprints allowed)
		)
		(placement
			(enabled no)
			(sheetname "")
		)
		(fill yes
			(thermal_gap 0.5)
			(thermal_bridge_width 0.5)
			(island_removal_mode 0)
		)
		(polygon
			(pts
				(arc
					(start 383.871724 -239.853216)
					(mid 383.218944 -239.853216)
					(end 383.871724 -239.853216)
				)
			)
		)
	)
	(zone
		(layers "B.Cu" "In4.Cu" "In6.Cu" "In11.Cu" "In13.Cu" "In15.Cu")
		(hatch none 0.5)
		(connect_pads
			(clearance 0)
		)
		(min_thickness 0.25)
		(keepout
			(tracks not_allowed)
			(vias allowed)
			(pads allowed)
			(copperpour not_allowed)
			(footprints allowed)
		)
		(placement
			(enabled no)
			(sheetname "")
		)
		(fill yes
			(thermal_gap 0.5)
			(thermal_bridge_width 0.5)
			(island_removal_mode 0)
		)
		(polygon
			(pts
				(arc
					(start 405.949404 -301.01667)
					(mid 405.296624 -301.01667)
					(end 405.949404 -301.01667)
				)
			)
		)
	)
	(zone
		(layers "B.Cu" "In4.Cu" "In6.Cu" "In11.Cu" "In13.Cu" "In15.Cu")
		(hatch none 0.5)
		(connect_pads
			(clearance 0)
		)
		(min_thickness 0.25)
		(keepout
			(tracks not_allowed)
			(vias allowed)
			(pads allowed)
			(copperpour not_allowed)
			(footprints allowed)
		)
		(placement
			(enabled no)
			(sheetname "")
		)
		(fill yes
			(thermal_gap 0.5)
			(thermal_bridge_width 0.5)
			(island_removal_mode 0)
		)
		(polygon
			(pts
				(arc
					(start 405.949404 -302.716692)
					(mid 405.296624 -302.716692)
					(end 405.949404 -302.716692)
				)
			)
		)
	)
	(zone
		(layers "B.Cu" "In4.Cu" "In6.Cu" "In11.Cu" "In13.Cu" "In15.Cu")
		(hatch none 0.5)
		(connect_pads
			(clearance 0)
		)
		(min_thickness 0.25)
		(keepout
			(tracks not_allowed)
			(vias allowed)
			(pads allowed)
			(copperpour not_allowed)
			(footprints allowed)
		)
		(placement
			(enabled no)
			(sheetname "")
		)
		(fill yes
			(thermal_gap 0.5)
			(thermal_bridge_width 0.5)
			(island_removal_mode 0)
		)
		(polygon
			(pts
				(arc
					(start 127.979424 -407.00452)
					(mid 127.275844 -407.00452)
					(end 127.979424 -407.00452)
				)
			)
		)
	)
	(zone
		(layers "B.Cu" "In4.Cu" "In6.Cu" "In11.Cu" "In13.Cu" "In15.Cu")
		(hatch none 0.5)
		(connect_pads
			(clearance 0)
		)
		(min_thickness 0.25)
		(keepout
			(tracks not_allowed)
			(vias allowed)
			(pads allowed)
			(copperpour not_allowed)
			(footprints allowed)
		)
		(placement
			(enabled no)
			(sheetname "")
		)
		(fill yes
			(thermal_gap 0.5)
			(thermal_bridge_width 0.5)
			(island_removal_mode 0)
		)
		(polygon
			(pts
				(arc
					(start 173.122336 -218.566746)
					(mid 172.469556 -218.566746)
					(end 173.122336 -218.566746)
				)
			)
		)
	)
	(zone
		(layers "B.Cu" "In4.Cu" "In6.Cu" "In11.Cu" "In13.Cu" "In15.Cu")
		(hatch none 0.5)
		(connect_pads
			(clearance 0)
		)
		(min_thickness 0.25)
		(keepout
			(tracks not_allowed)
			(vias allowed)
			(pads allowed)
			(copperpour not_allowed)
			(footprints allowed)
		)
		(placement
			(enabled no)
			(sheetname "")
		)
		(fill yes
			(thermal_gap 0.5)
			(thermal_bridge_width 0.5)
			(island_removal_mode 0)
		)
		(polygon
			(pts
				(arc
					(start 106.797602 -225.203258)
					(mid 106.144822 -225.203258)
					(end 106.797602 -225.203258)
				)
			)
		)
	)
	(zone
		(layers "B.Cu" "In4.Cu" "In6.Cu" "In11.Cu" "In13.Cu" "In15.Cu")
		(hatch none 0.5)
		(connect_pads
			(clearance 0)
		)
		(min_thickness 0.25)
		(keepout
			(tracks not_allowed)
			(vias allowed)
			(pads allowed)
			(copperpour not_allowed)
			(footprints allowed)
		)
		(placement
			(enabled no)
			(sheetname "")
		)
		(fill yes
			(thermal_gap 0.5)
			(thermal_bridge_width 0.5)
			(island_removal_mode 0)
		)
		(polygon
			(pts
				(arc
					(start 47.290736 -210.066636)
					(mid 46.637956 -210.066636)
					(end 47.290736 -210.066636)
				)
			)
		)
	)
	(zone
		(layers "B.Cu" "In4.Cu" "In6.Cu" "In11.Cu" "In13.Cu" "In15.Cu")
		(hatch none 0.5)
		(connect_pads
			(clearance 0)
		)
		(min_thickness 0.25)
		(keepout
			(tracks not_allowed)
			(vias allowed)
			(pads allowed)
			(copperpour not_allowed)
			(footprints allowed)
		)
		(placement
			(enabled no)
			(sheetname "")
		)
		(fill yes
			(thermal_gap 0.5)
			(thermal_bridge_width 0.5)
			(island_removal_mode 0)
		)
		(polygon
			(pts
				(arc
					(start 405.949404 -306.96662)
					(mid 405.296624 -306.96662)
					(end 405.949404 -306.96662)
				)
			)
		)
	)
	(zone
		(layers "B.Cu" "In4.Cu" "In6.Cu" "In11.Cu" "In13.Cu" "In15.Cu")
		(hatch none 0.5)
		(connect_pads
			(clearance 0)
		)
		(min_thickness 0.25)
		(keepout
			(tracks not_allowed)
			(vias allowed)
			(pads allowed)
			(copperpour not_allowed)
			(footprints allowed)
		)
		(placement
			(enabled no)
			(sheetname "")
		)
		(fill yes
			(thermal_gap 0.5)
			(thermal_bridge_width 0.5)
			(island_removal_mode 0)
		)
		(polygon
			(pts
				(arc
					(start 138.751056 -221.94774)
					(mid 138.098276 -221.94774)
					(end 138.751056 -221.94774)
				)
			)
		)
	)
	(zone
		(layers "B.Cu" "In4.Cu" "In6.Cu" "In11.Cu" "In13.Cu" "In15.Cu")
		(hatch none 0.5)
		(connect_pads
			(clearance 0)
		)
		(min_thickness 0.25)
		(keepout
			(tracks not_allowed)
			(vias allowed)
			(pads allowed)
			(copperpour not_allowed)
			(footprints allowed)
		)
		(placement
			(enabled no)
			(sheetname "")
		)
		(fill yes
			(thermal_gap 0.5)
			(thermal_bridge_width 0.5)
			(island_removal_mode 0)
		)
		(polygon
			(pts
				(arc
					(start 173.046136 -266.1666)
					(mid 172.393356 -266.1666)
					(end 173.046136 -266.1666)
				)
			)
		)
	)
	(zone
		(layers "B.Cu" "In4.Cu" "In6.Cu" "In11.Cu" "In13.Cu" "In15.Cu")
		(hatch none 0.5)
		(connect_pads
			(clearance 0)
		)
		(min_thickness 0.25)
		(keepout
			(tracks not_allowed)
			(vias allowed)
			(pads allowed)
			(copperpour not_allowed)
			(footprints allowed)
		)
		(placement
			(enabled no)
			(sheetname "")
		)
		(fill yes
			(thermal_gap 0.5)
			(thermal_bridge_width 0.5)
			(island_removal_mode 0)
		)
		(polygon
			(pts
				(arc
					(start 118.545356 -224.389442)
					(mid 117.892576 -224.389442)
					(end 118.545356 -224.389442)
				)
			)
		)
	)
	(zone
		(layers "B.Cu" "In4.Cu" "In6.Cu" "In11.Cu" "In13.Cu" "In15.Cu")
		(hatch none 0.5)
		(connect_pads
			(clearance 0)
		)
		(min_thickness 0.25)
		(keepout
			(tracks not_allowed)
			(vias allowed)
			(pads allowed)
			(copperpour not_allowed)
			(footprints allowed)
		)
		(placement
			(enabled no)
			(sheetname "")
		)
		(fill yes
			(thermal_gap 0.5)
			(thermal_bridge_width 0.5)
			(island_removal_mode 0)
		)
		(polygon
			(pts
				(arc
					(start 173.122336 -252.566678)
					(mid 172.469556 -252.566678)
					(end 173.122336 -252.566678)
				)
			)
		)
	)
	(zone
		(layers "B.Cu" "In4.Cu" "In6.Cu" "In11.Cu" "In13.Cu" "In15.Cu")
		(hatch none 0.5)
		(connect_pads
			(clearance 0)
		)
		(min_thickness 0.25)
		(keepout
			(tracks not_allowed)
			(vias allowed)
			(pads allowed)
			(copperpour not_allowed)
			(footprints allowed)
		)
		(placement
			(enabled no)
			(sheetname "")
		)
		(fill yes
			(thermal_gap 0.5)
			(thermal_bridge_width 0.5)
			(island_removal_mode 0)
		)
		(polygon
			(pts
				(arc
					(start 18.679668 -19.13636)
					(mid 17.976088 -19.13636)
					(end 18.679668 -19.13636)
				)
			)
		)
	)
	(zone
		(layers "B.Cu" "In4.Cu" "In6.Cu" "In11.Cu" "In13.Cu" "In15.Cu")
		(hatch none 0.5)
		(connect_pads
			(clearance 0)
		)
		(min_thickness 0.25)
		(keepout
			(tracks not_allowed)
			(vias allowed)
			(pads allowed)
			(copperpour not_allowed)
			(footprints allowed)
		)
		(placement
			(enabled no)
			(sheetname "")
		)
		(fill yes
			(thermal_gap 0.5)
			(thermal_bridge_width 0.5)
			(island_removal_mode 0)
		)
		(polygon
			(pts
				(arc
					(start 89.411556 -245.55069)
					(mid 88.758776 -245.55069)
					(end 89.411556 -245.55069)
				)
			)
		)
	)
	(zone
		(layers "B.Cu" "In4.Cu" "In6.Cu" "In11.Cu" "In13.Cu" "In15.Cu")
		(hatch none 0.5)
		(connect_pads
			(clearance 0)
		)
		(min_thickness 0.25)
		(keepout
			(tracks not_allowed)
			(vias allowed)
			(pads allowed)
			(copperpour not_allowed)
			(footprints allowed)
		)
		(placement
			(enabled no)
			(sheetname "")
		)
		(fill yes
			(thermal_gap 0.5)
			(thermal_bridge_width 0.5)
			(island_removal_mode 0)
		)
		(polygon
			(pts
				(arc
					(start 425.162472 -206.666592)
					(mid 424.509692 -206.666592)
					(end 425.162472 -206.666592)
				)
			)
		)
	)
	(zone
		(layers "B.Cu" "In4.Cu" "In6.Cu" "In11.Cu" "In13.Cu" "In15.Cu")
		(hatch none 0.5)
		(connect_pads
			(clearance 0)
		)
		(min_thickness 0.25)
		(keepout
			(tracks not_allowed)
			(vias allowed)
			(pads allowed)
			(copperpour not_allowed)
			(footprints allowed)
		)
		(placement
			(enabled no)
			(sheetname "")
		)
		(fill yes
			(thermal_gap 0.5)
			(thermal_bridge_width 0.5)
			(island_removal_mode 0)
		)
		(polygon
			(pts
				(arc
					(start 295.230804 -215.166702)
					(mid 294.578024 -215.166702)
					(end 295.230804 -215.166702)
				)
			)
		)
	)
	(zone
		(layers "B.Cu" "In4.Cu" "In6.Cu" "In11.Cu" "In13.Cu" "In15.Cu")
		(hatch none 0.5)
		(connect_pads
			(clearance 0)
		)
		(min_thickness 0.25)
		(keepout
			(tracks not_allowed)
			(vias allowed)
			(pads allowed)
			(copperpour not_allowed)
			(footprints allowed)
		)
		(placement
			(enabled no)
			(sheetname "")
		)
		(fill yes
			(thermal_gap 0.5)
			(thermal_bridge_width 0.5)
			(island_removal_mode 0)
		)
		(polygon
			(pts
				(arc
					(start 337.351624 -226.017328)
					(mid 336.698844 -226.017328)
					(end 337.351624 -226.017328)
				)
			)
		)
	)
	(zone
		(layers "B.Cu" "In4.Cu" "In6.Cu" "In11.Cu" "In13.Cu" "In15.Cu")
		(hatch none 0.5)
		(connect_pads
			(clearance 0)
		)
		(min_thickness 0.25)
		(keepout
			(tracks not_allowed)
			(vias allowed)
			(pads allowed)
			(copperpour not_allowed)
			(footprints allowed)
		)
		(placement
			(enabled no)
			(sheetname "")
		)
		(fill yes
			(thermal_gap 0.5)
			(thermal_bridge_width 0.5)
			(island_removal_mode 0)
		)
		(polygon
			(pts
				(arc
					(start 65.857628 -407.00452)
					(mid 65.154048 -407.00452)
					(end 65.857628 -407.00452)
				)
			)
		)
	)
	(zone
		(layers "B.Cu" "In4.Cu" "In6.Cu" "In11.Cu" "In13.Cu" "In15.Cu")
		(hatch none 0.5)
		(connect_pads
			(clearance 0)
		)
		(min_thickness 0.25)
		(keepout
			(tracks not_allowed)
			(vias allowed)
			(pads allowed)
			(copperpour not_allowed)
			(footprints allowed)
		)
		(placement
			(enabled no)
			(sheetname "")
		)
		(fill yes
			(thermal_gap 0.5)
			(thermal_bridge_width 0.5)
			(island_removal_mode 0)
		)
		(polygon
			(pts
				(arc
					(start 124.916184 -407.00452)
					(mid 124.212604 -407.00452)
					(end 124.916184 -407.00452)
				)
			)
		)
	)
	(zone
		(layers "B.Cu" "In4.Cu" "In6.Cu" "In11.Cu" "In13.Cu" "In15.Cu")
		(hatch none 0.5)
		(connect_pads
			(clearance 0)
		)
		(min_thickness 0.25)
		(keepout
			(tracks not_allowed)
			(vias allowed)
			(pads allowed)
			(copperpour not_allowed)
			(footprints allowed)
		)
		(placement
			(enabled no)
			(sheetname "")
		)
		(fill yes
			(thermal_gap 0.5)
			(thermal_bridge_width 0.5)
			(island_removal_mode 0)
		)
		(polygon
			(pts
				(arc
					(start 405.949404 -232.166668)
					(mid 405.296624 -232.166668)
					(end 405.949404 -232.166668)
				)
			)
		)
	)
	(zone
		(layers "B.Cu" "In4.Cu" "In6.Cu" "In11.Cu" "In13.Cu" "In15.Cu")
		(hatch none 0.5)
		(connect_pads
			(clearance 0)
		)
		(min_thickness 0.25)
		(keepout
			(tracks not_allowed)
			(vias allowed)
			(pads allowed)
			(copperpour not_allowed)
			(footprints allowed)
		)
		(placement
			(enabled no)
			(sheetname "")
		)
		(fill yes
			(thermal_gap 0.5)
			(thermal_bridge_width 0.5)
			(island_removal_mode 0)
		)
		(polygon
			(pts
				(arc
					(start 135.931656 -230.086662)
					(mid 135.278876 -230.086662)
					(end 135.931656 -230.086662)
				)
			)
		)
	)
	(zone
		(layers "B.Cu" "In4.Cu" "In6.Cu" "In11.Cu" "In13.Cu" "In15.Cu")
		(hatch none 0.5)
		(connect_pads
			(clearance 0)
		)
		(min_thickness 0.25)
		(keepout
			(tracks not_allowed)
			(vias allowed)
			(pads allowed)
			(copperpour not_allowed)
			(footprints allowed)
		)
		(placement
			(enabled no)
			(sheetname "")
		)
		(fill yes
			(thermal_gap 0.5)
			(thermal_bridge_width 0.5)
			(island_removal_mode 0)
		)
		(polygon
			(pts
				(arc
					(start 381.522224 -235.783882)
					(mid 380.869444 -235.783882)
					(end 381.522224 -235.783882)
				)
			)
		)
	)
	(zone
		(layers "B.Cu" "In4.Cu" "In6.Cu" "In11.Cu" "In13.Cu" "In15.Cu")
		(hatch none 0.5)
		(connect_pads
			(clearance 0)
		)
		(min_thickness 0.25)
		(keepout
			(tracks not_allowed)
			(vias allowed)
			(pads allowed)
			(copperpour not_allowed)
			(footprints allowed)
		)
		(placement
			(enabled no)
			(sheetname "")
		)
		(fill yes
			(thermal_gap 0.5)
			(thermal_bridge_width 0.5)
			(island_removal_mode 0)
		)
		(polygon
			(pts
				(arc
					(start 425.162472 -251.716794)
					(mid 424.509692 -251.716794)
					(end 425.162472 -251.716794)
				)
			)
		)
	)
	(zone
		(layers "B.Cu" "In4.Cu" "In6.Cu" "In11.Cu" "In13.Cu" "In15.Cu")
		(hatch none 0.5)
		(connect_pads
			(clearance 0)
		)
		(min_thickness 0.25)
		(keepout
			(tracks not_allowed)
			(vias allowed)
			(pads allowed)
			(copperpour not_allowed)
			(footprints allowed)
		)
		(placement
			(enabled no)
			(sheetname "")
		)
		(fill yes
			(thermal_gap 0.5)
			(thermal_bridge_width 0.5)
			(island_removal_mode 0)
		)
		(polygon
			(pts
				(arc
					(start 360.37647 -225.203258)
					(mid 359.72369 -225.203258)
					(end 360.37647 -225.203258)
				)
			)
		)
	)
	(zone
		(layers "B.Cu" "In4.Cu" "In6.Cu" "In11.Cu" "In13.Cu" "In15.Cu")
		(hatch none 0.5)
		(connect_pads
			(clearance 0)
		)
		(min_thickness 0.25)
		(keepout
			(tracks not_allowed)
			(vias allowed)
			(pads allowed)
			(copperpour not_allowed)
			(footprints allowed)
		)
		(placement
			(enabled no)
			(sheetname "")
		)
		(fill yes
			(thermal_gap 0.5)
			(thermal_bridge_width 0.5)
			(island_removal_mode 0)
		)
		(polygon
			(pts
				(arc
					(start 158.009336 -228.766624)
					(mid 157.356556 -228.766624)
					(end 158.009336 -228.766624)
				)
			)
		)
	)
	(zone
		(layers "B.Cu" "In4.Cu" "In6.Cu" "In11.Cu" "In13.Cu" "In15.Cu")
		(hatch none 0.5)
		(connect_pads
			(clearance 0)
		)
		(min_thickness 0.25)
		(keepout
			(tracks not_allowed)
			(vias allowed)
			(pads allowed)
			(copperpour not_allowed)
			(footprints allowed)
		)
		(placement
			(enabled no)
			(sheetname "")
		)
		(fill yes
			(thermal_gap 0.5)
			(thermal_bridge_width 0.5)
			(island_removal_mode 0)
		)
		(polygon
			(pts
				(arc
					(start 134.991856 -236.597952)
					(mid 134.339076 -236.597952)
					(end 134.991856 -236.597952)
				)
			)
		)
	)
	(zone
		(layers "B.Cu" "In4.Cu" "In6.Cu" "In11.Cu" "In13.Cu" "In15.Cu")
		(hatch none 0.5)
		(connect_pads
			(clearance 0)
		)
		(min_thickness 0.25)
		(keepout
			(tracks not_allowed)
			(vias allowed)
			(pads allowed)
			(copperpour not_allowed)
			(footprints allowed)
		)
		(placement
			(enabled no)
			(sheetname "")
		)
		(fill yes
			(thermal_gap 0.5)
			(thermal_bridge_width 0.5)
			(island_removal_mode 0)
		)
		(polygon
			(pts
				(arc
					(start 385.281424 -224.389442)
					(mid 384.628644 -224.389442)
					(end 385.281424 -224.389442)
				)
			)
		)
	)
	(zone
		(layers "B.Cu" "In4.Cu" "In6.Cu" "In11.Cu" "In13.Cu" "In15.Cu")
		(hatch none 0.5)
		(connect_pads
			(clearance 0)
		)
		(min_thickness 0.25)
		(keepout
			(tracks not_allowed)
			(vias allowed)
			(pads allowed)
			(copperpour not_allowed)
			(footprints allowed)
		)
		(placement
			(enabled no)
			(sheetname "")
		)
		(fill yes
			(thermal_gap 0.5)
			(thermal_bridge_width 0.5)
			(island_removal_mode 0)
		)
		(polygon
			(pts
				(arc
					(start 93.640402 -249.620024)
					(mid 92.987622 -249.620024)
					(end 93.640402 -249.620024)
				)
			)
		)
	)
	(zone
		(layers "B.Cu" "In4.Cu" "In6.Cu" "In11.Cu" "In13.Cu" "In15.Cu")
		(hatch none 0.5)
		(connect_pads
			(clearance 0)
		)
		(min_thickness 0.25)
		(keepout
			(tracks not_allowed)
			(vias allowed)
			(pads allowed)
			(copperpour not_allowed)
			(footprints allowed)
		)
		(placement
			(enabled no)
			(sheetname "")
		)
		(fill yes
			(thermal_gap 0.5)
			(thermal_bridge_width 0.5)
			(island_removal_mode 0)
		)
		(polygon
			(pts
				(arc
					(start 381.522224 -240.667286)
					(mid 380.869444 -240.667286)
					(end 381.522224 -240.667286)
				)
			)
		)
	)
	(zone
		(layers "B.Cu" "In4.Cu" "In6.Cu" "In11.Cu" "In13.Cu" "In15.Cu")
		(hatch none 0.5)
		(connect_pads
			(clearance 0)
		)
		(min_thickness 0.25)
		(keepout
			(tracks not_allowed)
			(vias allowed)
			(pads allowed)
			(copperpour not_allowed)
			(footprints allowed)
		)
		(placement
			(enabled no)
			(sheetname "")
		)
		(fill yes
			(thermal_gap 0.5)
			(thermal_bridge_width 0.5)
			(island_removal_mode 0)
		)
		(polygon
			(pts
				(arc
					(start 299.330872 -206.666592)
					(mid 298.678092 -206.666592)
					(end 299.330872 -206.666592)
				)
			)
		)
	)
	(zone
		(layers "B.Cu" "In4.Cu" "In6.Cu" "In11.Cu" "In13.Cu" "In15.Cu")
		(hatch none 0.5)
		(connect_pads
			(clearance 0)
		)
		(min_thickness 0.25)
		(keepout
			(tracks not_allowed)
			(vias allowed)
			(pads allowed)
			(copperpour not_allowed)
			(footprints allowed)
		)
		(placement
			(enabled no)
			(sheetname "")
		)
		(fill yes
			(thermal_gap 0.5)
			(thermal_bridge_width 0.5)
			(island_removal_mode 0)
		)
		(polygon
			(pts
				(arc
					(start 299.356272 -293.366952)
					(mid 298.703492 -293.366952)
					(end 299.356272 -293.366952)
				)
			)
		)
	)
	(zone
		(layers "B.Cu" "In4.Cu" "In6.Cu" "In11.Cu" "In13.Cu" "In15.Cu")
		(hatch none 0.5)
		(connect_pads
			(clearance 0)
		)
		(min_thickness 0.25)
		(keepout
			(tracks not_allowed)
			(vias allowed)
			(pads allowed)
			(copperpour not_allowed)
			(footprints allowed)
		)
		(placement
			(enabled no)
			(sheetname "")
		)
		(fill yes
			(thermal_gap 0.5)
			(thermal_bridge_width 0.5)
			(island_removal_mode 0)
		)
		(polygon
			(pts
				(arc
					(start 371.764052 -285.661354)
					(mid 371.111272 -285.661354)
					(end 371.764052 -285.661354)
				)
			)
		)
	)
	(zone
		(layers "B.Cu" "In4.Cu" "In6.Cu" "In11.Cu" "In13.Cu" "In15.Cu")
		(hatch none 0.5)
		(connect_pads
			(clearance 0)
		)
		(min_thickness 0.25)
		(keepout
			(tracks not_allowed)
			(vias allowed)
			(pads allowed)
			(copperpour not_allowed)
			(footprints allowed)
		)
		(placement
			(enabled no)
			(sheetname "")
		)
		(fill yes
			(thermal_gap 0.5)
			(thermal_bridge_width 0.5)
			(island_removal_mode 0)
		)
		(polygon
			(pts
				(arc
					(start 42.201084 -19.13636)
					(mid 41.497504 -19.13636)
					(end 42.201084 -19.13636)
				)
			)
		)
	)
	(zone
		(layers "B.Cu" "In4.Cu" "In6.Cu" "In11.Cu" "In13.Cu" "In15.Cu")
		(hatch none 0.5)
		(connect_pads
			(clearance 0)
		)
		(min_thickness 0.25)
		(keepout
			(tracks not_allowed)
			(vias allowed)
			(pads allowed)
			(copperpour not_allowed)
			(footprints allowed)
		)
		(placement
			(enabled no)
			(sheetname "")
		)
		(fill yes
			(thermal_gap 0.5)
			(thermal_bridge_width 0.5)
			(island_removal_mode 0)
		)
		(polygon
			(pts
				(arc
					(start 91.291156 -242.294918)
					(mid 90.638376 -242.294918)
					(end 91.291156 -242.294918)
				)
			)
		)
	)
	(zone
		(layers "B.Cu" "In4.Cu" "In6.Cu" "In11.Cu" "In13.Cu" "In15.Cu")
		(hatch none 0.5)
		(connect_pads
			(clearance 0)
		)
		(min_thickness 0.25)
		(keepout
			(tracks not_allowed)
			(vias allowed)
			(pads allowed)
			(copperpour not_allowed)
			(footprints allowed)
		)
		(placement
			(enabled no)
			(sheetname "")
		)
		(fill yes
			(thermal_gap 0.5)
			(thermal_bridge_width 0.5)
			(island_removal_mode 0)
		)
		(polygon
			(pts
				(arc
					(start 362.726224 -224.389442)
					(mid 362.073444 -224.389442)
					(end 362.726224 -224.389442)
				)
			)
		)
	)
	(zone
		(layers "B.Cu" "In4.Cu" "In6.Cu" "In11.Cu" "In13.Cu" "In15.Cu")
		(hatch none 0.5)
		(connect_pads
			(clearance 0)
		)
		(min_thickness 0.25)
		(keepout
			(tracks not_allowed)
			(vias allowed)
			(pads allowed)
			(copperpour not_allowed)
			(footprints allowed)
		)
		(placement
			(enabled no)
			(sheetname "")
		)
		(fill yes
			(thermal_gap 0.5)
			(thermal_bridge_width 0.5)
			(island_removal_mode 0)
		)
		(polygon
			(pts
				(arc
					(start 299.330872 -208.366614)
					(mid 298.678092 -208.366614)
					(end 299.330872 -208.366614)
				)
			)
		)
	)
	(zone
		(layers "B.Cu" "In4.Cu" "In6.Cu" "In11.Cu" "In13.Cu" "In15.Cu")
		(hatch none 0.5)
		(connect_pads
			(clearance 0)
		)
		(min_thickness 0.25)
		(keepout
			(tracks not_allowed)
			(vias allowed)
			(pads allowed)
			(copperpour not_allowed)
			(footprints allowed)
		)
		(placement
			(enabled no)
			(sheetname "")
		)
		(fill yes
			(thermal_gap 0.5)
			(thermal_bridge_width 0.5)
			(island_removal_mode 0)
		)
		(polygon
			(pts
				(arc
					(start 383.041652 -261.244842)
					(mid 382.388872 -261.244842)
					(end 383.041652 -261.244842)
				)
			)
		)
	)
	(zone
		(layers "B.Cu" "In4.Cu" "In6.Cu" "In11.Cu" "In13.Cu" "In15.Cu")
		(hatch none 0.5)
		(connect_pads
			(clearance 0)
		)
		(min_thickness 0.25)
		(keepout
			(tracks not_allowed)
			(vias allowed)
			(pads allowed)
			(copperpour not_allowed)
			(footprints allowed)
		)
		(placement
			(enabled no)
			(sheetname "")
		)
		(fill yes
			(thermal_gap 0.5)
			(thermal_bridge_width 0.5)
			(island_removal_mode 0)
		)
		(polygon
			(pts
				(arc
					(start 44.995084 -17.61236)
					(mid 44.291504 -17.61236)
					(end 44.995084 -17.61236)
				)
			)
		)
	)
	(zone
		(layers "B.Cu" "In4.Cu" "In6.Cu" "In11.Cu" "In13.Cu" "In15.Cu")
		(hatch none 0.5)
		(connect_pads
			(clearance 0)
		)
		(min_thickness 0.25)
		(keepout
			(tracks not_allowed)
			(vias allowed)
			(pads allowed)
			(copperpour not_allowed)
			(footprints allowed)
		)
		(placement
			(enabled no)
			(sheetname "")
		)
		(fill yes
			(thermal_gap 0.5)
			(thermal_bridge_width 0.5)
			(island_removal_mode 0)
		)
		(polygon
			(pts
				(arc
					(start 425.162472 -237.266734)
					(mid 424.509692 -237.266734)
					(end 425.162472 -237.266734)
				)
			)
		)
	)
	(zone
		(layers "B.Cu" "In4.Cu" "In6.Cu" "In11.Cu" "In13.Cu" "In15.Cu")
		(hatch none 0.5)
		(connect_pads
			(clearance 0)
		)
		(min_thickness 0.25)
		(keepout
			(tracks not_allowed)
			(vias allowed)
			(pads allowed)
			(copperpour not_allowed)
			(footprints allowed)
		)
		(placement
			(enabled no)
			(sheetname "")
		)
		(fill yes
			(thermal_gap 0.5)
			(thermal_bridge_width 0.5)
			(island_removal_mode 0)
		)
		(polygon
			(pts
				(arc
					(start 382.101852 -267.755878)
					(mid 381.449072 -267.755878)
					(end 382.101852 -267.755878)
				)
			)
		)
	)
	(zone
		(layers "B.Cu" "In4.Cu" "In6.Cu" "In11.Cu" "In13.Cu" "In15.Cu")
		(hatch none 0.5)
		(connect_pads
			(clearance 0)
		)
		(min_thickness 0.25)
		(keepout
			(tracks not_allowed)
			(vias allowed)
			(pads allowed)
			(copperpour not_allowed)
			(footprints allowed)
		)
		(placement
			(enabled no)
			(sheetname "")
		)
		(fill yes
			(thermal_gap 0.5)
			(thermal_bridge_width 0.5)
			(island_removal_mode 0)
		)
		(polygon
			(pts
				(arc
					(start 416.86988 -407.00452)
					(mid 416.1663 -407.00452)
					(end 416.86988 -407.00452)
				)
			)
		)
	)
	(zone
		(layers "B.Cu" "In4.Cu" "In6.Cu" "In11.Cu" "In13.Cu" "In15.Cu")
		(hatch none 0.5)
		(connect_pads
			(clearance 0)
		)
		(min_thickness 0.25)
		(keepout
			(tracks not_allowed)
			(vias allowed)
			(pads allowed)
			(copperpour not_allowed)
			(footprints allowed)
		)
		(placement
			(enabled no)
			(sheetname "")
		)
		(fill yes
			(thermal_gap 0.5)
			(thermal_bridge_width 0.5)
			(island_removal_mode 0)
		)
		(polygon
			(pts
				(arc
					(start 131.042664 -407.00452)
					(mid 130.339084 -407.00452)
					(end 131.042664 -407.00452)
				)
			)
		)
	)
	(zone
		(layers "B.Cu" "In4.Cu" "In6.Cu" "In11.Cu" "In13.Cu" "In15.Cu")
		(hatch none 0.5)
		(connect_pads
			(clearance 0)
		)
		(min_thickness 0.25)
		(keepout
			(tracks not_allowed)
			(vias allowed)
			(pads allowed)
			(copperpour not_allowed)
			(footprints allowed)
		)
		(placement
			(enabled no)
			(sheetname "")
		)
		(fill yes
			(thermal_gap 0.5)
			(thermal_bridge_width 0.5)
			(island_removal_mode 0)
		)
		(polygon
			(pts
				(arc
					(start 134.161784 -267.755878)
					(mid 133.509004 -267.755878)
					(end 134.161784 -267.755878)
				)
			)
		)
	)
	(zone
		(layers "B.Cu" "In4.Cu" "In6.Cu" "In11.Cu" "In13.Cu" "In15.Cu")
		(hatch none 0.5)
		(connect_pads
			(clearance 0)
		)
		(min_thickness 0.25)
		(keepout
			(tracks not_allowed)
			(vias allowed)
			(pads allowed)
			(copperpour not_allowed)
			(footprints allowed)
		)
		(placement
			(enabled no)
			(sheetname "")
		)
		(fill yes
			(thermal_gap 0.5)
			(thermal_bridge_width 0.5)
			(island_removal_mode 0)
		)
		(polygon
			(pts
				(arc
					(start 361.31627 -223.575626)
					(mid 360.66349 -223.575626)
					(end 361.31627 -223.575626)
				)
			)
		)
	)
	(zone
		(layers "B.Cu" "In4.Cu" "In6.Cu" "In11.Cu" "In13.Cu" "In15.Cu")
		(hatch none 0.5)
		(connect_pads
			(clearance 0)
		)
		(min_thickness 0.25)
		(keepout
			(tracks not_allowed)
			(vias allowed)
			(pads allowed)
			(copperpour not_allowed)
			(footprints allowed)
		)
		(placement
			(enabled no)
			(sheetname "")
		)
		(fill yes
			(thermal_gap 0.5)
			(thermal_bridge_width 0.5)
			(island_removal_mode 0)
		)
		(polygon
			(pts
				(arc
					(start 164.738304 -407.00452)
					(mid 164.034724 -407.00452)
					(end 164.738304 -407.00452)
				)
			)
		)
	)
	(zone
		(layers "B.Cu" "In4.Cu" "In6.Cu" "In11.Cu" "In13.Cu" "In15.Cu")
		(hatch none 0.5)
		(connect_pads
			(clearance 0)
		)
		(min_thickness 0.25)
		(keepout
			(tracks not_allowed)
			(vias allowed)
			(pads allowed)
			(copperpour not_allowed)
			(footprints allowed)
		)
		(placement
			(enabled no)
			(sheetname "")
		)
		(fill yes
			(thermal_gap 0.5)
			(thermal_bridge_width 0.5)
			(island_removal_mode 0)
		)
		(polygon
			(pts
				(arc
					(start 51.390804 -208.366614)
					(mid 50.738024 -208.366614)
					(end 51.390804 -208.366614)
				)
			)
		)
	)
	(zone
		(layers "B.Cu" "In4.Cu" "In6.Cu" "In11.Cu" "In13.Cu" "In15.Cu")
		(hatch none 0.5)
		(connect_pads
			(clearance 0)
		)
		(min_thickness 0.25)
		(keepout
			(tracks not_allowed)
			(vias allowed)
			(pads allowed)
			(copperpour not_allowed)
			(footprints allowed)
		)
		(placement
			(enabled no)
			(sheetname "")
		)
		(fill yes
			(thermal_gap 0.5)
			(thermal_bridge_width 0.5)
			(island_removal_mode 0)
		)
		(polygon
			(pts
				(arc
					(start 325.774558 -400.858228)
					(mid 325.070978 -400.858228)
					(end 325.774558 -400.858228)
				)
			)
		)
	)
	(zone
		(layers "B.Cu" "In4.Cu" "In6.Cu" "In11.Cu" "In13.Cu" "In15.Cu")
		(hatch none 0.5)
		(connect_pads
			(clearance 0)
		)
		(min_thickness 0.25)
		(keepout
			(tracks not_allowed)
			(vias allowed)
			(pads allowed)
			(copperpour not_allowed)
			(footprints allowed)
		)
		(placement
			(enabled no)
			(sheetname "")
		)
		(fill yes
			(thermal_gap 0.5)
			(thermal_bridge_width 0.5)
			(island_removal_mode 0)
		)
		(polygon
			(pts
				(arc
					(start 295.230804 -312.066686)
					(mid 294.578024 -312.066686)
					(end 295.230804 -312.066686)
				)
			)
		)
	)
	(zone
		(layers "B.Cu" "In4.Cu" "In6.Cu" "In11.Cu" "In13.Cu" "In15.Cu")
		(hatch none 0.5)
		(connect_pads
			(clearance 0)
		)
		(min_thickness 0.25)
		(keepout
			(tracks not_allowed)
			(vias allowed)
			(pads allowed)
			(copperpour not_allowed)
			(footprints allowed)
		)
		(placement
			(enabled no)
			(sheetname "")
		)
		(fill yes
			(thermal_gap 0.5)
			(thermal_bridge_width 0.5)
			(island_removal_mode 0)
		)
		(polygon
			(pts
				(arc
					(start 64.994028 -407.00452)
					(mid 64.290448 -407.00452)
					(end 64.994028 -407.00452)
				)
			)
		)
	)
	(zone
		(layers "B.Cu" "In4.Cu" "In6.Cu" "In11.Cu" "In13.Cu" "In15.Cu")
		(hatch none 0.5)
		(connect_pads
			(clearance 0)
		)
		(min_thickness 0.25)
		(keepout
			(tracks not_allowed)
			(vias allowed)
			(pads allowed)
			(copperpour not_allowed)
			(footprints allowed)
		)
		(placement
			(enabled no)
			(sheetname "")
		)
		(fill yes
			(thermal_gap 0.5)
			(thermal_bridge_width 0.5)
			(island_removal_mode 0)
		)
		(polygon
			(pts
				(arc
					(start 339.341206 -265.314176)
					(mid 338.688426 -265.314176)
					(end 339.341206 -265.314176)
				)
			)
		)
	)
	(zone
		(layers "B.Cu" "In4.Cu" "In6.Cu" "In11.Cu" "In13.Cu" "In15.Cu")
		(hatch none 0.5)
		(connect_pads
			(clearance 0)
		)
		(min_thickness 0.25)
		(keepout
			(tracks not_allowed)
			(vias allowed)
			(pads allowed)
			(copperpour not_allowed)
			(footprints allowed)
		)
		(placement
			(enabled no)
			(sheetname "")
		)
		(fill yes
			(thermal_gap 0.5)
			(thermal_bridge_width 0.5)
			(island_removal_mode 0)
		)
		(polygon
			(pts
				(arc
					(start 432.706272 -259.366766)
					(mid 432.053492 -259.366766)
					(end 432.706272 -259.366766)
				)
			)
		)
	)
	(zone
		(layers "B.Cu" "In4.Cu" "In6.Cu" "In11.Cu" "In13.Cu" "In15.Cu")
		(hatch none 0.5)
		(connect_pads
			(clearance 0)
		)
		(min_thickness 0.25)
		(keepout
			(tracks not_allowed)
			(vias allowed)
			(pads allowed)
			(copperpour not_allowed)
			(footprints allowed)
		)
		(placement
			(enabled no)
			(sheetname "")
		)
		(fill yes
			(thermal_gap 0.5)
			(thermal_bridge_width 0.5)
			(island_removal_mode 0)
		)
		(polygon
			(pts
				(arc
					(start 135.571738 -266.942062)
					(mid 134.918958 -266.942062)
					(end 135.571738 -266.942062)
				)
			)
		)
	)
	(zone
		(layers "B.Cu" "In4.Cu" "In6.Cu" "In11.Cu" "In13.Cu" "In15.Cu")
		(hatch none 0.5)
		(connect_pads
			(clearance 0)
		)
		(min_thickness 0.25)
		(keepout
			(tracks not_allowed)
			(vias allowed)
			(pads allowed)
			(copperpour not_allowed)
			(footprints allowed)
		)
		(placement
			(enabled no)
			(sheetname "")
		)
		(fill yes
			(thermal_gap 0.5)
			(thermal_bridge_width 0.5)
			(island_removal_mode 0)
		)
		(polygon
			(pts
				(arc
					(start 410.049472 -301.866554)
					(mid 409.396692 -301.866554)
					(end 410.049472 -301.866554)
				)
			)
		)
	)
	(zone
		(layers "B.Cu" "In4.Cu" "In6.Cu" "In11.Cu" "In13.Cu" "In15.Cu")
		(hatch none 0.5)
		(connect_pads
			(clearance 0)
		)
		(min_thickness 0.25)
		(keepout
			(tracks not_allowed)
			(vias allowed)
			(pads allowed)
			(copperpour not_allowed)
			(footprints allowed)
		)
		(placement
			(enabled no)
			(sheetname "")
		)
		(fill yes
			(thermal_gap 0.5)
			(thermal_bridge_width 0.5)
			(island_removal_mode 0)
		)
		(polygon
			(pts
				(arc
					(start 47.290736 -207.51673)
					(mid 46.637956 -207.51673)
					(end 47.290736 -207.51673)
				)
			)
		)
	)
	(zone
		(layers "B.Cu" "In4.Cu" "In6.Cu" "In11.Cu" "In13.Cu" "In15.Cu")
		(hatch none 0.5)
		(connect_pads
			(clearance 0)
		)
		(min_thickness 0.25)
		(keepout
			(tracks not_allowed)
			(vias allowed)
			(pads allowed)
			(copperpour not_allowed)
			(footprints allowed)
		)
		(placement
			(enabled no)
			(sheetname "")
		)
		(fill yes
			(thermal_gap 0.5)
			(thermal_bridge_width 0.5)
			(island_removal_mode 0)
		)
		(polygon
			(pts
				(arc
					(start 425.162472 -233.016806)
					(mid 424.509692 -233.016806)
					(end 425.162472 -233.016806)
				)
			)
		)
	)
	(zone
		(layers "B.Cu" "In4.Cu" "In6.Cu" "In11.Cu" "In13.Cu" "In15.Cu")
		(hatch none 0.5)
		(connect_pads
			(clearance 0)
		)
		(min_thickness 0.25)
		(keepout
			(tracks not_allowed)
			(vias allowed)
			(pads allowed)
			(copperpour not_allowed)
			(footprints allowed)
		)
		(placement
			(enabled no)
			(sheetname "")
		)
		(fill yes
			(thermal_gap 0.5)
			(thermal_bridge_width 0.5)
			(island_removal_mode 0)
		)
		(polygon
			(pts
				(arc
					(start 128.053338 -286.475424)
					(mid 127.400558 -286.475424)
					(end 128.053338 -286.475424)
				)
			)
		)
	)
	(zone
		(layers "B.Cu" "In4.Cu" "In6.Cu" "In11.Cu" "In13.Cu" "In15.Cu")
		(hatch none 0.5)
		(connect_pads
			(clearance 0)
		)
		(min_thickness 0.25)
		(keepout
			(tracks not_allowed)
			(vias allowed)
			(pads allowed)
			(copperpour not_allowed)
			(footprints allowed)
		)
		(placement
			(enabled no)
			(sheetname "")
		)
		(fill yes
			(thermal_gap 0.5)
			(thermal_bridge_width 0.5)
			(island_removal_mode 0)
		)
		(polygon
			(pts
				(arc
					(start 393.187174 -19.125438)
					(mid 392.483594 -19.125438)
					(end 393.187174 -19.125438)
				)
			)
		)
	)
	(zone
		(layers "B.Cu" "In4.Cu" "In6.Cu" "In11.Cu" "In13.Cu" "In15.Cu")
		(hatch none 0.5)
		(connect_pads
			(clearance 0)
		)
		(min_thickness 0.25)
		(keepout
			(tracks not_allowed)
			(vias allowed)
			(pads allowed)
			(copperpour not_allowed)
			(footprints allowed)
		)
		(placement
			(enabled no)
			(sheetname "")
		)
		(fill yes
			(thermal_gap 0.5)
			(thermal_bridge_width 0.5)
			(island_removal_mode 0)
		)
		(polygon
			(pts
				(arc
					(start 66.478404 -229.616762)
					(mid 65.825624 -229.616762)
					(end 66.478404 -229.616762)
				)
			)
		)
	)
	(zone
		(layers "B.Cu" "In4.Cu" "In6.Cu" "In11.Cu" "In13.Cu" "In15.Cu")
		(hatch none 0.5)
		(connect_pads
			(clearance 0)
		)
		(min_thickness 0.25)
		(keepout
			(tracks not_allowed)
			(vias allowed)
			(pads allowed)
			(copperpour not_allowed)
			(footprints allowed)
		)
		(placement
			(enabled no)
			(sheetname "")
		)
		(fill yes
			(thermal_gap 0.5)
			(thermal_bridge_width 0.5)
			(island_removal_mode 0)
		)
		(polygon
			(pts
				(arc
					(start 340.171024 -248.806208)
					(mid 339.518244 -248.806208)
					(end 340.171024 -248.806208)
				)
			)
		)
	)
	(zone
		(layers "B.Cu" "In4.Cu" "In6.Cu" "In11.Cu" "In13.Cu" "In15.Cu")
		(hatch none 0.5)
		(connect_pads
			(clearance 0)
		)
		(min_thickness 0.25)
		(keepout
			(tracks not_allowed)
			(vias allowed)
			(pads allowed)
			(copperpour not_allowed)
			(footprints allowed)
		)
		(placement
			(enabled no)
			(sheetname "")
		)
		(fill yes
			(thermal_gap 0.5)
			(thermal_bridge_width 0.5)
			(island_removal_mode 0)
		)
		(polygon
			(pts
				(arc
					(start 134.161784 -274.266914)
					(mid 133.509004 -274.266914)
					(end 134.161784 -274.266914)
				)
			)
		)
	)
	(zone
		(layers "B.Cu" "In4.Cu" "In6.Cu" "In11.Cu" "In13.Cu" "In15.Cu")
		(hatch none 0.5)
		(connect_pads
			(clearance 0)
		)
		(min_thickness 0.25)
		(keepout
			(tracks not_allowed)
			(vias allowed)
			(pads allowed)
			(copperpour not_allowed)
			(footprints allowed)
		)
		(placement
			(enabled no)
			(sheetname "")
		)
		(fill yes
			(thermal_gap 0.5)
			(thermal_bridge_width 0.5)
			(island_removal_mode 0)
		)
		(polygon
			(pts
				(arc
					(start 162.109404 -302.716692)
					(mid 161.456624 -302.716692)
					(end 162.109404 -302.716692)
				)
			)
		)
	)
	(zone
		(layers "B.Cu" "In4.Cu" "In6.Cu" "In11.Cu" "In13.Cu" "In15.Cu")
		(hatch none 0.5)
		(connect_pads
			(clearance 0)
		)
		(min_thickness 0.25)
		(keepout
			(tracks not_allowed)
			(vias allowed)
			(pads allowed)
			(copperpour not_allowed)
			(footprints allowed)
		)
		(placement
			(enabled no)
			(sheetname "")
		)
		(fill yes
			(thermal_gap 0.5)
			(thermal_bridge_width 0.5)
			(island_removal_mode 0)
		)
		(polygon
			(pts
				(arc
					(start 383.041652 -279.150318)
					(mid 382.388872 -279.150318)
					(end 383.041652 -279.150318)
				)
			)
		)
	)
	(zone
		(layers "B.Cu" "In4.Cu" "In6.Cu" "In11.Cu" "In13.Cu" "In15.Cu")
		(hatch none 0.5)
		(connect_pads
			(clearance 0)
		)
		(min_thickness 0.25)
		(keepout
			(tracks not_allowed)
			(vias allowed)
			(pads allowed)
			(copperpour not_allowed)
			(footprints allowed)
		)
		(placement
			(enabled no)
			(sheetname "")
		)
		(fill yes
			(thermal_gap 0.5)
			(thermal_bridge_width 0.5)
			(island_removal_mode 0)
		)
		(polygon
			(pts
				(arc
					(start 299.356272 -273.816572)
					(mid 298.703492 -273.816572)
					(end 299.356272 -273.816572)
				)
			)
		)
	)
	(zone
		(layers "B.Cu" "In4.Cu" "In6.Cu" "In11.Cu" "In13.Cu" "In15.Cu")
		(hatch none 0.5)
		(connect_pads
			(clearance 0)
		)
		(min_thickness 0.25)
		(keepout
			(tracks not_allowed)
			(vias allowed)
			(pads allowed)
			(copperpour not_allowed)
			(footprints allowed)
		)
		(placement
			(enabled no)
			(sheetname "")
		)
		(fill yes
			(thermal_gap 0.5)
			(thermal_bridge_width 0.5)
			(island_removal_mode 0)
		)
		(polygon
			(pts
				(arc
					(start 135.571738 -271.825212)
					(mid 134.918958 -271.825212)
					(end 135.571738 -271.825212)
				)
			)
		)
	)
	(zone
		(layers "B.Cu" "In4.Cu" "In6.Cu" "In11.Cu" "In13.Cu" "In15.Cu")
		(hatch none 0.5)
		(connect_pads
			(clearance 0)
		)
		(min_thickness 0.25)
		(keepout
			(tracks not_allowed)
			(vias allowed)
			(pads allowed)
			(copperpour not_allowed)
			(footprints allowed)
		)
		(placement
			(enabled no)
			(sheetname "")
		)
		(fill yes
			(thermal_gap 0.5)
			(thermal_bridge_width 0.5)
			(island_removal_mode 0)
		)
		(polygon
			(pts
				(arc
					(start 177.222404 -312.066686)
					(mid 176.569624 -312.066686)
					(end 177.222404 -312.066686)
				)
			)
		)
	)
	(zone
		(layers "B.Cu" "In4.Cu" "In6.Cu" "In11.Cu" "In13.Cu" "In15.Cu")
		(hatch none 0.5)
		(connect_pads
			(clearance 0)
		)
		(min_thickness 0.25)
		(keepout
			(tracks not_allowed)
			(vias allowed)
			(pads allowed)
			(copperpour not_allowed)
			(footprints allowed)
		)
		(placement
			(enabled no)
			(sheetname "")
		)
		(fill yes
			(thermal_gap 0.5)
			(thermal_bridge_width 0.5)
			(island_removal_mode 0)
		)
		(polygon
			(pts
				(arc
					(start 421.062404 -249.166634)
					(mid 420.409624 -249.166634)
					(end 421.062404 -249.166634)
				)
			)
		)
	)
	(zone
		(layers "B.Cu" "In4.Cu" "In6.Cu" "In11.Cu" "In13.Cu" "In15.Cu")
		(hatch none 0.5)
		(connect_pads
			(clearance 0)
		)
		(min_thickness 0.25)
		(keepout
			(tracks not_allowed)
			(vias allowed)
			(pads allowed)
			(copperpour not_allowed)
			(footprints allowed)
		)
		(placement
			(enabled no)
			(sheetname "")
		)
		(fill yes
			(thermal_gap 0.5)
			(thermal_bridge_width 0.5)
			(island_removal_mode 0)
		)
		(polygon
			(pts
				(arc
					(start 133.692138 -286.475424)
					(mid 133.039358 -286.475424)
					(end 133.692138 -286.475424)
				)
			)
		)
	)
	(zone
		(layers "B.Cu" "In4.Cu" "In6.Cu" "In11.Cu" "In13.Cu" "In15.Cu")
		(hatch none 0.5)
		(connect_pads
			(clearance 0)
		)
		(min_thickness 0.25)
		(keepout
			(tracks not_allowed)
			(vias allowed)
			(pads allowed)
			(copperpour not_allowed)
			(footprints allowed)
		)
		(placement
			(enabled no)
			(sheetname "")
		)
		(fill yes
			(thermal_gap 0.5)
			(thermal_bridge_width 0.5)
			(island_removal_mode 0)
		)
		(polygon
			(pts
				(arc
					(start 381.992124 -239.853216)
					(mid 381.339344 -239.853216)
					(end 381.992124 -239.853216)
				)
			)
		)
	)
	(zone
		(layers "B.Cu" "In4.Cu" "In6.Cu" "In11.Cu" "In13.Cu" "In15.Cu")
		(hatch none 0.5)
		(connect_pads
			(clearance 0)
		)
		(min_thickness 0.25)
		(keepout
			(tracks not_allowed)
			(vias allowed)
			(pads allowed)
			(copperpour not_allowed)
			(footprints allowed)
		)
		(placement
			(enabled no)
			(sheetname "")
		)
		(fill yes
			(thermal_gap 0.5)
			(thermal_bridge_width 0.5)
			(island_removal_mode 0)
		)
		(polygon
			(pts
				(arc
					(start 314.418472 -302.716692)
					(mid 313.765692 -302.716692)
					(end 314.418472 -302.716692)
				)
			)
		)
	)
	(zone
		(layers "B.Cu" "In4.Cu" "In6.Cu" "In11.Cu" "In13.Cu" "In15.Cu")
		(hatch none 0.5)
		(connect_pads
			(clearance 0)
		)
		(min_thickness 0.25)
		(keepout
			(tracks not_allowed)
			(vias allowed)
			(pads allowed)
			(copperpour not_allowed)
			(footprints allowed)
		)
		(placement
			(enabled no)
			(sheetname "")
		)
		(fill yes
			(thermal_gap 0.5)
			(thermal_bridge_width 0.5)
			(island_removal_mode 0)
		)
		(polygon
			(pts
				(arc
					(start 173.122336 -314.616592)
					(mid 172.469556 -314.616592)
					(end 173.122336 -314.616592)
				)
			)
		)
	)
	(zone
		(layers "B.Cu" "In4.Cu" "In6.Cu" "In11.Cu" "In13.Cu" "In15.Cu")
		(hatch none 0.5)
		(connect_pads
			(clearance 0)
		)
		(min_thickness 0.25)
		(keepout
			(tracks not_allowed)
			(vias allowed)
			(pads allowed)
			(copperpour not_allowed)
			(footprints allowed)
		)
		(placement
			(enabled no)
			(sheetname "")
		)
		(fill yes
			(thermal_gap 0.5)
			(thermal_bridge_width 0.5)
			(island_removal_mode 0)
		)
		(polygon
			(pts
				(arc
					(start 396.844774 -17.601438)
					(mid 396.141194 -17.601438)
					(end 396.844774 -17.601438)
				)
			)
		)
	)
	(zone
		(layers "B.Cu" "In4.Cu" "In6.Cu" "In11.Cu" "In13.Cu" "In15.Cu")
		(hatch none 0.5)
		(connect_pads
			(clearance 0)
		)
		(min_thickness 0.25)
		(keepout
			(tracks not_allowed)
			(vias allowed)
			(pads allowed)
			(copperpour not_allowed)
			(footprints allowed)
		)
		(placement
			(enabled no)
			(sheetname "")
		)
		(fill yes
			(thermal_gap 0.5)
			(thermal_bridge_width 0.5)
			(island_removal_mode 0)
		)
		(polygon
			(pts
				(arc
					(start 89.521284 -265.314176)
					(mid 88.868504 -265.314176)
					(end 89.521284 -265.314176)
				)
			)
		)
	)
	(zone
		(layers "B.Cu" "In4.Cu" "In6.Cu" "In11.Cu" "In13.Cu" "In15.Cu")
		(hatch none 0.5)
		(connect_pads
			(clearance 0)
		)
		(min_thickness 0.25)
		(keepout
			(tracks not_allowed)
			(vias allowed)
			(pads allowed)
			(copperpour not_allowed)
			(footprints allowed)
		)
		(placement
			(enabled no)
			(sheetname "")
		)
		(fill yes
			(thermal_gap 0.5)
			(thermal_bridge_width 0.5)
			(island_removal_mode 0)
		)
		(polygon
			(pts
				(arc
					(start 47.290736 -291.666676)
					(mid 46.637956 -291.666676)
					(end 47.290736 -291.666676)
				)
			)
		)
	)
	(zone
		(layers "B.Cu" "In4.Cu" "In6.Cu" "In11.Cu" "In13.Cu" "In15.Cu")
		(hatch none 0.5)
		(connect_pads
			(clearance 0)
		)
		(min_thickness 0.25)
		(keepout
			(tracks not_allowed)
			(vias allowed)
			(pads allowed)
			(copperpour not_allowed)
			(footprints allowed)
		)
		(placement
			(enabled no)
			(sheetname "")
		)
		(fill yes
			(thermal_gap 0.5)
			(thermal_bridge_width 0.5)
			(island_removal_mode 0)
		)
		(polygon
			(pts
				(arc
					(start 295.230804 -264.466578)
					(mid 294.578024 -264.466578)
					(end 295.230804 -264.466578)
				)
			)
		)
	)
	(zone
		(layers "B.Cu" "In4.Cu" "In6.Cu" "In11.Cu" "In13.Cu" "In15.Cu")
		(hatch none 0.5)
		(connect_pads
			(clearance 0)
		)
		(min_thickness 0.25)
		(keepout
			(tracks not_allowed)
			(vias allowed)
			(pads allowed)
			(copperpour not_allowed)
			(footprints allowed)
		)
		(placement
			(enabled no)
			(sheetname "")
		)
		(fill yes
			(thermal_gap 0.5)
			(thermal_bridge_width 0.5)
			(island_removal_mode 0)
		)
		(polygon
			(pts
				(arc
					(start 90.351356 -234.15625)
					(mid 89.698576 -234.15625)
					(end 90.351356 -234.15625)
				)
			)
		)
	)
	(zone
		(layers "B.Cu" "In4.Cu" "In6.Cu" "In11.Cu" "In13.Cu" "In15.Cu")
		(hatch none 0.5)
		(connect_pads
			(clearance 0)
		)
		(min_thickness 0.25)
		(keepout
			(tracks not_allowed)
			(vias allowed)
			(pads allowed)
			(copperpour not_allowed)
			(footprints allowed)
		)
		(placement
			(enabled no)
			(sheetname "")
		)
		(fill yes
			(thermal_gap 0.5)
			(thermal_bridge_width 0.5)
			(island_removal_mode 0)
		)
		(polygon
			(pts
				(arc
					(start 383.041652 -266.128246)
					(mid 382.388872 -266.128246)
					(end 383.041652 -266.128246)
				)
			)
		)
	)
	(zone
		(layers "B.Cu" "In4.Cu" "In6.Cu" "In11.Cu" "In13.Cu" "In15.Cu")
		(hatch none 0.5)
		(connect_pads
			(clearance 0)
		)
		(min_thickness 0.25)
		(keepout
			(tracks not_allowed)
			(vias allowed)
			(pads allowed)
			(copperpour not_allowed)
			(footprints allowed)
		)
		(placement
			(enabled no)
			(sheetname "")
		)
		(fill yes
			(thermal_gap 0.5)
			(thermal_bridge_width 0.5)
			(island_removal_mode 0)
		)
		(polygon
			(pts
				(arc
					(start 310.318404 -305.266598)
					(mid 309.665624 -305.266598)
					(end 310.318404 -305.266598)
				)
			)
		)
	)
	(zone
		(layers "B.Cu" "In4.Cu" "In6.Cu" "In11.Cu" "In13.Cu" "In15.Cu")
		(hatch none 0.5)
		(connect_pads
			(clearance 0)
		)
		(min_thickness 0.25)
		(keepout
			(tracks not_allowed)
			(vias allowed)
			(pads allowed)
			(copperpour not_allowed)
			(footprints allowed)
		)
		(placement
			(enabled no)
			(sheetname "")
		)
		(fill yes
			(thermal_gap 0.5)
			(thermal_bridge_width 0.5)
			(island_removal_mode 0)
		)
		(polygon
			(pts
				(arc
					(start 295.230804 -233.86669)
					(mid 294.578024 -233.86669)
					(end 295.230804 -233.86669)
				)
			)
		)
	)
	(zone
		(layers "B.Cu" "In4.Cu" "In6.Cu" "In11.Cu" "In13.Cu" "In15.Cu")
		(hatch none 0.5)
		(connect_pads
			(clearance 0)
		)
		(min_thickness 0.25)
		(keepout
			(tracks not_allowed)
			(vias allowed)
			(pads allowed)
			(copperpour not_allowed)
			(footprints allowed)
		)
		(placement
			(enabled no)
			(sheetname "")
		)
		(fill yes
			(thermal_gap 0.5)
			(thermal_bridge_width 0.5)
			(island_removal_mode 0)
		)
		(polygon
			(pts
				(arc
					(start 410.7434 -407.00452)
					(mid 410.03982 -407.00452)
					(end 410.7434 -407.00452)
				)
			)
		)
	)
	(zone
		(layers "B.Cu" "In4.Cu" "In6.Cu" "In11.Cu" "In13.Cu" "In15.Cu")
		(hatch none 0.5)
		(connect_pads
			(clearance 0)
		)
		(min_thickness 0.25)
		(keepout
			(tracks not_allowed)
			(vias allowed)
			(pads allowed)
			(copperpour not_allowed)
			(footprints allowed)
		)
		(placement
			(enabled no)
			(sheetname "")
		)
		(fill yes
			(thermal_gap 0.5)
			(thermal_bridge_width 0.5)
			(island_removal_mode 0)
		)
		(polygon
			(pts
				(arc
					(start 376.463052 -285.661354)
					(mid 375.810272 -285.661354)
					(end 376.463052 -285.661354)
				)
			)
		)
	)
	(zone
		(layers "B.Cu" "In4.Cu" "In6.Cu" "In11.Cu" "In13.Cu" "In15.Cu")
		(hatch none 0.5)
		(connect_pads
			(clearance 0)
		)
		(min_thickness 0.25)
		(keepout
			(tracks not_allowed)
			(vias allowed)
			(pads allowed)
			(copperpour not_allowed)
			(footprints allowed)
		)
		(placement
			(enabled no)
			(sheetname "")
		)
		(fill yes
			(thermal_gap 0.5)
			(thermal_bridge_width 0.5)
			(island_removal_mode 0)
		)
		(polygon
			(pts
				(arc
					(start 91.291156 -247.178322)
					(mid 90.638376 -247.178322)
					(end 91.291156 -247.178322)
				)
			)
		)
	)
	(zone
		(layers "B.Cu" "In4.Cu" "In6.Cu" "In11.Cu" "In13.Cu" "In15.Cu")
		(hatch none 0.5)
		(connect_pads
			(clearance 0)
		)
		(min_thickness 0.25)
		(keepout
			(tracks not_allowed)
			(vias allowed)
			(pads allowed)
			(copperpour not_allowed)
			(footprints allowed)
		)
		(placement
			(enabled no)
			(sheetname "")
		)
		(fill yes
			(thermal_gap 0.5)
			(thermal_bridge_width 0.5)
			(island_removal_mode 0)
		)
		(polygon
			(pts
				(arc
					(start 55.804308 -407.00452)
					(mid 55.100728 -407.00452)
					(end 55.804308 -407.00452)
				)
			)
		)
	)
	(zone
		(layers "B.Cu" "In4.Cu" "In6.Cu" "In11.Cu" "In13.Cu" "In15.Cu")
		(hatch none 0.5)
		(connect_pads
			(clearance 0)
		)
		(min_thickness 0.25)
		(keepout
			(tracks not_allowed)
			(vias allowed)
			(pads allowed)
			(copperpour not_allowed)
			(footprints allowed)
		)
		(placement
			(enabled no)
			(sheetname "")
		)
		(fill yes
			(thermal_gap 0.5)
			(thermal_bridge_width 0.5)
			(island_removal_mode 0)
		)
		(polygon
			(pts
				(arc
					(start 52.741068 -407.00452)
					(mid 52.037488 -407.00452)
					(end 52.741068 -407.00452)
				)
			)
		)
	)
	(zone
		(layers "B.Cu" "In4.Cu" "In6.Cu" "In11.Cu" "In13.Cu" "In15.Cu")
		(hatch none 0.5)
		(connect_pads
			(clearance 0)
		)
		(min_thickness 0.25)
		(keepout
			(tracks not_allowed)
			(vias allowed)
			(pads allowed)
			(copperpour not_allowed)
			(footprints allowed)
		)
		(placement
			(enabled no)
			(sheetname "")
		)
		(fill yes
			(thermal_gap 0.5)
			(thermal_bridge_width 0.5)
			(island_removal_mode 0)
		)
		(polygon
			(pts
				(arc
					(start 89.521284 -276.708616)
					(mid 88.868504 -276.708616)
					(end 89.521284 -276.708616)
				)
			)
		)
	)
	(zone
		(layers "B.Cu" "In4.Cu" "In6.Cu" "In11.Cu" "In13.Cu" "In15.Cu")
		(hatch none 0.5)
		(connect_pads
			(clearance 0)
		)
		(min_thickness 0.25)
		(keepout
			(tracks not_allowed)
			(vias allowed)
			(pads allowed)
			(copperpour not_allowed)
			(footprints allowed)
		)
		(placement
			(enabled no)
			(sheetname "")
		)
		(fill yes
			(thermal_gap 0.5)
			(thermal_bridge_width 0.5)
			(island_removal_mode 0)
		)
		(polygon
			(pts
				(arc
					(start 135.101584 -272.639282)
					(mid 134.448804 -272.639282)
					(end 135.101584 -272.639282)
				)
			)
		)
	)
	(zone
		(layers "B.Cu" "In4.Cu" "In6.Cu" "In11.Cu" "In13.Cu" "In15.Cu")
		(hatch none 0.5)
		(connect_pads
			(clearance 0)
		)
		(min_thickness 0.25)
		(keepout
			(tracks not_allowed)
			(vias allowed)
			(pads allowed)
			(copperpour not_allowed)
			(footprints allowed)
		)
		(placement
			(enabled no)
			(sheetname "")
		)
		(fill yes
			(thermal_gap 0.5)
			(thermal_bridge_width 0.5)
			(island_removal_mode 0)
		)
		(polygon
			(pts
				(arc
					(start 299.356272 -261.916672)
					(mid 298.703492 -261.916672)
					(end 299.356272 -261.916672)
				)
			)
		)
	)
	(zone
		(layers "B.Cu" "In4.Cu" "In6.Cu" "In11.Cu" "In13.Cu" "In15.Cu")
		(hatch none 0.5)
		(connect_pads
			(clearance 0)
		)
		(min_thickness 0.25)
		(keepout
			(tracks not_allowed)
			(vias allowed)
			(pads allowed)
			(copperpour not_allowed)
			(footprints allowed)
		)
		(placement
			(enabled no)
			(sheetname "")
		)
		(fill yes
			(thermal_gap 0.5)
			(thermal_bridge_width 0.5)
			(island_removal_mode 0)
		)
		(polygon
			(pts
				(arc
					(start 173.122336 -209.216752)
					(mid 172.469556 -209.216752)
					(end 173.122336 -209.216752)
				)
			)
		)
	)
	(zone
		(layers "B.Cu" "In4.Cu" "In6.Cu" "In11.Cu" "In13.Cu" "In15.Cu")
		(hatch none 0.5)
		(connect_pads
			(clearance 0)
		)
		(min_thickness 0.25)
		(keepout
			(tracks not_allowed)
			(vias allowed)
			(pads allowed)
			(copperpour not_allowed)
			(footprints allowed)
		)
		(placement
			(enabled no)
			(sheetname "")
		)
		(fill yes
			(thermal_gap 0.5)
			(thermal_bridge_width 0.5)
			(island_removal_mode 0)
		)
		(polygon
			(pts
				(arc
					(start 299.356272 -296.766742)
					(mid 298.703492 -296.766742)
					(end 299.356272 -296.766742)
				)
			)
		)
	)
	(zone
		(layers "B.Cu" "In4.Cu" "In6.Cu" "In11.Cu" "In13.Cu" "In15.Cu")
		(hatch none 0.5)
		(connect_pads
			(clearance 0)
		)
		(min_thickness 0.25)
		(keepout
			(tracks not_allowed)
			(vias allowed)
			(pads allowed)
			(copperpour not_allowed)
			(footprints allowed)
		)
		(placement
			(enabled no)
			(sheetname "")
		)
		(fill yes
			(thermal_gap 0.5)
			(thermal_bridge_width 0.5)
			(island_removal_mode 0)
		)
		(polygon
			(pts
				(arc
					(start 90.821002 -226.831144)
					(mid 90.168222 -226.831144)
					(end 90.821002 -226.831144)
				)
			)
		)
	)
	(zone
		(layers "B.Cu" "In4.Cu" "In6.Cu" "In11.Cu" "In13.Cu" "In15.Cu")
		(hatch none 0.5)
		(connect_pads
			(clearance 0)
		)
		(min_thickness 0.25)
		(keepout
			(tracks not_allowed)
			(vias allowed)
			(pads allowed)
			(copperpour not_allowed)
			(footprints allowed)
		)
		(placement
			(enabled no)
			(sheetname "")
		)
		(fill yes
			(thermal_gap 0.5)
			(thermal_bridge_width 0.5)
			(island_removal_mode 0)
		)
		(polygon
			(pts
				(arc
					(start 425.162472 -315.46673)
					(mid 424.509692 -315.46673)
					(end 425.162472 -315.46673)
				)
			)
		)
	)
	(zone
		(layers "B.Cu" "In4.Cu" "In6.Cu" "In11.Cu" "In13.Cu" "In15.Cu")
		(hatch none 0.5)
		(connect_pads
			(clearance 0)
		)
		(min_thickness 0.25)
		(keepout
			(tracks not_allowed)
			(vias allowed)
			(pads allowed)
			(copperpour not_allowed)
			(footprints allowed)
		)
		(placement
			(enabled no)
			(sheetname "")
		)
		(fill yes
			(thermal_gap 0.5)
			(thermal_bridge_width 0.5)
			(island_removal_mode 0)
		)
		(polygon
			(pts
				(arc
					(start 337.351624 -239.0394)
					(mid 336.698844 -239.0394)
					(end 337.351624 -239.0394)
				)
			)
		)
	)
	(zone
		(layers "B.Cu" "In4.Cu" "In6.Cu" "In11.Cu" "In13.Cu" "In15.Cu")
		(hatch none 0.5)
		(connect_pads
			(clearance 0)
		)
		(min_thickness 0.25)
		(keepout
			(tracks not_allowed)
			(vias allowed)
			(pads allowed)
			(copperpour not_allowed)
			(footprints allowed)
		)
		(placement
			(enabled no)
			(sheetname "")
		)
		(fill yes
			(thermal_gap 0.5)
			(thermal_bridge_width 0.5)
			(island_removal_mode 0)
		)
		(polygon
			(pts
				(arc
					(start 347.799406 -286.475424)
					(mid 347.146626 -286.475424)
					(end 347.799406 -286.475424)
				)
			)
		)
	)
	(zone
		(layers "B.Cu" "In4.Cu" "In6.Cu" "In11.Cu" "In13.Cu" "In15.Cu")
		(hatch none 0.5)
		(connect_pads
			(clearance 0)
		)
		(min_thickness 0.25)
		(keepout
			(tracks not_allowed)
			(vias allowed)
			(pads allowed)
			(copperpour not_allowed)
			(footprints allowed)
		)
		(placement
			(enabled no)
			(sheetname "")
		)
		(fill yes
			(thermal_gap 0.5)
			(thermal_bridge_width 0.5)
			(island_removal_mode 0)
		)
		(polygon
			(pts
				(arc
					(start 127.113538 -284.847538)
					(mid 126.460758 -284.847538)
					(end 127.113538 -284.847538)
				)
			)
		)
	)
	(zone
		(layers "B.Cu" "In4.Cu" "In6.Cu" "In11.Cu" "In13.Cu" "In15.Cu")
		(hatch none 0.5)
		(connect_pads
			(clearance 0)
		)
		(min_thickness 0.25)
		(keepout
			(tracks not_allowed)
			(vias allowed)
			(pads allowed)
			(copperpour not_allowed)
			(footprints allowed)
		)
		(placement
			(enabled no)
			(sheetname "")
		)
		(fill yes
			(thermal_gap 0.5)
			(thermal_bridge_width 0.5)
			(island_removal_mode 0)
		)
		(polygon
			(pts
				(arc
					(start 62.378336 -301.01667)
					(mid 61.725556 -301.01667)
					(end 62.378336 -301.01667)
				)
			)
		)
	)
	(zone
		(layers "B.Cu" "In4.Cu" "In6.Cu" "In11.Cu" "In13.Cu" "In15.Cu")
		(hatch none 0.5)
		(connect_pads
			(clearance 0)
		)
		(min_thickness 0.25)
		(keepout
			(tracks not_allowed)
			(vias allowed)
			(pads allowed)
			(copperpour not_allowed)
			(footprints allowed)
		)
		(placement
			(enabled no)
			(sheetname "")
		)
		(fill yes
			(thermal_gap 0.5)
			(thermal_bridge_width 0.5)
			(island_removal_mode 0)
		)
		(polygon
			(pts
				(arc
					(start 370.824252 -285.661354)
					(mid 370.171472 -285.661354)
					(end 370.824252 -285.661354)
				)
			)
		)
	)
	(zone
		(layers "B.Cu" "In4.Cu" "In6.Cu" "In11.Cu" "In13.Cu" "In15.Cu")
		(hatch none 0.5)
		(connect_pads
			(clearance 0)
		)
		(min_thickness 0.25)
		(keepout
			(tracks not_allowed)
			(vias allowed)
			(pads allowed)
			(copperpour not_allowed)
			(footprints allowed)
		)
		(placement
			(enabled no)
			(sheetname "")
		)
		(fill yes
			(thermal_gap 0.5)
			(thermal_bridge_width 0.5)
			(island_removal_mode 0)
		)
		(polygon
			(pts
				(arc
					(start 401.55368 -407.00452)
					(mid 400.8501 -407.00452)
					(end 401.55368 -407.00452)
				)
			)
		)
	)
	(zone
		(layers "B.Cu" "In4.Cu" "In6.Cu" "In11.Cu" "In13.Cu" "In15.Cu")
		(hatch none 0.5)
		(connect_pads
			(clearance 0)
		)
		(min_thickness 0.25)
		(keepout
			(tracks not_allowed)
			(vias allowed)
			(pads allowed)
			(copperpour not_allowed)
			(footprints allowed)
		)
		(placement
			(enabled no)
			(sheetname "")
		)
		(fill yes
			(thermal_gap 0.5)
			(thermal_bridge_width 0.5)
			(island_removal_mode 0)
		)
		(polygon
			(pts
				(arc
					(start 47.290736 -267.866622)
					(mid 46.637956 -267.866622)
					(end 47.290736 -267.866622)
				)
			)
		)
	)
	(zone
		(layers "B.Cu" "In4.Cu" "In6.Cu" "In11.Cu" "In13.Cu" "In15.Cu")
		(hatch none 0.5)
		(connect_pads
			(clearance 0)
		)
		(min_thickness 0.25)
		(keepout
			(tracks not_allowed)
			(vias allowed)
			(pads allowed)
			(copperpour not_allowed)
			(footprints allowed)
		)
		(placement
			(enabled no)
			(sheetname "")
		)
		(fill yes
			(thermal_gap 0.5)
			(thermal_bridge_width 0.5)
			(island_removal_mode 0)
		)
		(polygon
			(pts
				(arc
					(start 380.222252 -285.661354)
					(mid 379.569472 -285.661354)
					(end 380.222252 -285.661354)
				)
			)
		)
	)
	(zone
		(layers "B.Cu" "In4.Cu" "In6.Cu" "In11.Cu" "In13.Cu" "In15.Cu")
		(hatch none 0.5)
		(connect_pads
			(clearance 0)
		)
		(min_thickness 0.25)
		(keepout
			(tracks not_allowed)
			(vias allowed)
			(pads allowed)
			(copperpour not_allowed)
			(footprints allowed)
		)
		(placement
			(enabled no)
			(sheetname "")
		)
		(fill yes
			(thermal_gap 0.5)
			(thermal_bridge_width 0.5)
			(island_removal_mode 0)
		)
		(polygon
			(pts
				(arc
					(start 173.122336 -316.316614)
					(mid 172.469556 -316.316614)
					(end 173.122336 -316.316614)
				)
			)
		)
	)
	(zone
		(layers "B.Cu" "In4.Cu" "In6.Cu" "In11.Cu" "In13.Cu" "In15.Cu")
		(hatch none 0.5)
		(connect_pads
			(clearance 0)
		)
		(min_thickness 0.25)
		(keepout
			(tracks not_allowed)
			(vias allowed)
			(pads allowed)
			(copperpour not_allowed)
			(footprints allowed)
		)
		(placement
			(enabled no)
			(sheetname "")
		)
		(fill yes
			(thermal_gap 0.5)
			(thermal_bridge_width 0.5)
			(island_removal_mode 0)
		)
		(polygon
			(pts
				(arc
					(start 135.571484 -258.80314)
					(mid 134.918704 -258.80314)
					(end 135.571484 -258.80314)
				)
			)
		)
	)
	(zone
		(layers "B.Cu" "In4.Cu" "In6.Cu" "In11.Cu" "In13.Cu" "In15.Cu")
		(hatch none 0.5)
		(connect_pads
			(clearance 0)
		)
		(min_thickness 0.25)
		(keepout
			(tracks not_allowed)
			(vias allowed)
			(pads allowed)
			(copperpour not_allowed)
			(footprints allowed)
		)
		(placement
			(enabled no)
			(sheetname "")
		)
		(fill yes
			(thermal_gap 0.5)
			(thermal_bridge_width 0.5)
			(island_removal_mode 0)
		)
		(polygon
			(pts
				(arc
					(start 135.461756 -240.667286)
					(mid 134.808976 -240.667286)
					(end 135.461756 -240.667286)
				)
			)
		)
	)
	(zone
		(layers "B.Cu" "In4.Cu" "In6.Cu" "In11.Cu" "In13.Cu" "In15.Cu")
		(hatch none 0.5)
		(connect_pads
			(clearance 0)
		)
		(min_thickness 0.25)
		(keepout
			(tracks not_allowed)
			(vias allowed)
			(pads allowed)
			(copperpour not_allowed)
			(footprints allowed)
		)
		(placement
			(enabled no)
			(sheetname "")
		)
		(fill yes
			(thermal_gap 0.5)
			(thermal_bridge_width 0.5)
			(island_removal_mode 0)
		)
		(polygon
			(pts
				(arc
					(start 378.342652 -256.361438)
					(mid 377.689872 -256.361438)
					(end 378.342652 -256.361438)
				)
			)
		)
	)
	(zone
		(layers "B.Cu" "In4.Cu" "In6.Cu" "In11.Cu" "In13.Cu" "In15.Cu")
		(hatch none 0.5)
		(connect_pads
			(clearance 0)
		)
		(min_thickness 0.25)
		(keepout
			(tracks not_allowed)
			(vias allowed)
			(pads allowed)
			(copperpour not_allowed)
			(footprints allowed)
		)
		(placement
			(enabled no)
			(sheetname "")
		)
		(fill yes
			(thermal_gap 0.5)
			(thermal_bridge_width 0.5)
			(island_removal_mode 0)
		)
		(polygon
			(pts
				(arc
					(start 135.101584 -261.244842)
					(mid 134.448804 -261.244842)
					(end 135.101584 -261.244842)
				)
			)
		)
	)
	(zone
		(layers "B.Cu" "In4.Cu" "In6.Cu" "In11.Cu" "In13.Cu" "In15.Cu")
		(hatch none 0.5)
		(connect_pads
			(clearance 0)
		)
		(min_thickness 0.25)
		(keepout
			(tracks not_allowed)
			(vias allowed)
			(pads allowed)
			(copperpour not_allowed)
			(footprints allowed)
		)
		(placement
			(enabled no)
			(sheetname "")
		)
		(fill yes
			(thermal_gap 0.5)
			(thermal_bridge_width 0.5)
			(island_removal_mode 0)
		)
		(polygon
			(pts
				(arc
					(start 421.062404 -218.566746)
					(mid 420.409624 -218.566746)
					(end 421.062404 -218.566746)
				)
			)
		)
	)
	(zone
		(layers "B.Cu" "In4.Cu" "In6.Cu" "In11.Cu" "In13.Cu" "In15.Cu")
		(hatch none 0.5)
		(connect_pads
			(clearance 0)
		)
		(min_thickness 0.25)
		(keepout
			(tracks not_allowed)
			(vias allowed)
			(pads allowed)
			(copperpour not_allowed)
			(footprints allowed)
		)
		(placement
			(enabled no)
			(sheetname "")
		)
		(fill yes
			(thermal_gap 0.5)
			(thermal_bridge_width 0.5)
			(island_removal_mode 0)
		)
		(polygon
			(pts
				(arc
					(start 412.745174 -17.601438)
					(mid 412.041594 -17.601438)
					(end 412.745174 -17.601438)
				)
			)
		)
	)
	(zone
		(layers "B.Cu" "In4.Cu" "In6.Cu" "In11.Cu" "In13.Cu" "In15.Cu")
		(hatch none 0.5)
		(connect_pads
			(clearance 0)
		)
		(min_thickness 0.25)
		(keepout
			(tracks not_allowed)
			(vias allowed)
			(pads allowed)
			(copperpour not_allowed)
			(footprints allowed)
		)
		(placement
			(enabled no)
			(sheetname "")
		)
		(fill yes
			(thermal_gap 0.5)
			(thermal_bridge_width 0.5)
			(island_removal_mode 0)
		)
		(polygon
			(pts
				(arc
					(start 89.051384 -274.266914)
					(mid 88.398604 -274.266914)
					(end 89.051384 -274.266914)
				)
			)
		)
	)
	(zone
		(layers "B.Cu" "In4.Cu" "In6.Cu" "In11.Cu" "In13.Cu" "In15.Cu")
		(hatch none 0.5)
		(connect_pads
			(clearance 0)
		)
		(min_thickness 0.25)
		(keepout
			(tracks not_allowed)
			(vias allowed)
			(pads allowed)
			(copperpour not_allowed)
			(footprints allowed)
		)
		(placement
			(enabled no)
			(sheetname "")
		)
		(fill yes
			(thermal_gap 0.5)
			(thermal_bridge_width 0.5)
			(island_removal_mode 0)
		)
		(polygon
			(pts
				(arc
					(start 177.222404 -292.51656)
					(mid 176.569624 -292.51656)
					(end 177.222404 -292.51656)
				)
			)
		)
	)
	(zone
		(layers "B.Cu" "In4.Cu" "In6.Cu" "In11.Cu" "In13.Cu" "In15.Cu")
		(hatch none 0.5)
		(connect_pads
			(clearance 0)
		)
		(min_thickness 0.25)
		(keepout
			(tracks not_allowed)
			(vias allowed)
			(pads allowed)
			(copperpour not_allowed)
			(footprints allowed)
		)
		(placement
			(enabled no)
			(sheetname "")
		)
		(fill yes
			(thermal_gap 0.5)
			(thermal_bridge_width 0.5)
			(island_removal_mode 0)
		)
		(polygon
			(pts
				(arc
					(start 366.01527 -225.203258)
					(mid 365.36249 -225.203258)
					(end 366.01527 -225.203258)
				)
			)
		)
	)
	(zone
		(layers "B.Cu" "In4.Cu" "In6.Cu" "In11.Cu" "In13.Cu" "In15.Cu")
		(hatch none 0.5)
		(connect_pads
			(clearance 0)
		)
		(min_thickness 0.25)
		(keepout
			(tracks not_allowed)
			(vias allowed)
			(pads allowed)
			(copperpour not_allowed)
			(footprints allowed)
		)
		(placement
			(enabled no)
			(sheetname "")
		)
		(fill yes
			(thermal_gap 0.5)
			(thermal_bridge_width 0.5)
			(island_removal_mode 0)
		)
		(polygon
			(pts
				(arc
					(start 354.73767 -225.203258)
					(mid 354.08489 -225.203258)
					(end 354.73767 -225.203258)
				)
			)
		)
	)
	(zone
		(layers "B.Cu" "In4.Cu" "In6.Cu" "In11.Cu" "In13.Cu" "In15.Cu")
		(hatch none 0.5)
		(connect_pads
			(clearance 0)
		)
		(min_thickness 0.25)
		(keepout
			(tracks not_allowed)
			(vias allowed)
			(pads allowed)
			(copperpour not_allowed)
			(footprints allowed)
		)
		(placement
			(enabled no)
			(sheetname "")
		)
		(fill yes
			(thermal_gap 0.5)
			(thermal_bridge_width 0.5)
			(island_removal_mode 0)
		)
		(polygon
			(pts
				(arc
					(start 287.687004 -267.866622)
					(mid 287.034224 -267.866622)
					(end 287.687004 -267.866622)
				)
			)
		)
	)
	(zone
		(layers "B.Cu" "In4.Cu" "In6.Cu" "In11.Cu" "In13.Cu" "In15.Cu")
		(hatch none 0.5)
		(connect_pads
			(clearance 0)
		)
		(min_thickness 0.25)
		(keepout
			(tracks not_allowed)
			(vias allowed)
			(pads allowed)
			(copperpour not_allowed)
			(footprints allowed)
		)
		(placement
			(enabled no)
			(sheetname "")
		)
		(fill yes
			(thermal_gap 0.5)
			(thermal_bridge_width 0.5)
			(island_removal_mode 0)
		)
		(polygon
			(pts
				(arc
					(start 90.461084 -275.08073)
					(mid 89.808304 -275.08073)
					(end 90.461084 -275.08073)
				)
			)
		)
	)
	(zone
		(layers "B.Cu" "In4.Cu" "In6.Cu" "In11.Cu" "In13.Cu" "In15.Cu")
		(hatch none 0.5)
		(connect_pads
			(clearance 0)
		)
		(min_thickness 0.25)
		(keepout
			(tracks not_allowed)
			(vias allowed)
			(pads allowed)
			(copperpour not_allowed)
			(footprints allowed)
		)
		(placement
			(enabled no)
			(sheetname "")
		)
		(fill yes
			(thermal_gap 0.5)
			(thermal_bridge_width 0.5)
			(island_removal_mode 0)
		)
		(polygon
			(pts
				(arc
					(start 158.009336 -230.466646)
					(mid 157.356556 -230.466646)
					(end 158.009336 -230.466646)
				)
			)
		)
	)
	(zone
		(layers "B.Cu" "In4.Cu" "In6.Cu" "In11.Cu" "In13.Cu" "In15.Cu")
		(hatch none 0.5)
		(connect_pads
			(clearance 0)
		)
		(min_thickness 0.25)
		(keepout
			(tracks not_allowed)
			(vias allowed)
			(pads allowed)
			(copperpour not_allowed)
			(footprints allowed)
		)
		(placement
			(enabled no)
			(sheetname "")
		)
		(fill yes
			(thermal_gap 0.5)
			(thermal_bridge_width 0.5)
			(island_removal_mode 0)
		)
		(polygon
			(pts
				(arc
					(start 372.703852 -285.661354)
					(mid 372.051072 -285.661354)
					(end 372.703852 -285.661354)
				)
			)
		)
	)
	(zone
		(layers "B.Cu" "In4.Cu" "In6.Cu" "In11.Cu" "In13.Cu" "In15.Cu")
		(hatch none 0.5)
		(connect_pads
			(clearance 0)
		)
		(min_thickness 0.25)
		(keepout
			(tracks not_allowed)
			(vias allowed)
			(pads allowed)
			(copperpour not_allowed)
			(footprints allowed)
		)
		(placement
			(enabled no)
			(sheetname "")
		)
		(fill yes
			(thermal_gap 0.5)
			(thermal_bridge_width 0.5)
			(island_removal_mode 0)
		)
		(polygon
			(pts
				(arc
					(start 71.984108 -407.00452)
					(mid 71.280528 -407.00452)
					(end 71.984108 -407.00452)
				)
			)
		)
	)
	(zone
		(layers "B.Cu" "In4.Cu" "In6.Cu" "In11.Cu" "In13.Cu" "In15.Cu")
		(hatch none 0.5)
		(connect_pads
			(clearance 0)
		)
		(min_thickness 0.25)
		(keepout
			(tracks not_allowed)
			(vias allowed)
			(pads allowed)
			(copperpour not_allowed)
			(footprints allowed)
		)
		(placement
			(enabled no)
			(sheetname "")
		)
		(fill yes
			(thermal_gap 0.5)
			(thermal_bridge_width 0.5)
			(island_removal_mode 0)
		)
		(polygon
			(pts
				(arc
					(start 336.991452 -275.8948)
					(mid 336.338672 -275.8948)
					(end 336.991452 -275.8948)
				)
			)
		)
	)
	(zone
		(layers "B.Cu" "In4.Cu" "In6.Cu" "In11.Cu" "In13.Cu" "In15.Cu")
		(hatch none 0.5)
		(connect_pads
			(clearance 0)
		)
		(min_thickness 0.25)
		(keepout
			(tracks not_allowed)
			(vias allowed)
			(pads allowed)
			(copperpour not_allowed)
			(footprints allowed)
		)
		(placement
			(enabled no)
			(sheetname "")
		)
		(fill yes
			(thermal_gap 0.5)
			(thermal_bridge_width 0.5)
			(island_removal_mode 0)
		)
		(polygon
			(pts
				(arc
					(start 295.230804 -272.966688)
					(mid 294.578024 -272.966688)
					(end 295.230804 -272.966688)
				)
			)
		)
	)
	(zone
		(layers "B.Cu" "In4.Cu" "In6.Cu" "In11.Cu" "In13.Cu" "In15.Cu")
		(hatch none 0.5)
		(connect_pads
			(clearance 0)
		)
		(min_thickness 0.25)
		(keepout
			(tracks not_allowed)
			(vias allowed)
			(pads allowed)
			(copperpour not_allowed)
			(footprints allowed)
		)
		(placement
			(enabled no)
			(sheetname "")
		)
		(fill yes
			(thermal_gap 0.5)
			(thermal_bridge_width 0.5)
			(island_removal_mode 0)
		)
		(polygon
			(pts
				(arc
					(start 369.414806 -284.847538)
					(mid 368.762026 -284.847538)
					(end 369.414806 -284.847538)
				)
			)
		)
	)
	(zone
		(layers "B.Cu" "In4.Cu" "In6.Cu" "In11.Cu" "In13.Cu" "In15.Cu")
		(hatch none 0.5)
		(connect_pads
			(clearance 0)
		)
		(min_thickness 0.25)
		(keepout
			(tracks not_allowed)
			(vias allowed)
			(pads allowed)
			(copperpour not_allowed)
			(footprints allowed)
		)
		(placement
			(enabled no)
			(sheetname "")
		)
		(fill yes
			(thermal_gap 0.5)
			(thermal_bridge_width 0.5)
			(island_removal_mode 0)
		)
		(polygon
			(pts
				(arc
					(start 299.330872 -212.616796)
					(mid 298.678092 -212.616796)
					(end 299.330872 -212.616796)
				)
			)
		)
	)
	(zone
		(layers "B.Cu" "In4.Cu" "In6.Cu" "In11.Cu" "In13.Cu" "In15.Cu")
		(hatch none 0.5)
		(connect_pads
			(clearance 0)
		)
		(min_thickness 0.25)
		(keepout
			(tracks not_allowed)
			(vias allowed)
			(pads allowed)
			(copperpour not_allowed)
			(footprints allowed)
		)
		(placement
			(enabled no)
			(sheetname "")
		)
		(fill yes
			(thermal_gap 0.5)
			(thermal_bridge_width 0.5)
			(island_removal_mode 0)
		)
		(polygon
			(pts
				(arc
					(start 66.478404 -227.066602)
					(mid 65.825624 -227.066602)
					(end 66.478404 -227.066602)
				)
			)
		)
	)
	(zone
		(layers "B.Cu" "In4.Cu" "In6.Cu" "In11.Cu" "In13.Cu" "In15.Cu")
		(hatch none 0.5)
		(connect_pads
			(clearance 0)
		)
		(min_thickness 0.25)
		(keepout
			(tracks not_allowed)
			(vias allowed)
			(pads allowed)
			(copperpour not_allowed)
			(footprints allowed)
		)
		(placement
			(enabled no)
			(sheetname "")
		)
		(fill yes
			(thermal_gap 0.5)
			(thermal_bridge_width 0.5)
			(island_removal_mode 0)
		)
		(polygon
			(pts
				(arc
					(start 162.109404 -225.36658)
					(mid 161.456624 -225.36658)
					(end 162.109404 -225.36658)
				)
			)
		)
	)
	(zone
		(layers "B.Cu" "In4.Cu" "In6.Cu" "In11.Cu" "In13.Cu" "In15.Cu")
		(hatch none 0.5)
		(connect_pads
			(clearance 0)
		)
		(min_thickness 0.25)
		(keepout
			(tracks not_allowed)
			(vias allowed)
			(pads allowed)
			(copperpour not_allowed)
			(footprints allowed)
		)
		(placement
			(enabled no)
			(sheetname "")
		)
		(fill yes
			(thermal_gap 0.5)
			(thermal_bridge_width 0.5)
			(island_removal_mode 0)
		)
		(polygon
			(pts
				(arc
					(start 90.930984 -269.38351)
					(mid 90.278204 -269.38351)
					(end 90.930984 -269.38351)
				)
			)
		)
	)
	(zone
		(layers "B.Cu" "In4.Cu" "In6.Cu" "In11.Cu" "In13.Cu" "In15.Cu")
		(hatch none 0.5)
		(connect_pads
			(clearance 0)
		)
		(min_thickness 0.25)
		(keepout
			(tracks not_allowed)
			(vias allowed)
			(pads allowed)
			(copperpour not_allowed)
			(footprints allowed)
		)
		(placement
			(enabled no)
			(sheetname "")
		)
		(fill yes
			(thermal_gap 0.5)
			(thermal_bridge_width 0.5)
			(island_removal_mode 0)
		)
		(polygon
			(pts
				(arc
					(start 421.062404 -274.66671)
					(mid 420.409624 -274.66671)
					(end 421.062404 -274.66671)
				)
			)
		)
	)
	(zone
		(layers "B.Cu" "In4.Cu" "In6.Cu" "In11.Cu" "In13.Cu" "In15.Cu")
		(hatch none 0.5)
		(connect_pads
			(clearance 0)
		)
		(min_thickness 0.25)
		(keepout
			(tracks not_allowed)
			(vias allowed)
			(pads allowed)
			(copperpour not_allowed)
			(footprints allowed)
		)
		(placement
			(enabled no)
			(sheetname "")
		)
		(fill yes
			(thermal_gap 0.5)
			(thermal_bridge_width 0.5)
			(island_removal_mode 0)
		)
		(polygon
			(pts
				(arc
					(start 135.101584 -269.38351)
					(mid 134.448804 -269.38351)
					(end 135.101584 -269.38351)
				)
			)
		)
	)
	(zone
		(layers "B.Cu" "In4.Cu" "In6.Cu" "In11.Cu" "In13.Cu" "In15.Cu")
		(hatch none 0.5)
		(connect_pads
			(clearance 0)
		)
		(min_thickness 0.25)
		(keepout
			(tracks not_allowed)
			(vias allowed)
			(pads allowed)
			(copperpour not_allowed)
			(footprints allowed)
		)
		(placement
			(enabled no)
			(sheetname "")
		)
		(fill yes
			(thermal_gap 0.5)
			(thermal_bridge_width 0.5)
			(island_removal_mode 0)
		)
		(polygon
			(pts
				(arc
					(start 310.458358 -400.858228)
					(mid 309.754778 -400.858228)
					(end 310.458358 -400.858228)
				)
			)
		)
	)
	(zone
		(layers "B.Cu" "In4.Cu" "In6.Cu" "In11.Cu" "In13.Cu" "In15.Cu")
		(hatch none 0.5)
		(connect_pads
			(clearance 0)
		)
		(min_thickness 0.25)
		(keepout
			(tracks not_allowed)
			(vias allowed)
			(pads allowed)
			(copperpour not_allowed)
			(footprints allowed)
		)
		(placement
			(enabled no)
			(sheetname "")
		)
		(fill yes
			(thermal_gap 0.5)
			(thermal_bridge_width 0.5)
			(island_removal_mode 0)
		)
		(polygon
			(pts
				(arc
					(start 421.062404 -213.46668)
					(mid 420.409624 -213.46668)
					(end 421.062404 -213.46668)
				)
			)
		)
	)
	(zone
		(layers "B.Cu" "In4.Cu" "In6.Cu" "In11.Cu" "In13.Cu" "In15.Cu")
		(hatch none 0.5)
		(connect_pads
			(clearance 0)
		)
		(min_thickness 0.25)
		(keepout
			(tracks not_allowed)
			(vias allowed)
			(pads allowed)
			(copperpour not_allowed)
			(footprints allowed)
		)
		(placement
			(enabled no)
			(sheetname "")
		)
		(fill yes
			(thermal_gap 0.5)
			(thermal_bridge_width 0.5)
			(island_removal_mode 0)
		)
		(polygon
			(pts
				(arc
					(start 162.109404 -298.466764)
					(mid 161.456624 -298.466764)
					(end 162.109404 -298.466764)
				)
			)
		)
	)
	(zone
		(layers "B.Cu" "In4.Cu" "In6.Cu" "In11.Cu" "In13.Cu" "In15.Cu")
		(hatch none 0.5)
		(connect_pads
			(clearance 0)
		)
		(min_thickness 0.25)
		(keepout
			(tracks not_allowed)
			(vias allowed)
			(pads allowed)
			(copperpour not_allowed)
			(footprints allowed)
		)
		(placement
			(enabled no)
			(sheetname "")
		)
		(fill yes
			(thermal_gap 0.5)
			(thermal_bridge_width 0.5)
			(island_removal_mode 0)
		)
		(polygon
			(pts
				(arc
					(start 91.291156 -227.64496)
					(mid 90.638376 -227.64496)
					(end 91.291156 -227.64496)
				)
			)
		)
	)
	(zone
		(layers "B.Cu" "In4.Cu" "In6.Cu" "In11.Cu" "In13.Cu" "In15.Cu")
		(hatch none 0.5)
		(connect_pads
			(clearance 0)
		)
		(min_thickness 0.25)
		(keepout
			(tracks not_allowed)
			(vias allowed)
			(pads allowed)
			(copperpour not_allowed)
			(footprints allowed)
		)
		(placement
			(enabled no)
			(sheetname "")
		)
		(fill yes
			(thermal_gap 0.5)
			(thermal_bridge_width 0.5)
			(island_removal_mode 0)
		)
		(polygon
			(pts
				(arc
					(start 126.173738 -286.475424)
					(mid 125.520958 -286.475424)
					(end 126.173738 -286.475424)
				)
			)
		)
	)
	(zone
		(layers "B.Cu" "In4.Cu" "In6.Cu" "In11.Cu" "In13.Cu" "In15.Cu")
		(hatch none 0.5)
		(connect_pads
			(clearance 0)
		)
		(min_thickness 0.25)
		(keepout
			(tracks not_allowed)
			(vias allowed)
			(pads allowed)
			(copperpour not_allowed)
			(footprints allowed)
		)
		(placement
			(enabled no)
			(sheetname "")
		)
		(fill yes
			(thermal_gap 0.5)
			(thermal_bridge_width 0.5)
			(island_removal_mode 0)
		)
		(polygon
			(pts
				(arc
					(start 338.401152 -276.708616)
					(mid 337.748372 -276.708616)
					(end 338.401152 -276.708616)
				)
			)
		)
	)
	(zone
		(layers "B.Cu" "In4.Cu" "In6.Cu" "In11.Cu" "In13.Cu" "In15.Cu")
		(hatch none 0.5)
		(connect_pads
			(clearance 0)
		)
		(min_thickness 0.25)
		(keepout
			(tracks not_allowed)
			(vias allowed)
			(pads allowed)
			(copperpour not_allowed)
			(footprints allowed)
		)
		(placement
			(enabled no)
			(sheetname "")
		)
		(fill yes
			(thermal_gap 0.5)
			(thermal_bridge_width 0.5)
			(island_removal_mode 0)
		)
		(polygon
			(pts
				(arc
					(start 425.162472 -221.96679)
					(mid 424.509692 -221.96679)
					(end 425.162472 -221.96679)
				)
			)
		)
	)
	(zone
		(layers "B.Cu" "In4.Cu" "In6.Cu" "In11.Cu" "In13.Cu" "In15.Cu")
		(hatch none 0.5)
		(connect_pads
			(clearance 0)
		)
		(min_thickness 0.25)
		(keepout
			(tracks not_allowed)
			(vias allowed)
			(pads allowed)
			(copperpour not_allowed)
			(footprints allowed)
		)
		(placement
			(enabled no)
			(sheetname "")
		)
		(fill yes
			(thermal_gap 0.5)
			(thermal_bridge_width 0.5)
			(island_removal_mode 0)
		)
		(polygon
			(pts
				(arc
					(start 336.88147 -231.714548)
					(mid 336.22869 -231.714548)
					(end 336.88147 -231.714548)
				)
			)
		)
	)
	(zone
		(layers "B.Cu" "In4.Cu" "In6.Cu" "In11.Cu" "In13.Cu" "In15.Cu")
		(hatch none 0.5)
		(connect_pads
			(clearance 0)
		)
		(min_thickness 0.25)
		(keepout
			(tracks not_allowed)
			(vias allowed)
			(pads allowed)
			(copperpour not_allowed)
			(footprints allowed)
		)
		(placement
			(enabled no)
			(sheetname "")
		)
		(fill yes
			(thermal_gap 0.5)
			(thermal_bridge_width 0.5)
			(island_removal_mode 0)
		)
		(polygon
			(pts
				(arc
					(start 90.930984 -254.733552)
					(mid 90.278204 -254.733552)
					(end 90.930984 -254.733552)
				)
			)
		)
	)
	(zone
		(layers "B.Cu" "In4.Cu" "In6.Cu" "In11.Cu" "In13.Cu" "In15.Cu")
		(hatch none 0.5)
		(connect_pads
			(clearance 0)
		)
		(min_thickness 0.25)
		(keepout
			(tracks not_allowed)
			(vias allowed)
			(pads allowed)
			(copperpour not_allowed)
			(footprints allowed)
		)
		(placement
			(enabled no)
			(sheetname "")
		)
		(fill yes
			(thermal_gap 0.5)
			(thermal_bridge_width 0.5)
			(island_removal_mode 0)
		)
		(polygon
			(pts
				(arc
					(start 51.390804 -248.31675)
					(mid 50.738024 -248.31675)
					(end 51.390804 -248.31675)
				)
			)
		)
	)
	(zone
		(layers "B.Cu" "In4.Cu" "In6.Cu" "In11.Cu" "In13.Cu" "In15.Cu")
		(hatch none 0.5)
		(connect_pads
			(clearance 0)
		)
		(min_thickness 0.25)
		(keepout
			(tracks not_allowed)
			(vias allowed)
			(pads allowed)
			(copperpour not_allowed)
			(footprints allowed)
		)
		(placement
			(enabled no)
			(sheetname "")
		)
		(fill yes
			(thermal_gap 0.5)
			(thermal_bridge_width 0.5)
			(island_removal_mode 0)
		)
		(polygon
			(pts
				(arc
					(start 377.402852 -285.661354)
					(mid 376.750072 -285.661354)
					(end 377.402852 -285.661354)
				)
			)
		)
	)
	(zone
		(layers "B.Cu" "In4.Cu" "In6.Cu" "In11.Cu" "In13.Cu" "In15.Cu")
		(hatch none 0.5)
		(connect_pads
			(clearance 0)
		)
		(min_thickness 0.25)
		(keepout
			(tracks not_allowed)
			(vias allowed)
			(pads allowed)
			(copperpour not_allowed)
			(footprints allowed)
		)
		(placement
			(enabled no)
			(sheetname "")
		)
		(fill yes
			(thermal_gap 0.5)
			(thermal_bridge_width 0.5)
			(island_removal_mode 0)
		)
		(polygon
			(pts
				(arc
					(start 295.230804 -278.916638)
					(mid 294.578024 -278.916638)
					(end 295.230804 -278.916638)
				)
			)
		)
	)
	(zone
		(layers "B.Cu" "In4.Cu" "In6.Cu" "In11.Cu" "In13.Cu" "In15.Cu")
		(hatch none 0.5)
		(connect_pads
			(clearance 0)
		)
		(min_thickness 0.25)
		(keepout
			(tracks not_allowed)
			(vias allowed)
			(pads allowed)
			(copperpour not_allowed)
			(footprints allowed)
		)
		(placement
			(enabled no)
			(sheetname "")
		)
		(fill yes
			(thermal_gap 0.5)
			(thermal_bridge_width 0.5)
			(island_removal_mode 0)
		)
		(polygon
			(pts
				(arc
					(start 336.88147 -247.992138)
					(mid 336.22869 -247.992138)
					(end 336.88147 -247.992138)
				)
			)
		)
	)
	(zone
		(layers "B.Cu" "In4.Cu" "In6.Cu" "In11.Cu" "In13.Cu" "In15.Cu")
		(hatch none 0.5)
		(connect_pads
			(clearance 0)
		)
		(min_thickness 0.25)
		(keepout
			(tracks not_allowed)
			(vias allowed)
			(pads allowed)
			(copperpour not_allowed)
			(footprints allowed)
		)
		(placement
			(enabled no)
			(sheetname "")
		)
		(fill yes
			(thermal_gap 0.5)
			(thermal_bridge_width 0.5)
			(island_removal_mode 0)
		)
		(polygon
			(pts
				(arc
					(start 295.230804 -207.51673)
					(mid 294.578024 -207.51673)
					(end 295.230804 -207.51673)
				)
			)
		)
	)
	(zone
		(layers "B.Cu" "In4.Cu" "In6.Cu" "In11.Cu" "In13.Cu" "In15.Cu")
		(hatch none 0.5)
		(connect_pads
			(clearance 0)
		)
		(min_thickness 0.25)
		(keepout
			(tracks not_allowed)
			(vias allowed)
			(pads allowed)
			(copperpour not_allowed)
			(footprints allowed)
		)
		(placement
			(enabled no)
			(sheetname "")
		)
		(fill yes
			(thermal_gap 0.5)
			(thermal_bridge_width 0.5)
			(island_removal_mode 0)
		)
		(polygon
			(pts
				(arc
					(start 141.095984 -407.00452)
					(mid 140.392404 -407.00452)
					(end 141.095984 -407.00452)
				)
			)
		)
	)
	(zone
		(layers "B.Cu" "In4.Cu" "In6.Cu" "In11.Cu" "In13.Cu" "In15.Cu")
		(hatch none 0.5)
		(connect_pads
			(clearance 0)
		)
		(min_thickness 0.25)
		(keepout
			(tracks not_allowed)
			(vias allowed)
			(pads allowed)
			(copperpour not_allowed)
			(footprints allowed)
		)
		(placement
			(enabled no)
			(sheetname "")
		)
		(fill yes
			(thermal_gap 0.5)
			(thermal_bridge_width 0.5)
			(island_removal_mode 0)
		)
		(polygon
			(pts
				(arc
					(start 173.122336 -291.666676)
					(mid 172.469556 -291.666676)
					(end 173.122336 -291.666676)
				)
			)
		)
	)
	(zone
		(layers "B.Cu" "In4.Cu" "In6.Cu" "In11.Cu" "In13.Cu" "In15.Cu")
		(hatch none 0.5)
		(connect_pads
			(clearance 0)
		)
		(min_thickness 0.25)
		(keepout
			(tracks not_allowed)
			(vias allowed)
			(pads allowed)
			(copperpour not_allowed)
			(footprints allowed)
		)
		(placement
			(enabled no)
			(sheetname "")
		)
		(fill yes
			(thermal_gap 0.5)
			(thermal_bridge_width 0.5)
			(island_removal_mode 0)
		)
		(polygon
			(pts
				(arc
					(start 415.84499 -19.125438)
					(mid 415.14141 -19.125438)
					(end 415.84499 -19.125438)
				)
			)
		)
	)
	(zone
		(layers "B.Cu" "In4.Cu" "In6.Cu" "In11.Cu" "In13.Cu" "In15.Cu")
		(hatch none 0.5)
		(connect_pads
			(clearance 0)
		)
		(min_thickness 0.25)
		(keepout
			(tracks not_allowed)
			(vias allowed)
			(pads allowed)
			(copperpour not_allowed)
			(footprints allowed)
		)
		(placement
			(enabled no)
			(sheetname "")
		)
		(fill yes
			(thermal_gap 0.5)
			(thermal_bridge_width 0.5)
			(island_removal_mode 0)
		)
		(polygon
			(pts
				(arc
					(start 338.401152 -273.453098)
					(mid 337.748372 -273.453098)
					(end 338.401152 -273.453098)
				)
			)
		)
	)
	(zone
		(layers "B.Cu" "In4.Cu" "In6.Cu" "In11.Cu" "In13.Cu" "In15.Cu")
		(hatch none 0.5)
		(connect_pads
			(clearance 0)
		)
		(min_thickness 0.25)
		(keepout
			(tracks not_allowed)
			(vias allowed)
			(pads allowed)
			(copperpour not_allowed)
			(footprints allowed)
		)
		(placement
			(enabled no)
			(sheetname "")
		)
		(fill yes
			(thermal_gap 0.5)
			(thermal_bridge_width 0.5)
			(island_removal_mode 0)
		)
		(polygon
			(pts
				(arc
					(start 93.640402 -247.992138)
					(mid 92.987622 -247.992138)
					(end 93.640402 -247.992138)
				)
			)
		)
	)
	(zone
		(layers "B.Cu" "In4.Cu" "In6.Cu" "In11.Cu" "In13.Cu" "In15.Cu")
		(hatch none 0.5)
		(connect_pads
			(clearance 0)
		)
		(min_thickness 0.25)
		(keepout
			(tracks not_allowed)
			(vias allowed)
			(pads allowed)
			(copperpour not_allowed)
			(footprints allowed)
		)
		(placement
			(enabled no)
			(sheetname "")
		)
		(fill yes
			(thermal_gap 0.5)
			(thermal_bridge_width 0.5)
			(island_removal_mode 0)
		)
		(polygon
			(pts
				(arc
					(start 99.859338 -286.475424)
					(mid 99.206558 -286.475424)
					(end 99.859338 -286.475424)
				)
			)
		)
	)
	(zone
		(layers "B.Cu" "In4.Cu" "In6.Cu" "In11.Cu" "In13.Cu" "In15.Cu")
		(hatch none 0.5)
		(connect_pads
			(clearance 0)
		)
		(min_thickness 0.25)
		(keepout
			(tracks not_allowed)
			(vias allowed)
			(pads allowed)
			(copperpour not_allowed)
			(footprints allowed)
		)
		(placement
			(enabled no)
			(sheetname "")
		)
		(fill yes
			(thermal_gap 0.5)
			(thermal_bridge_width 0.5)
			(island_removal_mode 0)
		)
		(polygon
			(pts
				(arc
					(start 355.207824 -224.389442)
					(mid 354.555044 -224.389442)
					(end 355.207824 -224.389442)
				)
			)
		)
	)
	(zone
		(layers "B.Cu" "In4.Cu" "In6.Cu" "In11.Cu" "In13.Cu" "In15.Cu")
		(hatch none 0.5)
		(connect_pads
			(clearance 0)
		)
		(min_thickness 0.25)
		(keepout
			(tracks not_allowed)
			(vias allowed)
			(pads allowed)
			(copperpour not_allowed)
			(footprints allowed)
		)
		(placement
			(enabled no)
			(sheetname "")
		)
		(fill yes
			(thermal_gap 0.5)
			(thermal_bridge_width 0.5)
			(island_removal_mode 0)
		)
		(polygon
			(pts
				(arc
					(start 381.162052 -272.639282)
					(mid 380.509272 -272.639282)
					(end 381.162052 -272.639282)
				)
			)
		)
	)
	(zone
		(layers "B.Cu" "In4.Cu" "In6.Cu" "In11.Cu" "In13.Cu" "In15.Cu")
		(hatch none 0.5)
		(connect_pads
			(clearance 0)
		)
		(min_thickness 0.25)
		(keepout
			(tracks not_allowed)
			(vias allowed)
			(pads allowed)
			(copperpour not_allowed)
			(footprints allowed)
		)
		(placement
			(enabled no)
			(sheetname "")
		)
		(fill yes
			(thermal_gap 0.5)
			(thermal_bridge_width 0.5)
			(island_removal_mode 0)
		)
		(polygon
			(pts
				(arc
					(start 91.291156 -232.528364)
					(mid 90.638376 -232.528364)
					(end 91.291156 -232.528364)
				)
			)
		)
	)
	(zone
		(layers "B.Cu" "In4.Cu" "In6.Cu" "In11.Cu" "In13.Cu" "In15.Cu")
		(hatch none 0.5)
		(connect_pads
			(clearance 0)
		)
		(min_thickness 0.25)
		(keepout
			(tracks not_allowed)
			(vias allowed)
			(pads allowed)
			(copperpour not_allowed)
			(footprints allowed)
		)
		(placement
			(enabled no)
			(sheetname "")
		)
		(fill yes
			(thermal_gap 0.5)
			(thermal_bridge_width 0.5)
			(island_removal_mode 0)
		)
		(polygon
			(pts
				(arc
					(start 133.691884 -266.941808)
					(mid 133.039104 -266.941808)
					(end 133.691884 -266.941808)
				)
			)
		)
	)
	(zone
		(layers "B.Cu" "In4.Cu" "In6.Cu" "In11.Cu" "In13.Cu" "In15.Cu")
		(hatch none 0.5)
		(connect_pads
			(clearance 0)
		)
		(min_thickness 0.25)
		(keepout
			(tracks not_allowed)
			(vias allowed)
			(pads allowed)
			(copperpour not_allowed)
			(footprints allowed)
		)
		(placement
			(enabled no)
			(sheetname "")
		)
		(fill yes
			(thermal_gap 0.5)
			(thermal_bridge_width 0.5)
			(island_removal_mode 0)
		)
		(polygon
			(pts
				(arc
					(start 162.109404 -300.166786)
					(mid 161.456624 -300.166786)
					(end 162.109404 -300.166786)
				)
			)
		)
	)
	(zone
		(layers "B.Cu" "In4.Cu" "In6.Cu" "In11.Cu" "In13.Cu" "In15.Cu")
		(hatch none 0.5)
		(connect_pads
			(clearance 0)
		)
		(min_thickness 0.25)
		(keepout
			(tracks not_allowed)
			(vias allowed)
			(pads allowed)
			(copperpour not_allowed)
			(footprints allowed)
		)
		(placement
			(enabled no)
			(sheetname "")
		)
		(fill yes
			(thermal_gap 0.5)
			(thermal_bridge_width 0.5)
			(island_removal_mode 0)
		)
		(polygon
			(pts
				(arc
					(start 173.046136 -264.466578)
					(mid 172.393356 -264.466578)
					(end 173.046136 -264.466578)
				)
			)
		)
	)
	(zone
		(layers "B.Cu" "In4.Cu" "In6.Cu" "In11.Cu" "In13.Cu" "In15.Cu")
		(hatch none 0.5)
		(connect_pads
			(clearance 0)
		)
		(min_thickness 0.25)
		(keepout
			(tracks not_allowed)
			(vias allowed)
			(pads allowed)
			(copperpour not_allowed)
			(footprints allowed)
		)
		(placement
			(enabled no)
			(sheetname "")
		)
		(fill yes
			(thermal_gap 0.5)
			(thermal_bridge_width 0.5)
			(island_removal_mode 0)
		)
		(polygon
			(pts
				(arc
					(start 387.16077 -222.761556)
					(mid 386.50799 -222.761556)
					(end 387.16077 -222.761556)
				)
			)
		)
	)
	(zone
		(layers "B.Cu" "In4.Cu" "In6.Cu" "In11.Cu" "In13.Cu" "In15.Cu")
		(hatch none 0.5)
		(connect_pads
			(clearance 0)
		)
		(min_thickness 0.25)
		(keepout
			(tracks not_allowed)
			(vias allowed)
			(pads allowed)
			(copperpour not_allowed)
			(footprints allowed)
		)
		(placement
			(enabled no)
			(sheetname "")
		)
		(fill yes
			(thermal_gap 0.5)
			(thermal_bridge_width 0.5)
			(island_removal_mode 0)
		)
		(polygon
			(pts
				(arc
					(start 47.290736 -289.966654)
					(mid 46.637956 -289.966654)
					(end 47.290736 -289.966654)
				)
			)
		)
	)
	(zone
		(layers "B.Cu" "In4.Cu" "In6.Cu" "In11.Cu" "In13.Cu" "In15.Cu")
		(hatch none 0.5)
		(connect_pads
			(clearance 0)
		)
		(min_thickness 0.25)
		(keepout
			(tracks not_allowed)
			(vias allowed)
			(pads allowed)
			(copperpour not_allowed)
			(footprints allowed)
		)
		(placement
			(enabled no)
			(sheetname "")
		)
		(fill yes
			(thermal_gap 0.5)
			(thermal_bridge_width 0.5)
			(island_removal_mode 0)
		)
		(polygon
			(pts
				(arc
					(start 90.461084 -276.708616)
					(mid 89.808304 -276.708616)
					(end 90.461084 -276.708616)
				)
			)
		)
	)
	(zone
		(layers "B.Cu" "In4.Cu" "In6.Cu" "In11.Cu" "In13.Cu" "In15.Cu")
		(hatch none 0.5)
		(connect_pads
			(clearance 0)
		)
		(min_thickness 0.25)
		(keepout
			(tracks not_allowed)
			(vias allowed)
			(pads allowed)
			(copperpour not_allowed)
			(footprints allowed)
		)
		(placement
			(enabled no)
			(sheetname "")
		)
		(fill yes
			(thermal_gap 0.5)
			(thermal_bridge_width 0.5)
			(island_removal_mode 0)
		)
		(polygon
			(pts
				(arc
					(start 88.941402 -241.481102)
					(mid 88.288622 -241.481102)
					(end 88.941402 -241.481102)
				)
			)
		)
	)
	(zone
		(layers "B.Cu" "In4.Cu" "In6.Cu" "In11.Cu" "In13.Cu" "In15.Cu")
		(hatch none 0.5)
		(connect_pads
			(clearance 0)
		)
		(min_thickness 0.25)
		(keepout
			(tracks not_allowed)
			(vias allowed)
			(pads allowed)
			(copperpour not_allowed)
			(footprints allowed)
		)
		(placement
			(enabled no)
			(sheetname "")
		)
		(fill yes
			(thermal_gap 0.5)
			(thermal_bridge_width 0.5)
			(island_removal_mode 0)
		)
		(polygon
			(pts
				(arc
					(start 295.230804 -295.916604)
					(mid 294.578024 -295.916604)
					(end 295.230804 -295.916604)
				)
			)
		)
	)
	(zone
		(layers "B.Cu" "In4.Cu" "In6.Cu" "In11.Cu" "In13.Cu" "In15.Cu")
		(hatch none 0.5)
		(connect_pads
			(clearance 0)
		)
		(min_thickness 0.25)
		(keepout
			(tracks not_allowed)
			(vias allowed)
			(pads allowed)
			(copperpour not_allowed)
			(footprints allowed)
		)
		(placement
			(enabled no)
			(sheetname "")
		)
		(fill yes
			(thermal_gap 0.5)
			(thermal_bridge_width 0.5)
			(island_removal_mode 0)
		)
		(polygon
			(pts
				(arc
					(start 379.282452 -285.661354)
					(mid 378.629672 -285.661354)
					(end 379.282452 -285.661354)
				)
			)
		)
	)
	(zone
		(layers "B.Cu" "In4.Cu" "In6.Cu" "In11.Cu" "In13.Cu" "In15.Cu")
		(hatch none 0.5)
		(connect_pads
			(clearance 0)
		)
		(min_thickness 0.25)
		(keepout
			(tracks not_allowed)
			(vias allowed)
			(pads allowed)
			(copperpour not_allowed)
			(footprints allowed)
		)
		(placement
			(enabled no)
			(sheetname "")
		)
		(fill yes
			(thermal_gap 0.5)
			(thermal_bridge_width 0.5)
			(island_removal_mode 0)
		)
		(polygon
			(pts
				(arc
					(start 51.416204 -307.816758)
					(mid 50.763424 -307.816758)
					(end 51.416204 -307.816758)
				)
			)
		)
	)
	(zone
		(layers "B.Cu" "In4.Cu" "In6.Cu" "In11.Cu" "In13.Cu" "In15.Cu")
		(hatch none 0.5)
		(connect_pads
			(clearance 0)
		)
		(min_thickness 0.25)
		(keepout
			(tracks not_allowed)
			(vias allowed)
			(pads allowed)
			(copperpour not_allowed)
			(footprints allowed)
		)
		(placement
			(enabled no)
			(sheetname "")
		)
		(fill yes
			(thermal_gap 0.5)
			(thermal_bridge_width 0.5)
			(island_removal_mode 0)
		)
		(polygon
			(pts
				(arc
					(start 386.221224 -221.133924)
					(mid 385.568444 -221.133924)
					(end 386.221224 -221.133924)
				)
			)
		)
	)
	(zone
		(layers "B.Cu" "In4.Cu" "In6.Cu" "In11.Cu" "In13.Cu" "In15.Cu")
		(hatch none 0.5)
		(connect_pads
			(clearance 0)
		)
		(min_thickness 0.25)
		(keepout
			(tracks not_allowed)
			(vias allowed)
			(pads allowed)
			(copperpour not_allowed)
			(footprints allowed)
		)
		(placement
			(enabled no)
			(sheetname "")
		)
		(fill yes
			(thermal_gap 0.5)
			(thermal_bridge_width 0.5)
			(island_removal_mode 0)
		)
		(polygon
			(pts
				(arc
					(start 341.156798 -0.048006)
					(mid 340.453218 -0.048006)
					(end 341.156798 -0.048006)
				)
			)
		)
	)
	(zone
		(layers "B.Cu" "In4.Cu" "In6.Cu" "In11.Cu" "In13.Cu" "In15.Cu")
		(hatch none 0.5)
		(connect_pads
			(clearance 0)
		)
		(min_thickness 0.25)
		(keepout
			(tracks not_allowed)
			(vias allowed)
			(pads allowed)
			(copperpour not_allowed)
			(footprints allowed)
		)
		(placement
			(enabled no)
			(sheetname "")
		)
		(fill yes
			(thermal_gap 0.5)
			(thermal_bridge_width 0.5)
			(island_removal_mode 0)
		)
		(polygon
			(pts
				(arc
					(start 133.692138 -273.453098)
					(mid 133.039358 -273.453098)
					(end 133.692138 -273.453098)
				)
			)
		)
	)
	(zone
		(layers "B.Cu" "In4.Cu" "In6.Cu" "In11.Cu" "In13.Cu" "In15.Cu")
		(hatch none 0.5)
		(connect_pads
			(clearance 0)
		)
		(min_thickness 0.25)
		(keepout
			(tracks not_allowed)
			(vias allowed)
			(pads allowed)
			(copperpour not_allowed)
			(footprints allowed)
		)
		(placement
			(enabled no)
			(sheetname "")
		)
		(fill yes
			(thermal_gap 0.5)
			(thermal_bridge_width 0.5)
			(island_removal_mode 0)
		)
		(polygon
			(pts
				(arc
					(start 342.050624 -248.806208)
					(mid 341.397844 -248.806208)
					(end 342.050624 -248.806208)
				)
			)
		)
	)
	(zone
		(layers "B.Cu" "In4.Cu" "In6.Cu" "In11.Cu" "In13.Cu" "In15.Cu")
		(hatch none 0.5)
		(connect_pads
			(clearance 0)
		)
		(min_thickness 0.25)
		(keepout
			(tracks not_allowed)
			(vias allowed)
			(pads allowed)
			(copperpour not_allowed)
			(footprints allowed)
		)
		(placement
			(enabled no)
			(sheetname "")
		)
		(fill yes
			(thermal_gap 0.5)
			(thermal_bridge_width 0.5)
			(island_removal_mode 0)
		)
		(polygon
			(pts
				(arc
					(start 177.222404 -309.516526)
					(mid 176.569624 -309.516526)
					(end 177.222404 -309.516526)
				)
			)
		)
	)
	(zone
		(layers "B.Cu" "In4.Cu" "In6.Cu" "In11.Cu" "In13.Cu" "In15.Cu")
		(hatch none 0.5)
		(connect_pads
			(clearance 0)
		)
		(min_thickness 0.25)
		(keepout
			(tracks not_allowed)
			(vias allowed)
			(pads allowed)
			(copperpour not_allowed)
			(footprints allowed)
		)
		(placement
			(enabled no)
			(sheetname "")
		)
		(fill yes
			(thermal_gap 0.5)
			(thermal_bridge_width 0.5)
			(island_removal_mode 0)
		)
		(polygon
			(pts
				(arc
					(start 382.101852 -269.38351)
					(mid 381.449072 -269.38351)
					(end 382.101852 -269.38351)
				)
			)
		)
	)
	(zone
		(layers "B.Cu" "In4.Cu" "In6.Cu" "In11.Cu" "In13.Cu" "In15.Cu")
		(hatch none 0.5)
		(connect_pads
			(clearance 0)
		)
		(min_thickness 0.25)
		(keepout
			(tracks not_allowed)
			(vias allowed)
			(pads allowed)
			(copperpour not_allowed)
			(footprints allowed)
		)
		(placement
			(enabled no)
			(sheetname "")
		)
		(fill yes
			(thermal_gap 0.5)
			(thermal_bridge_width 0.5)
			(island_removal_mode 0)
		)
		(polygon
			(pts
				(arc
					(start 337.461352 -257.175254)
					(mid 336.808572 -257.175254)
					(end 337.461352 -257.175254)
				)
			)
		)
	)
	(zone
		(layers "B.Cu" "In4.Cu" "In6.Cu" "In11.Cu" "In13.Cu" "In15.Cu")
		(hatch none 0.5)
		(connect_pads
			(clearance 0)
		)
		(min_thickness 0.25)
		(keepout
			(tracks not_allowed)
			(vias allowed)
			(pads allowed)
			(copperpour not_allowed)
			(footprints allowed)
		)
		(placement
			(enabled no)
			(sheetname "")
		)
		(fill yes
			(thermal_gap 0.5)
			(thermal_bridge_width 0.5)
			(island_removal_mode 0)
		)
		(polygon
			(pts
				(arc
					(start 129.462784 -285.661354)
					(mid 128.810004 -285.661354)
					(end 129.462784 -285.661354)
				)
			)
		)
	)
	(zone
		(layers "B.Cu" "In4.Cu" "In6.Cu" "In11.Cu" "In13.Cu" "In15.Cu")
		(hatch none 0.5)
		(connect_pads
			(clearance 0)
		)
		(min_thickness 0.25)
		(keepout
			(tracks not_allowed)
			(vias allowed)
			(pads allowed)
			(copperpour not_allowed)
			(footprints allowed)
		)
		(placement
			(enabled no)
			(sheetname "")
		)
		(fill yes
			(thermal_gap 0.5)
			(thermal_bridge_width 0.5)
			(island_removal_mode 0)
		)
		(polygon
			(pts
				(arc
					(start 383.041652 -274.266914)
					(mid 382.388872 -274.266914)
					(end 383.041652 -274.266914)
				)
			)
		)
	)
	(zone
		(layers "B.Cu" "In4.Cu" "In6.Cu" "In11.Cu" "In13.Cu" "In15.Cu")
		(hatch none 0.5)
		(connect_pads
			(clearance 0)
		)
		(min_thickness 0.25)
		(keepout
			(tracks not_allowed)
			(vias allowed)
			(pads allowed)
			(copperpour not_allowed)
			(footprints allowed)
		)
		(placement
			(enabled no)
			(sheetname "")
		)
		(fill yes
			(thermal_gap 0.5)
			(thermal_bridge_width 0.5)
			(island_removal_mode 0)
		)
		(polygon
			(pts
				(arc
					(start 47.290736 -264.466578)
					(mid 46.637956 -264.466578)
					(end 47.290736 -264.466578)
				)
			)
		)
	)
	(zone
		(layers "B.Cu" "In4.Cu" "In6.Cu" "In11.Cu" "In13.Cu" "In15.Cu")
		(hatch none 0.5)
		(connect_pads
			(clearance 0)
		)
		(min_thickness 0.25)
		(keepout
			(tracks not_allowed)
			(vias allowed)
			(pads allowed)
			(copperpour not_allowed)
			(footprints allowed)
		)
		(placement
			(enabled no)
			(sheetname "")
		)
		(fill yes
			(thermal_gap 0.5)
			(thermal_bridge_width 0.5)
			(island_removal_mode 0)
		)
		(polygon
			(pts
				(arc
					(start 90.461084 -257.175254)
					(mid 89.808304 -257.175254)
					(end 90.461084 -257.175254)
				)
			)
		)
	)
	(zone
		(layers "B.Cu" "In4.Cu" "In6.Cu" "In11.Cu" "In13.Cu" "In15.Cu")
		(hatch none 0.5)
		(connect_pads
			(clearance 0)
		)
		(min_thickness 0.25)
		(keepout
			(tracks not_allowed)
			(vias allowed)
			(pads allowed)
			(copperpour not_allowed)
			(footprints allowed)
		)
		(placement
			(enabled no)
			(sheetname "")
		)
		(fill yes
			(thermal_gap 0.5)
			(thermal_bridge_width 0.5)
			(island_removal_mode 0)
		)
		(polygon
			(pts
				(arc
					(start 162.538664 -407.00452)
					(mid 161.835084 -407.00452)
					(end 162.538664 -407.00452)
				)
			)
		)
	)
	(zone
		(layers "B.Cu" "In4.Cu" "In6.Cu" "In11.Cu" "In13.Cu" "In15.Cu")
		(hatch none 0.5)
		(connect_pads
			(clearance 0)
		)
		(min_thickness 0.25)
		(keepout
			(tracks not_allowed)
			(vias allowed)
			(pads allowed)
			(copperpour not_allowed)
			(footprints allowed)
		)
		(placement
			(enabled no)
			(sheetname "")
		)
		(fill yes
			(thermal_gap 0.5)
			(thermal_bridge_width 0.5)
			(island_removal_mode 0)
		)
		(polygon
			(pts
				(arc
					(start 89.411556 -240.667286)
					(mid 88.758776 -240.667286)
					(end 89.411556 -240.667286)
				)
			)
		)
	)
	(zone
		(layers "B.Cu" "In4.Cu" "In6.Cu" "In11.Cu" "In13.Cu" "In15.Cu")
		(hatch none 0.5)
		(connect_pads
			(clearance 0)
		)
		(min_thickness 0.25)
		(keepout
			(tracks not_allowed)
			(vias allowed)
			(pads allowed)
			(copperpour not_allowed)
			(footprints allowed)
		)
		(placement
			(enabled no)
			(sheetname "")
		)
		(fill yes
			(thermal_gap 0.5)
			(thermal_bridge_width 0.5)
			(island_removal_mode 0)
		)
		(polygon
			(pts
				(arc
					(start 49.719484 -17.61236)
					(mid 49.015904 -17.61236)
					(end 49.719484 -17.61236)
				)
			)
		)
	)
	(zone
		(layers "B.Cu" "In4.Cu" "In6.Cu" "In11.Cu" "In13.Cu" "In15.Cu")
		(hatch none 0.5)
		(connect_pads
			(clearance 0)
		)
		(min_thickness 0.25)
		(keepout
			(tracks not_allowed)
			(vias allowed)
			(pads allowed)
			(copperpour not_allowed)
			(footprints allowed)
		)
		(placement
			(enabled no)
			(sheetname "")
		)
		(fill yes
			(thermal_gap 0.5)
			(thermal_bridge_width 0.5)
			(island_removal_mode 0)
		)
		(polygon
			(pts
				(arc
					(start 425.162472 -278.066754)
					(mid 424.509692 -278.066754)
					(end 425.162472 -278.066754)
				)
			)
		)
	)
	(zone
		(layers "B.Cu" "In4.Cu" "In6.Cu" "In11.Cu" "In13.Cu" "In15.Cu")
		(hatch none 0.5)
		(connect_pads
			(clearance 0)
		)
		(min_thickness 0.25)
		(keepout
			(tracks not_allowed)
			(vias allowed)
			(pads allowed)
			(copperpour not_allowed)
			(footprints allowed)
		)
		(placement
			(enabled no)
			(sheetname "")
		)
		(fill yes
			(thermal_gap 0.5)
			(thermal_bridge_width 0.5)
			(island_removal_mode 0)
		)
		(polygon
			(pts
				(arc
					(start 66.478404 -301.866808)
					(mid 65.825624 -301.866808)
					(end 66.478404 -301.866808)
				)
			)
		)
	)
	(zone
		(layers "B.Cu" "In4.Cu" "In6.Cu" "In11.Cu" "In13.Cu" "In15.Cu")
		(hatch none 0.5)
		(connect_pads
			(clearance 0)
		)
		(min_thickness 0.25)
		(keepout
			(tracks not_allowed)
			(vias allowed)
			(pads allowed)
			(copperpour not_allowed)
			(footprints allowed)
		)
		(placement
			(enabled no)
			(sheetname "")
		)
		(fill yes
			(thermal_gap 0.5)
			(thermal_bridge_width 0.5)
			(island_removal_mode 0)
		)
		(polygon
			(pts
				(arc
					(start 51.416204 -272.116804)
					(mid 50.763424 -272.116804)
					(end 51.416204 -272.116804)
				)
			)
		)
	)
	(zone
		(layers "B.Cu" "In4.Cu" "In6.Cu" "In11.Cu" "In13.Cu" "In15.Cu")
		(hatch none 0.5)
		(connect_pads
			(clearance 0)
		)
		(min_thickness 0.25)
		(keepout
			(tracks not_allowed)
			(vias allowed)
			(pads allowed)
			(copperpour not_allowed)
			(footprints allowed)
		)
		(placement
			(enabled no)
			(sheetname "")
		)
		(fill yes
			(thermal_gap 0.5)
			(thermal_bridge_width 0.5)
			(island_removal_mode 0)
		)
		(polygon
			(pts
				(arc
					(start 374.113806 -286.475424)
					(mid 373.461026 -286.475424)
					(end 374.113806 -286.475424)
				)
			)
		)
	)
	(zone
		(layers "B.Cu" "In4.Cu" "In6.Cu" "In11.Cu" "In13.Cu" "In15.Cu")
		(hatch none 0.5)
		(connect_pads
			(clearance 0)
		)
		(min_thickness 0.25)
		(keepout
			(tracks not_allowed)
			(vias allowed)
			(pads allowed)
			(copperpour not_allowed)
			(footprints allowed)
		)
		(placement
			(enabled no)
			(sheetname "")
		)
		(fill yes
			(thermal_gap 0.5)
			(thermal_bridge_width 0.5)
			(island_removal_mode 0)
		)
		(polygon
			(pts
				(arc
					(start 316.584838 -400.858228)
					(mid 315.881258 -400.858228)
					(end 316.584838 -400.858228)
				)
			)
		)
	)
	(zone
		(layers "B.Cu" "In4.Cu" "In6.Cu" "In11.Cu" "In13.Cu" "In15.Cu")
		(hatch none 0.5)
		(connect_pads
			(clearance 0)
		)
		(min_thickness 0.25)
		(keepout
			(tracks not_allowed)
			(vias allowed)
			(pads allowed)
			(copperpour not_allowed)
			(footprints allowed)
		)
		(placement
			(enabled no)
			(sheetname "")
		)
		(fill yes
			(thermal_gap 0.5)
			(thermal_bridge_width 0.5)
			(island_removal_mode 0)
		)
		(polygon
			(pts
				(arc
					(start 134.161784 -266.128246)
					(mid 133.509004 -266.128246)
					(end 134.161784 -266.128246)
				)
			)
		)
	)
	(zone
		(layers "B.Cu" "In4.Cu" "In6.Cu" "In11.Cu" "In13.Cu" "In15.Cu")
		(hatch none 0.5)
		(connect_pads
			(clearance 0)
		)
		(min_thickness 0.25)
		(keepout
			(tracks not_allowed)
			(vias allowed)
			(pads allowed)
			(copperpour not_allowed)
			(footprints allowed)
		)
		(placement
			(enabled no)
			(sheetname "")
		)
		(fill yes
			(thermal_gap 0.5)
			(thermal_bridge_width 0.5)
			(island_removal_mode 0)
		)
		(polygon
			(pts
				(arc
					(start 136.871202 -223.575626)
					(mid 136.218422 -223.575626)
					(end 136.871202 -223.575626)
				)
			)
		)
	)
	(zone
		(layers "B.Cu" "In4.Cu" "In6.Cu" "In11.Cu" "In13.Cu" "In15.Cu")
		(hatch none 0.5)
		(connect_pads
			(clearance 0)
		)
		(min_thickness 0.25)
		(keepout
			(tracks not_allowed)
			(vias allowed)
			(pads allowed)
			(copperpour not_allowed)
			(footprints allowed)
		)
		(placement
			(enabled no)
			(sheetname "")
		)
		(fill yes
			(thermal_gap 0.5)
			(thermal_bridge_width 0.5)
			(island_removal_mode 0)
		)
		(polygon
			(pts
				(arc
					(start 90.821002 -246.364506)
					(mid 90.168222 -246.364506)
					(end 90.821002 -246.364506)
				)
			)
		)
	)
	(zone
		(layers "B.Cu" "In4.Cu" "In6.Cu" "In11.Cu" "In13.Cu" "In15.Cu")
		(hatch none 0.5)
		(connect_pads
			(clearance 0)
		)
		(min_thickness 0.25)
		(keepout
			(tracks not_allowed)
			(vias allowed)
			(pads allowed)
			(copperpour not_allowed)
			(footprints allowed)
		)
		(placement
			(enabled no)
			(sheetname "")
		)
		(fill yes
			(thermal_gap 0.5)
			(thermal_bridge_width 0.5)
			(island_removal_mode 0)
		)
		(polygon
			(pts
				(arc
					(start 135.931656 -234.970066)
					(mid 135.278876 -234.970066)
					(end 135.931656 -234.970066)
				)
			)
		)
	)
	(zone
		(layers "B.Cu" "In4.Cu" "In6.Cu" "In11.Cu" "In13.Cu" "In15.Cu")
		(hatch none 0.5)
		(connect_pads
			(clearance 0)
		)
		(min_thickness 0.25)
		(keepout
			(tracks not_allowed)
			(vias allowed)
			(pads allowed)
			(copperpour not_allowed)
			(footprints allowed)
		)
		(placement
			(enabled no)
			(sheetname "")
		)
		(fill yes
			(thermal_gap 0.5)
			(thermal_bridge_width 0.5)
			(island_removal_mode 0)
		)
		(polygon
			(pts
				(arc
					(start 134.991602 -243.108988)
					(mid 134.338822 -243.108988)
					(end 134.991602 -243.108988)
				)
			)
		)
	)
	(zone
		(layers "B.Cu" "In4.Cu" "In6.Cu" "In11.Cu" "In13.Cu" "In15.Cu")
		(hatch none 0.5)
		(connect_pads
			(clearance 0)
		)
		(min_thickness 0.25)
		(keepout
			(tracks not_allowed)
			(vias allowed)
			(pads allowed)
			(copperpour not_allowed)
			(footprints allowed)
		)
		(placement
			(enabled no)
			(sheetname "")
		)
		(fill yes
			(thermal_gap 0.5)
			(thermal_bridge_width 0.5)
			(island_removal_mode 0)
		)
		(polygon
			(pts
				(arc
					(start 134.052056 -238.225584)
					(mid 133.399276 -238.225584)
					(end 134.052056 -238.225584)
				)
			)
		)
	)
	(zone
		(layers "B.Cu" "In4.Cu" "In6.Cu" "In11.Cu" "In13.Cu" "In15.Cu")
		(hatch none 0.5)
		(connect_pads
			(clearance 0)
		)
		(min_thickness 0.25)
		(keepout
			(tracks not_allowed)
			(vias allowed)
			(pads allowed)
			(copperpour not_allowed)
			(footprints allowed)
		)
		(placement
			(enabled no)
			(sheetname "")
		)
		(fill yes
			(thermal_gap 0.5)
			(thermal_bridge_width 0.5)
			(island_removal_mode 0)
		)
		(polygon
			(pts
				(arc
					(start 38.237668 -17.61236)
					(mid 37.534088 -17.61236)
					(end 38.237668 -17.61236)
				)
			)
		)
	)
	(zone
		(layers "B.Cu" "In4.Cu" "In6.Cu" "In11.Cu" "In13.Cu" "In15.Cu")
		(hatch none 0.5)
		(connect_pads
			(clearance 0)
		)
		(min_thickness 0.25)
		(keepout
			(tracks not_allowed)
			(vias allowed)
			(pads allowed)
			(copperpour not_allowed)
			(footprints allowed)
		)
		(placement
			(enabled no)
			(sheetname "")
		)
		(fill yes
			(thermal_gap 0.5)
			(thermal_bridge_width 0.5)
			(island_removal_mode 0)
		)
		(polygon
			(pts
				(arc
					(start 47.290736 -293.366698)
					(mid 46.637956 -293.366698)
					(end 47.290736 -293.366698)
				)
			)
		)
	)
	(zone
		(layers "B.Cu" "In4.Cu" "In6.Cu" "In11.Cu" "In13.Cu" "In15.Cu")
		(hatch none 0.5)
		(connect_pads
			(clearance 0)
		)
		(min_thickness 0.25)
		(keepout
			(tracks not_allowed)
			(vias allowed)
			(pads allowed)
			(copperpour not_allowed)
			(footprints allowed)
		)
		(placement
			(enabled no)
			(sheetname "")
		)
		(fill yes
			(thermal_gap 0.5)
			(thermal_bridge_width 0.5)
			(island_removal_mode 0)
		)
		(polygon
			(pts
				(arc
					(start 382.101852 -259.616956)
					(mid 381.449072 -259.616956)
					(end 382.101852 -259.616956)
				)
			)
		)
	)
	(zone
		(layers "B.Cu" "In4.Cu" "In6.Cu" "In11.Cu" "In13.Cu" "In15.Cu")
		(hatch none 0.5)
		(connect_pads
			(clearance 0)
		)
		(min_thickness 0.25)
		(keepout
			(tracks not_allowed)
			(vias allowed)
			(pads allowed)
			(copperpour not_allowed)
			(footprints allowed)
		)
		(placement
			(enabled no)
			(sheetname "")
		)
		(fill yes
			(thermal_gap 0.5)
			(thermal_bridge_width 0.5)
			(island_removal_mode 0)
		)
		(polygon
			(pts
				(arc
					(start 323.574918 -400.858228)
					(mid 322.871338 -400.858228)
					(end 323.574918 -400.858228)
				)
			)
		)
	)
	(zone
		(layers "B.Cu" "In4.Cu" "In6.Cu" "In11.Cu" "In13.Cu" "In15.Cu")
		(hatch none 0.5)
		(connect_pads
			(clearance 0)
		)
		(min_thickness 0.25)
		(keepout
			(tracks not_allowed)
			(vias allowed)
			(pads allowed)
			(copperpour not_allowed)
			(footprints allowed)
		)
		(placement
			(enabled no)
			(sheetname "")
		)
		(fill yes
			(thermal_gap 0.5)
			(thermal_bridge_width 0.5)
			(island_removal_mode 0)
		)
		(polygon
			(pts
				(arc
					(start 133.112002 -234.970066)
					(mid 132.459222 -234.970066)
					(end 133.112002 -234.970066)
				)
			)
		)
	)
	(zone
		(layers "B.Cu" "In4.Cu" "In6.Cu" "In11.Cu" "In13.Cu" "In15.Cu")
		(hatch none 0.5)
		(connect_pads
			(clearance 0)
		)
		(min_thickness 0.25)
		(keepout
			(tracks not_allowed)
			(vias allowed)
			(pads allowed)
			(copperpour not_allowed)
			(footprints allowed)
		)
		(placement
			(enabled no)
			(sheetname "")
		)
		(fill yes
			(thermal_gap 0.5)
			(thermal_bridge_width 0.5)
			(island_removal_mode 0)
		)
		(polygon
			(pts
				(arc
					(start 425.086272 -265.316716)
					(mid 424.433492 -265.316716)
					(end 425.086272 -265.316716)
				)
			)
		)
	)
	(zone
		(layers "B.Cu" "In4.Cu" "In6.Cu" "In11.Cu" "In13.Cu" "In15.Cu")
		(hatch none 0.5)
		(connect_pads
			(clearance 0)
		)
		(min_thickness 0.25)
		(keepout
			(tracks not_allowed)
			(vias allowed)
			(pads allowed)
			(copperpour not_allowed)
			(footprints allowed)
		)
		(placement
			(enabled no)
			(sheetname "")
		)
		(fill yes
			(thermal_gap 0.5)
			(thermal_bridge_width 0.5)
			(island_removal_mode 0)
		)
		(polygon
			(pts
				(arc
					(start 328.837798 -400.858228)
					(mid 328.134218 -400.858228)
					(end 328.837798 -400.858228)
				)
			)
		)
	)
	(zone
		(layers "B.Cu" "In4.Cu" "In6.Cu" "In11.Cu" "In13.Cu" "In15.Cu")
		(hatch none 0.5)
		(connect_pads
			(clearance 0)
		)
		(min_thickness 0.25)
		(keepout
			(tracks not_allowed)
			(vias allowed)
			(pads allowed)
			(copperpour not_allowed)
			(footprints allowed)
		)
		(placement
			(enabled no)
			(sheetname "")
		)
		(fill yes
			(thermal_gap 0.5)
			(thermal_bridge_width 0.5)
			(island_removal_mode 0)
		)
		(polygon
			(pts
				(arc
					(start 299.330872 -216.016586)
					(mid 298.678092 -216.016586)
					(end 299.330872 -216.016586)
				)
			)
		)
	)
	(zone
		(layers "B.Cu" "In4.Cu" "In6.Cu" "In11.Cu" "In13.Cu" "In15.Cu")
		(hatch none 0.5)
		(connect_pads
			(clearance 0)
		)
		(min_thickness 0.25)
		(keepout
			(tracks not_allowed)
			(vias allowed)
			(pads allowed)
			(copperpour not_allowed)
			(footprints allowed)
		)
		(placement
			(enabled no)
			(sheetname "")
		)
		(fill yes
			(thermal_gap 0.5)
			(thermal_bridge_width 0.5)
			(island_removal_mode 0)
		)
		(polygon
			(pts
				(arc
					(start 338.871052 -271.011396)
					(mid 338.218272 -271.011396)
					(end 338.871052 -271.011396)
				)
			)
		)
	)
	(zone
		(layers "B.Cu" "In4.Cu" "In6.Cu" "In11.Cu" "In13.Cu" "In15.Cu")
		(hatch none 0.5)
		(connect_pads
			(clearance 0)
		)
		(min_thickness 0.25)
		(keepout
			(tracks not_allowed)
			(vias allowed)
			(pads allowed)
			(copperpour not_allowed)
			(footprints allowed)
		)
		(placement
			(enabled no)
			(sheetname "")
		)
		(fill yes
			(thermal_gap 0.5)
			(thermal_bridge_width 0.5)
			(island_removal_mode 0)
		)
		(polygon
			(pts
				(arc
					(start 338.291424 -229.272846)
					(mid 337.638644 -229.272846)
					(end 338.291424 -229.272846)
				)
			)
		)
	)
	(zone
		(layers "B.Cu" "In4.Cu" "In6.Cu" "In11.Cu" "In13.Cu" "In15.Cu")
		(hatch none 0.5)
		(connect_pads
			(clearance 0)
		)
		(min_thickness 0.25)
		(keepout
			(tracks not_allowed)
			(vias allowed)
			(pads allowed)
			(copperpour not_allowed)
			(footprints allowed)
		)
		(placement
			(enabled no)
			(sheetname "")
		)
		(fill yes
			(thermal_gap 0.5)
			(thermal_bridge_width 0.5)
			(island_removal_mode 0)
		)
		(polygon
			(pts
				(arc
					(start 134.161784 -272.639282)
					(mid 133.509004 -272.639282)
					(end 134.161784 -272.639282)
				)
			)
		)
	)
	(zone
		(layers "B.Cu" "In4.Cu" "In6.Cu" "In11.Cu" "In13.Cu" "In15.Cu")
		(hatch none 0.5)
		(connect_pads
			(clearance 0)
		)
		(min_thickness 0.25)
		(keepout
			(tracks not_allowed)
			(vias allowed)
			(pads allowed)
			(copperpour not_allowed)
			(footprints allowed)
		)
		(placement
			(enabled no)
			(sheetname "")
		)
		(fill yes
			(thermal_gap 0.5)
			(thermal_bridge_width 0.5)
			(island_removal_mode 0)
		)
		(polygon
			(pts
				(arc
					(start 47.290736 -215.166702)
					(mid 46.637956 -215.166702)
					(end 47.290736 -215.166702)
				)
			)
		)
	)
	(zone
		(layers "B.Cu" "In4.Cu" "In6.Cu" "In11.Cu" "In13.Cu" "In15.Cu")
		(hatch none 0.5)
		(connect_pads
			(clearance 0)
		)
		(min_thickness 0.25)
		(keepout
			(tracks not_allowed)
			(vias allowed)
			(pads allowed)
			(copperpour not_allowed)
			(footprints allowed)
		)
		(placement
			(enabled no)
			(sheetname "")
		)
		(fill yes
			(thermal_gap 0.5)
			(thermal_bridge_width 0.5)
			(island_removal_mode 0)
		)
		(polygon
			(pts
				(arc
					(start 341.156798 0.815594)
					(mid 340.453218 0.815594)
					(end 341.156798 0.815594)
				)
			)
		)
	)
	(zone
		(layers "B.Cu" "In4.Cu" "In6.Cu" "In11.Cu" "In13.Cu" "In15.Cu")
		(hatch none 0.5)
		(connect_pads
			(clearance 0)
		)
		(min_thickness 0.25)
		(keepout
			(tracks not_allowed)
			(vias allowed)
			(pads allowed)
			(copperpour not_allowed)
			(footprints allowed)
		)
		(placement
			(enabled no)
			(sheetname "")
		)
		(fill yes
			(thermal_gap 0.5)
			(thermal_bridge_width 0.5)
			(island_removal_mode 0)
		)
		(polygon
			(pts
				(arc
					(start 339.231224 -227.64496)
					(mid 338.578444 -227.64496)
					(end 339.231224 -227.64496)
				)
			)
		)
	)
	(zone
		(layers "B.Cu" "In4.Cu" "In6.Cu" "In11.Cu" "In13.Cu" "In15.Cu")
		(hatch none 0.5)
		(connect_pads
			(clearance 0)
		)
		(min_thickness 0.25)
		(keepout
			(tracks not_allowed)
			(vias allowed)
			(pads allowed)
			(copperpour not_allowed)
			(footprints allowed)
		)
		(placement
			(enabled no)
			(sheetname "")
		)
		(fill yes
			(thermal_gap 0.5)
			(thermal_bridge_width 0.5)
			(island_removal_mode 0)
		)
		(polygon
			(pts
				(arc
					(start 342.160606 -286.475424)
					(mid 341.507826 -286.475424)
					(end 342.160606 -286.475424)
				)
			)
		)
	)
	(zone
		(layers "B.Cu" "In4.Cu" "In6.Cu" "In11.Cu" "In13.Cu" "In15.Cu")
		(hatch none 0.5)
		(connect_pads
			(clearance 0)
		)
		(min_thickness 0.25)
		(keepout
			(tracks not_allowed)
			(vias allowed)
			(pads allowed)
			(copperpour not_allowed)
			(footprints allowed)
		)
		(placement
			(enabled no)
			(sheetname "")
		)
		(fill yes
			(thermal_gap 0.5)
			(thermal_bridge_width 0.5)
			(island_removal_mode 0)
		)
		(polygon
			(pts
				(arc
					(start 51.416204 -293.366952)
					(mid 50.763424 -293.366952)
					(end 51.416204 -293.366952)
				)
			)
		)
	)
	(zone
		(layers "B.Cu" "In4.Cu" "In6.Cu" "In11.Cu" "In13.Cu" "In15.Cu")
		(hatch none 0.5)
		(connect_pads
			(clearance 0)
		)
		(min_thickness 0.25)
		(keepout
			(tracks not_allowed)
			(vias allowed)
			(pads allowed)
			(copperpour not_allowed)
			(footprints allowed)
		)
		(placement
			(enabled no)
			(sheetname "")
		)
		(fill yes
			(thermal_gap 0.5)
			(thermal_bridge_width 0.5)
			(island_removal_mode 0)
		)
		(polygon
			(pts
				(arc
					(start 47.290736 -237.266734)
					(mid 46.637956 -237.266734)
					(end 47.290736 -237.266734)
				)
			)
		)
	)
	(zone
		(layers "B.Cu" "In4.Cu" "In6.Cu" "In11.Cu" "In13.Cu" "In15.Cu")
		(hatch none 0.5)
		(connect_pads
			(clearance 0)
		)
		(min_thickness 0.25)
		(keepout
			(tracks not_allowed)
			(vias allowed)
			(pads allowed)
			(copperpour not_allowed)
			(footprints allowed)
		)
		(placement
			(enabled no)
			(sheetname "")
		)
		(fill yes
			(thermal_gap 0.5)
			(thermal_bridge_width 0.5)
			(island_removal_mode 0)
		)
		(polygon
			(pts
				(arc
					(start 346.859606 -284.847538)
					(mid 346.206826 -284.847538)
					(end 346.859606 -284.847538)
				)
			)
		)
	)
	(zone
		(layers "B.Cu" "In4.Cu" "In6.Cu" "In11.Cu" "In13.Cu" "In15.Cu")
		(hatch none 0.5)
		(connect_pads
			(clearance 0)
		)
		(min_thickness 0.25)
		(keepout
			(tracks not_allowed)
			(vias allowed)
			(pads allowed)
			(copperpour not_allowed)
			(footprints allowed)
		)
		(placement
			(enabled no)
			(sheetname "")
		)
		(fill yes
			(thermal_gap 0.5)
			(thermal_bridge_width 0.5)
			(island_removal_mode 0)
		)
		(polygon
			(pts
				(arc
					(start 343.100406 -284.847538)
					(mid 342.447626 -284.847538)
					(end 343.100406 -284.847538)
				)
			)
		)
	)
	(zone
		(layers "B.Cu" "In4.Cu" "In6.Cu" "In11.Cu" "In13.Cu" "In15.Cu")
		(hatch none 0.5)
		(connect_pads
			(clearance 0)
		)
		(min_thickness 0.25)
		(keepout
			(tracks not_allowed)
			(vias allowed)
			(pads allowed)
			(copperpour not_allowed)
			(footprints allowed)
		)
		(placement
			(enabled no)
			(sheetname "")
		)
		(fill yes
			(thermal_gap 0.5)
			(thermal_bridge_width 0.5)
			(island_removal_mode 0)
		)
		(polygon
			(pts
				(arc
					(start 135.461756 -239.0394)
					(mid 134.808976 -239.0394)
					(end 135.461756 -239.0394)
				)
			)
		)
	)
	(zone
		(layers "B.Cu" "In4.Cu" "In6.Cu" "In11.Cu" "In13.Cu" "In15.Cu")
		(hatch none 0.5)
		(connect_pads
			(clearance 0)
		)
		(min_thickness 0.25)
		(keepout
			(tracks not_allowed)
			(vias allowed)
			(pads allowed)
			(copperpour not_allowed)
			(footprints allowed)
		)
		(placement
			(enabled no)
			(sheetname "")
		)
		(fill yes
			(thermal_gap 0.5)
			(thermal_bridge_width 0.5)
			(island_removal_mode 0)
		)
		(polygon
			(pts
				(arc
					(start 383.401824 -245.55069)
					(mid 382.749044 -245.55069)
					(end 383.401824 -245.55069)
				)
			)
		)
	)
	(zone
		(layers "B.Cu" "In4.Cu" "In6.Cu" "In11.Cu" "In13.Cu" "In15.Cu")
		(hatch none 0.5)
		(connect_pads
			(clearance 0)
		)
		(min_thickness 0.25)
		(keepout
			(tracks not_allowed)
			(vias allowed)
			(pads allowed)
			(copperpour not_allowed)
			(footprints allowed)
		)
		(placement
			(enabled no)
			(sheetname "")
		)
		(fill yes
			(thermal_gap 0.5)
			(thermal_bridge_width 0.5)
			(island_removal_mode 0)
		)
		(polygon
			(pts
				(arc
					(start 291.787072 -267.016738)
					(mid 291.134292 -267.016738)
					(end 291.787072 -267.016738)
				)
			)
		)
	)
	(zone
		(layers "B.Cu" "In4.Cu" "In6.Cu" "In11.Cu" "In13.Cu" "In15.Cu")
		(hatch none 0.5)
		(connect_pads
			(clearance 0)
		)
		(min_thickness 0.25)
		(keepout
			(tracks not_allowed)
			(vias allowed)
			(pads allowed)
			(copperpour not_allowed)
			(footprints allowed)
		)
		(placement
			(enabled no)
			(sheetname "")
		)
		(fill yes
			(thermal_gap 0.5)
			(thermal_bridge_width 0.5)
			(island_removal_mode 0)
		)
		(polygon
			(pts
				(arc
					(start 425.162472 -261.916672)
					(mid 424.509692 -261.916672)
					(end 425.162472 -261.916672)
				)
			)
		)
	)
	(zone
		(layers "B.Cu" "In4.Cu" "In6.Cu" "In11.Cu" "In13.Cu" "In15.Cu")
		(hatch none 0.5)
		(connect_pads
			(clearance 0)
		)
		(min_thickness 0.25)
		(keepout
			(tracks not_allowed)
			(vias allowed)
			(pads allowed)
			(copperpour not_allowed)
			(footprints allowed)
		)
		(placement
			(enabled no)
			(sheetname "")
		)
		(fill yes
			(thermal_gap 0.5)
			(thermal_bridge_width 0.5)
			(island_removal_mode 0)
		)
		(polygon
			(pts
				(arc
					(start 338.76107 -226.831144)
					(mid 338.10829 -226.831144)
					(end 338.76107 -226.831144)
				)
			)
		)
	)
	(zone
		(layers "B.Cu" "In4.Cu" "In6.Cu" "In11.Cu" "In13.Cu" "In15.Cu")
		(hatch none 0.5)
		(connect_pads
			(clearance 0)
		)
		(min_thickness 0.25)
		(keepout
			(tracks not_allowed)
			(vias allowed)
			(pads allowed)
			(copperpour not_allowed)
			(footprints allowed)
		)
		(placement
			(enabled no)
			(sheetname "")
		)
		(fill yes
			(thermal_gap 0.5)
			(thermal_bridge_width 0.5)
			(island_removal_mode 0)
		)
		(polygon
			(pts
				(arc
					(start 58.99912 -19.13636)
					(mid 58.29554 -19.13636)
					(end 58.99912 -19.13636)
				)
			)
		)
	)
	(zone
		(layers "B.Cu" "In4.Cu" "In6.Cu" "In11.Cu" "In13.Cu" "In15.Cu")
		(hatch none 0.5)
		(connect_pads
			(clearance 0)
		)
		(min_thickness 0.25)
		(keepout
			(tracks not_allowed)
			(vias allowed)
			(pads allowed)
			(copperpour not_allowed)
			(footprints allowed)
		)
		(placement
			(enabled no)
			(sheetname "")
		)
		(fill yes
			(thermal_gap 0.5)
			(thermal_bridge_width 0.5)
			(island_removal_mode 0)
		)
		(polygon
			(pts
				(arc
					(start 137.341356 -221.133924)
					(mid 136.688576 -221.133924)
					(end 137.341356 -221.133924)
				)
			)
		)
	)
	(zone
		(layers "B.Cu" "In4.Cu" "In6.Cu" "In11.Cu" "In13.Cu" "In15.Cu")
		(hatch none 0.5)
		(connect_pads
			(clearance 0)
		)
		(min_thickness 0.25)
		(keepout
			(tracks not_allowed)
			(vias allowed)
			(pads allowed)
			(copperpour not_allowed)
			(footprints allowed)
		)
		(placement
			(enabled no)
			(sheetname "")
		)
		(fill yes
			(thermal_gap 0.5)
			(thermal_bridge_width 0.5)
			(island_removal_mode 0)
		)
		(polygon
			(pts
				(arc
					(start 177.222404 -212.616796)
					(mid 176.569624 -212.616796)
					(end 177.222404 -212.616796)
				)
			)
		)
	)
	(zone
		(layers "B.Cu" "In4.Cu" "In6.Cu" "In11.Cu" "In13.Cu" "In15.Cu")
		(hatch none 0.5)
		(connect_pads
			(clearance 0)
		)
		(min_thickness 0.25)
		(keepout
			(tracks not_allowed)
			(vias allowed)
			(pads allowed)
			(copperpour not_allowed)
			(footprints allowed)
		)
		(placement
			(enabled no)
			(sheetname "")
		)
		(fill yes
			(thermal_gap 0.5)
			(thermal_bridge_width 0.5)
			(island_removal_mode 0)
		)
		(polygon
			(pts
				(arc
					(start 339.340952 -284.847538)
					(mid 338.688172 -284.847538)
					(end 339.340952 -284.847538)
				)
			)
		)
	)
	(zone
		(layers "B.Cu" "In4.Cu" "In6.Cu" "In11.Cu" "In13.Cu" "In15.Cu")
		(hatch none 0.5)
		(connect_pads
			(clearance 0)
		)
		(min_thickness 0.25)
		(keepout
			(tracks not_allowed)
			(vias allowed)
			(pads allowed)
			(copperpour not_allowed)
			(footprints allowed)
		)
		(placement
			(enabled no)
			(sheetname "")
		)
		(fill yes
			(thermal_gap 0.5)
			(thermal_bridge_width 0.5)
			(island_removal_mode 0)
		)
		(polygon
			(pts
				(arc
					(start 425.162472 -292.51656)
					(mid 424.509692 -292.51656)
					(end 425.162472 -292.51656)
				)
			)
		)
	)
	(zone
		(layers "B.Cu" "In4.Cu" "In6.Cu" "In11.Cu" "In13.Cu" "In15.Cu")
		(hatch none 0.5)
		(connect_pads
			(clearance 0)
		)
		(min_thickness 0.25)
		(keepout
			(tracks not_allowed)
			(vias allowed)
			(pads allowed)
			(copperpour not_allowed)
			(footprints allowed)
		)
		(placement
			(enabled no)
			(sheetname "")
		)
		(fill yes
			(thermal_gap 0.5)
			(thermal_bridge_width 0.5)
			(island_removal_mode 0)
		)
		(polygon
			(pts
				(arc
					(start 51.416204 -292.516814)
					(mid 50.763424 -292.516814)
					(end 51.416204 -292.516814)
				)
			)
		)
	)
	(zone
		(layers "B.Cu" "In4.Cu" "In6.Cu" "In11.Cu" "In13.Cu" "In15.Cu")
		(hatch none 0.5)
		(connect_pads
			(clearance 0)
		)
		(min_thickness 0.25)
		(keepout
			(tracks not_allowed)
			(vias allowed)
			(pads allowed)
			(copperpour not_allowed)
			(footprints allowed)
		)
		(placement
			(enabled no)
			(sheetname "")
		)
		(fill yes
			(thermal_gap 0.5)
			(thermal_bridge_width 0.5)
			(island_removal_mode 0)
		)
		(polygon
			(pts
				(arc
					(start 336.88147 -226.831144)
					(mid 336.22869 -226.831144)
					(end 336.88147 -226.831144)
				)
			)
		)
	)
	(zone
		(layers "B.Cu" "In4.Cu" "In6.Cu" "In11.Cu" "In13.Cu" "In15.Cu")
		(hatch none 0.5)
		(connect_pads
			(clearance 0)
		)
		(min_thickness 0.25)
		(keepout
			(tracks not_allowed)
			(vias allowed)
			(pads allowed)
			(copperpour not_allowed)
			(footprints allowed)
		)
		(placement
			(enabled no)
			(sheetname "")
		)
		(fill yes
			(thermal_gap 0.5)
			(thermal_bridge_width 0.5)
			(island_removal_mode 0)
		)
		(polygon
			(pts
				(arc
					(start 358.49687 -225.203258)
					(mid 357.84409 -225.203258)
					(end 358.49687 -225.203258)
				)
			)
		)
	)
	(zone
		(layers "B.Cu" "In4.Cu" "In6.Cu" "In11.Cu" "In13.Cu" "In15.Cu")
		(hatch none 0.5)
		(connect_pads
			(clearance 0)
		)
		(min_thickness 0.25)
		(keepout
			(tracks not_allowed)
			(vias allowed)
			(pads allowed)
			(copperpour not_allowed)
			(footprints allowed)
		)
		(placement
			(enabled no)
			(sheetname "")
		)
		(fill yes
			(thermal_gap 0.5)
			(thermal_bridge_width 0.5)
			(island_removal_mode 0)
		)
		(polygon
			(pts
				(arc
					(start 43.847004 -267.016738)
					(mid 43.194224 -267.016738)
					(end 43.847004 -267.016738)
				)
			)
		)
	)
	(zone
		(layers "B.Cu" "In4.Cu" "In6.Cu" "In11.Cu" "In13.Cu" "In15.Cu")
		(hatch none 0.5)
		(connect_pads
			(clearance 0)
		)
		(min_thickness 0.25)
		(keepout
			(tracks not_allowed)
			(vias allowed)
			(pads allowed)
			(copperpour not_allowed)
			(footprints allowed)
		)
		(placement
			(enabled no)
			(sheetname "")
		)
		(fill yes
			(thermal_gap 0.5)
			(thermal_bridge_width 0.5)
			(island_removal_mode 0)
		)
		(polygon
			(pts
				(arc
					(start 173.122336 -245.76659)
					(mid 172.469556 -245.76659)
					(end 173.122336 -245.76659)
				)
			)
		)
	)
	(zone
		(layers "B.Cu" "In4.Cu" "In6.Cu" "In11.Cu" "In13.Cu" "In15.Cu")
		(hatch none 0.5)
		(connect_pads
			(clearance 0)
		)
		(min_thickness 0.25)
		(keepout
			(tracks not_allowed)
			(vias allowed)
			(pads allowed)
			(copperpour not_allowed)
			(footprints allowed)
		)
		(placement
			(enabled no)
			(sheetname "")
		)
		(fill yes
			(thermal_gap 0.5)
			(thermal_bridge_width 0.5)
			(island_removal_mode 0)
		)
		(polygon
			(pts
				(arc
					(start 138.751056 -223.575626)
					(mid 138.098276 -223.575626)
					(end 138.751056 -223.575626)
				)
			)
		)
	)
	(zone
		(layers "B.Cu" "In4.Cu" "In6.Cu" "In11.Cu" "In13.Cu" "In15.Cu")
		(hatch none 0.5)
		(connect_pads
			(clearance 0)
		)
		(min_thickness 0.25)
		(keepout
			(tracks not_allowed)
			(vias allowed)
			(pads allowed)
			(copperpour not_allowed)
			(footprints allowed)
		)
		(placement
			(enabled no)
			(sheetname "")
		)
		(fill yes
			(thermal_gap 0.5)
			(thermal_bridge_width 0.5)
			(island_removal_mode 0)
		)
		(polygon
			(pts
				(arc
					(start 51.416204 -309.51678)
					(mid 50.763424 -309.51678)
					(end 51.416204 -309.51678)
				)
			)
		)
	)
	(zone
		(layers "B.Cu" "In4.Cu" "In6.Cu" "In11.Cu" "In13.Cu" "In15.Cu")
		(hatch none 0.5)
		(connect_pads
			(clearance 0)
		)
		(min_thickness 0.25)
		(keepout
			(tracks not_allowed)
			(vias allowed)
			(pads allowed)
			(copperpour not_allowed)
			(footprints allowed)
		)
		(placement
			(enabled no)
			(sheetname "")
		)
		(fill yes
			(thermal_gap 0.5)
			(thermal_bridge_width 0.5)
			(island_removal_mode 0)
		)
		(polygon
			(pts
				(arc
					(start 162.109404 -227.066602)
					(mid 161.456624 -227.066602)
					(end 162.109404 -227.066602)
				)
			)
		)
	)
	(zone
		(layers "B.Cu" "In4.Cu" "In6.Cu" "In11.Cu" "In13.Cu" "In15.Cu")
		(hatch none 0.5)
		(connect_pads
			(clearance 0)
		)
		(min_thickness 0.25)
		(keepout
			(tracks not_allowed)
			(vias allowed)
			(pads allowed)
			(copperpour not_allowed)
			(footprints allowed)
		)
		(placement
			(enabled no)
			(sheetname "")
		)
		(fill yes
			(thermal_gap 0.5)
			(thermal_bridge_width 0.5)
			(island_removal_mode 0)
		)
		(polygon
			(pts
				(arc
					(start 89.051384 -259.616956)
					(mid 88.398604 -259.616956)
					(end 89.051384 -259.616956)
				)
			)
		)
	)
	(zone
		(layers "B.Cu" "In4.Cu" "In6.Cu" "In11.Cu" "In13.Cu" "In15.Cu")
		(hatch none 0.5)
		(connect_pads
			(clearance 0)
		)
		(min_thickness 0.25)
		(keepout
			(tracks not_allowed)
			(vias allowed)
			(pads allowed)
			(copperpour not_allowed)
			(footprints allowed)
		)
		(placement
			(enabled no)
			(sheetname "")
		)
		(fill yes
			(thermal_gap 0.5)
			(thermal_bridge_width 0.5)
			(island_removal_mode 0)
		)
		(polygon
			(pts
				(arc
					(start 337.351624 -243.922804)
					(mid 336.698844 -243.922804)
					(end 337.351624 -243.922804)
				)
			)
		)
	)
	(zone
		(layers "B.Cu" "In4.Cu" "In6.Cu" "In11.Cu" "In13.Cu" "In15.Cu")
		(hatch none 0.5)
		(connect_pads
			(clearance 0)
		)
		(min_thickness 0.25)
		(keepout
			(tracks not_allowed)
			(vias allowed)
			(pads allowed)
			(copperpour not_allowed)
			(footprints allowed)
		)
		(placement
			(enabled no)
			(sheetname "")
		)
		(fill yes
			(thermal_gap 0.5)
			(thermal_bridge_width 0.5)
			(island_removal_mode 0)
		)
		(polygon
			(pts
				(arc
					(start 383.041652 -269.38351)
					(mid 382.388872 -269.38351)
					(end 383.041652 -269.38351)
				)
			)
		)
	)
	(zone
		(layers "B.Cu" "In4.Cu" "In6.Cu" "In11.Cu" "In13.Cu" "In15.Cu")
		(hatch none 0.5)
		(connect_pads
			(clearance 0)
		)
		(min_thickness 0.25)
		(keepout
			(tracks not_allowed)
			(vias allowed)
			(pads allowed)
			(copperpour not_allowed)
			(footprints allowed)
		)
		(placement
			(enabled no)
			(sheetname "")
		)
		(fill yes
			(thermal_gap 0.5)
			(thermal_bridge_width 0.5)
			(island_removal_mode 0)
		)
		(polygon
			(pts
				(arc
					(start 339.341206 -255.547622)
					(mid 338.688426 -255.547622)
					(end 339.341206 -255.547622)
				)
			)
		)
	)
	(zone
		(layers "B.Cu" "In4.Cu" "In6.Cu" "In11.Cu" "In13.Cu" "In15.Cu")
		(hatch none 0.5)
		(connect_pads
			(clearance 0)
		)
		(min_thickness 0.25)
		(keepout
			(tracks not_allowed)
			(vias allowed)
			(pads allowed)
			(copperpour not_allowed)
			(footprints allowed)
		)
		(placement
			(enabled no)
			(sheetname "")
		)
		(fill yes
			(thermal_gap 0.5)
			(thermal_bridge_width 0.5)
			(island_removal_mode 0)
		)
		(polygon
			(pts
				(arc
					(start 177.222404 -208.366614)
					(mid 176.569624 -208.366614)
					(end 177.222404 -208.366614)
				)
			)
		)
	)
	(zone
		(layers "B.Cu" "In4.Cu" "In6.Cu" "In11.Cu" "In13.Cu" "In15.Cu")
		(hatch none 0.5)
		(connect_pads
			(clearance 0)
		)
		(min_thickness 0.25)
		(keepout
			(tracks not_allowed)
			(vias allowed)
			(pads allowed)
			(copperpour not_allowed)
			(footprints allowed)
		)
		(placement
			(enabled no)
			(sheetname "")
		)
		(fill yes
			(thermal_gap 0.5)
			(thermal_bridge_width 0.5)
			(island_removal_mode 0)
		)
		(polygon
			(pts
				(arc
					(start 425.162472 -248.31675)
					(mid 424.509692 -248.31675)
					(end 425.162472 -248.31675)
				)
			)
		)
	)
	(zone
		(layers "B.Cu" "In4.Cu" "In6.Cu" "In11.Cu" "In13.Cu" "In15.Cu")
		(hatch none 0.5)
		(connect_pads
			(clearance 0)
		)
		(min_thickness 0.25)
		(keepout
			(tracks not_allowed)
			(vias allowed)
			(pads allowed)
			(copperpour not_allowed)
			(footprints allowed)
		)
		(placement
			(enabled no)
			(sheetname "")
		)
		(fill yes
			(thermal_gap 0.5)
			(thermal_bridge_width 0.5)
			(island_removal_mode 0)
		)
		(polygon
			(pts
				(arc
					(start 425.162472 -289.11677)
					(mid 424.509692 -289.11677)
					(end 425.162472 -289.11677)
				)
			)
		)
	)
	(zone
		(layers "B.Cu" "In4.Cu" "In6.Cu" "In11.Cu" "In13.Cu" "In15.Cu")
		(hatch none 0.5)
		(connect_pads
			(clearance 0)
		)
		(min_thickness 0.25)
		(keepout
			(tracks not_allowed)
			(vias allowed)
			(pads allowed)
			(copperpour not_allowed)
			(footprints allowed)
		)
		(placement
			(enabled no)
			(sheetname "")
		)
		(fill yes
			(thermal_gap 0.5)
			(thermal_bridge_width 0.5)
			(island_removal_mode 0)
		)
		(polygon
			(pts
				(arc
					(start 158.009336 -305.266598)
					(mid 157.356556 -305.266598)
					(end 158.009336 -305.266598)
				)
			)
		)
	)
	(zone
		(layers "B.Cu" "In4.Cu" "In6.Cu" "In11.Cu" "In13.Cu" "In15.Cu")
		(hatch none 0.5)
		(connect_pads
			(clearance 0)
		)
		(min_thickness 0.25)
		(keepout
			(tracks not_allowed)
			(vias allowed)
			(pads allowed)
			(copperpour not_allowed)
			(footprints allowed)
		)
		(placement
			(enabled no)
			(sheetname "")
		)
		(fill yes
			(thermal_gap 0.5)
			(thermal_bridge_width 0.5)
			(island_removal_mode 0)
		)
		(polygon
			(pts
				(arc
					(start 111.496602 -223.575626)
					(mid 110.843822 -223.575626)
					(end 111.496602 -223.575626)
				)
			)
		)
	)
	(zone
		(layers "B.Cu" "In4.Cu" "In6.Cu" "In11.Cu" "In13.Cu" "In15.Cu")
		(hatch none 0.5)
		(connect_pads
			(clearance 0)
		)
		(min_thickness 0.25)
		(keepout
			(tracks not_allowed)
			(vias allowed)
			(pads allowed)
			(copperpour not_allowed)
			(footprints allowed)
		)
		(placement
			(enabled no)
			(sheetname "")
		)
		(fill yes
			(thermal_gap 0.5)
			(thermal_bridge_width 0.5)
			(island_removal_mode 0)
		)
		(polygon
			(pts
				(arc
					(start 295.230804 -219.41663)
					(mid 294.578024 -219.41663)
					(end 295.230804 -219.41663)
				)
			)
		)
	)
	(zone
		(layers "B.Cu" "In4.Cu" "In6.Cu" "In11.Cu" "In13.Cu" "In15.Cu")
		(hatch none 0.5)
		(connect_pads
			(clearance 0)
		)
		(min_thickness 0.25)
		(keepout
			(tracks not_allowed)
			(vias allowed)
			(pads allowed)
			(copperpour not_allowed)
			(footprints allowed)
		)
		(placement
			(enabled no)
			(sheetname "")
		)
		(fill yes
			(thermal_gap 0.5)
			(thermal_bridge_width 0.5)
			(island_removal_mode 0)
		)
		(polygon
			(pts
				(arc
					(start 92.810584 -285.661354)
					(mid 92.157804 -285.661354)
					(end 92.810584 -285.661354)
				)
			)
		)
	)
	(zone
		(layers "B.Cu" "In4.Cu" "In6.Cu" "In11.Cu" "In13.Cu" "In15.Cu")
		(hatch none 0.5)
		(connect_pads
			(clearance 0)
		)
		(min_thickness 0.25)
		(keepout
			(tracks not_allowed)
			(vias allowed)
			(pads allowed)
			(copperpour not_allowed)
			(footprints allowed)
		)
		(placement
			(enabled no)
			(sheetname "")
		)
		(fill yes
			(thermal_gap 0.5)
			(thermal_bridge_width 0.5)
			(island_removal_mode 0)
		)
		(polygon
			(pts
				(arc
					(start 88.941402 -231.714548)
					(mid 88.288622 -231.714548)
					(end 88.941402 -231.714548)
				)
			)
		)
	)
	(zone
		(layers "B.Cu" "In4.Cu" "In6.Cu" "In11.Cu" "In13.Cu" "In15.Cu")
		(hatch none 0.5)
		(connect_pads
			(clearance 0)
		)
		(min_thickness 0.25)
		(keepout
			(tracks not_allowed)
			(vias allowed)
			(pads allowed)
			(copperpour not_allowed)
			(footprints allowed)
		)
		(placement
			(enabled no)
			(sheetname "")
		)
		(fill yes
			(thermal_gap 0.5)
			(thermal_bridge_width 0.5)
			(island_removal_mode 0)
		)
		(polygon
			(pts
				(arc
					(start 337.931252 -285.661354)
					(mid 337.278472 -285.661354)
					(end 337.931252 -285.661354)
				)
			)
		)
	)
	(zone
		(layers "B.Cu" "In4.Cu" "In6.Cu" "In11.Cu" "In13.Cu" "In15.Cu")
		(hatch none 0.5)
		(connect_pads
			(clearance 0)
		)
		(min_thickness 0.25)
		(keepout
			(tracks not_allowed)
			(vias allowed)
			(pads allowed)
			(copperpour not_allowed)
			(footprints allowed)
		)
		(placement
			(enabled no)
			(sheetname "")
		)
		(fill yes
			(thermal_gap 0.5)
			(thermal_bridge_width 0.5)
			(island_removal_mode 0)
		)
		(polygon
			(pts
				(arc
					(start 130.872738 -284.847538)
					(mid 130.219958 -284.847538)
					(end 130.872738 -284.847538)
				)
			)
		)
	)
	(zone
		(layers "B.Cu" "In4.Cu" "In6.Cu" "In11.Cu" "In13.Cu" "In15.Cu")
		(hatch none 0.5)
		(connect_pads
			(clearance 0)
		)
		(min_thickness 0.25)
		(keepout
			(tracks not_allowed)
			(vias allowed)
			(pads allowed)
			(copperpour not_allowed)
			(footprints allowed)
		)
		(placement
			(enabled no)
			(sheetname "")
		)
		(fill yes
			(thermal_gap 0.5)
			(thermal_bridge_width 0.5)
			(island_removal_mode 0)
		)
		(polygon
			(pts
				(arc
					(start 395.4272 -407.00452)
					(mid 394.72362 -407.00452)
					(end 395.4272 -407.00452)
				)
			)
		)
	)
	(zone
		(layers "B.Cu" "In4.Cu" "In6.Cu" "In11.Cu" "In13.Cu" "In15.Cu")
		(hatch none 0.5)
		(connect_pads
			(clearance 0)
		)
		(min_thickness 0.25)
		(keepout
			(tracks not_allowed)
			(vias allowed)
			(pads allowed)
			(copperpour not_allowed)
			(footprints allowed)
		)
		(placement
			(enabled no)
			(sheetname "")
		)
		(fill yes
			(thermal_gap 0.5)
			(thermal_bridge_width 0.5)
			(island_removal_mode 0)
		)
		(polygon
			(pts
				(arc
					(start 136.041384 -262.872474)
					(mid 135.388604 -262.872474)
					(end 136.041384 -262.872474)
				)
			)
		)
	)
	(zone
		(layers "B.Cu" "In4.Cu" "In6.Cu" "In11.Cu" "In13.Cu" "In15.Cu")
		(hatch none 0.5)
		(connect_pads
			(clearance 0)
		)
		(min_thickness 0.25)
		(keepout
			(tracks not_allowed)
			(vias allowed)
			(pads allowed)
			(copperpour not_allowed)
			(footprints allowed)
		)
		(placement
			(enabled no)
			(sheetname "")
		)
		(fill yes
			(thermal_gap 0.5)
			(thermal_bridge_width 0.5)
			(island_removal_mode 0)
		)
		(polygon
			(pts
				(arc
					(start 107.267756 -224.389442)
					(mid 106.614976 -224.389442)
					(end 107.267756 -224.389442)
				)
			)
		)
	)
	(zone
		(layers "B.Cu" "In4.Cu" "In6.Cu" "In11.Cu" "In13.Cu" "In15.Cu")
		(hatch none 0.5)
		(connect_pads
			(clearance 0)
		)
		(min_thickness 0.25)
		(keepout
			(tracks not_allowed)
			(vias allowed)
			(pads allowed)
			(copperpour not_allowed)
			(footprints allowed)
		)
		(placement
			(enabled no)
			(sheetname "")
		)
		(fill yes
			(thermal_gap 0.5)
			(thermal_bridge_width 0.5)
			(island_removal_mode 0)
		)
		(polygon
			(pts
				(arc
					(start 410.049472 -302.716692)
					(mid 409.396692 -302.716692)
					(end 410.049472 -302.716692)
				)
			)
		)
	)
	(zone
		(layers "B.Cu" "In4.Cu" "In6.Cu" "In11.Cu" "In13.Cu" "In15.Cu")
		(hatch none 0.5)
		(connect_pads
			(clearance 0)
		)
		(min_thickness 0.25)
		(keepout
			(tracks not_allowed)
			(vias allowed)
			(pads allowed)
			(copperpour not_allowed)
			(footprints allowed)
		)
		(placement
			(enabled no)
			(sheetname "")
		)
		(fill yes
			(thermal_gap 0.5)
			(thermal_bridge_width 0.5)
			(island_removal_mode 0)
		)
		(polygon
			(pts
				(arc
					(start 90.351356 -230.900478)
					(mid 89.698576 -230.900478)
					(end 90.351356 -230.900478)
				)
			)
		)
	)
	(zone
		(layers "B.Cu" "In4.Cu" "In6.Cu" "In11.Cu" "In13.Cu" "In15.Cu")
		(hatch none 0.5)
		(connect_pads
			(clearance 0)
		)
		(min_thickness 0.25)
		(keepout
			(tracks not_allowed)
			(vias allowed)
			(pads allowed)
			(copperpour not_allowed)
			(footprints allowed)
		)
		(placement
			(enabled no)
			(sheetname "")
		)
		(fill yes
			(thermal_gap 0.5)
			(thermal_bridge_width 0.5)
			(island_removal_mode 0)
		)
		(polygon
			(pts
				(arc
					(start 425.162472 -296.766742)
					(mid 424.509692 -296.766742)
					(end 425.162472 -296.766742)
				)
			)
		)
	)
	(zone
		(layers "B.Cu" "In4.Cu" "In6.Cu" "In11.Cu" "In13.Cu" "In15.Cu")
		(hatch none 0.5)
		(connect_pads
			(clearance 0)
		)
		(min_thickness 0.25)
		(keepout
			(tracks not_allowed)
			(vias allowed)
			(pads allowed)
			(copperpour not_allowed)
			(footprints allowed)
		)
		(placement
			(enabled no)
			(sheetname "")
		)
		(fill yes
			(thermal_gap 0.5)
			(thermal_bridge_width 0.5)
			(island_removal_mode 0)
		)
		(polygon
			(pts
				(arc
					(start 336.88147 -233.34218)
					(mid 336.22869 -233.34218)
					(end 336.88147 -233.34218)
				)
			)
		)
	)
	(zone
		(layers "B.Cu" "In4.Cu" "In6.Cu" "In11.Cu" "In13.Cu" "In15.Cu")
		(hatch none 0.5)
		(connect_pads
			(clearance 0)
		)
		(min_thickness 0.25)
		(keepout
			(tracks not_allowed)
			(vias allowed)
			(pads allowed)
			(copperpour not_allowed)
			(footprints allowed)
		)
		(placement
			(enabled no)
			(sheetname "")
		)
		(fill yes
			(thermal_gap 0.5)
			(thermal_bridge_width 0.5)
			(island_removal_mode 0)
		)
		(polygon
			(pts
				(arc
					(start 89.521538 -271.825212)
					(mid 88.868758 -271.825212)
					(end 89.521538 -271.825212)
				)
			)
		)
	)
	(zone
		(layers "B.Cu" "In4.Cu" "In6.Cu" "In11.Cu" "In13.Cu" "In15.Cu")
		(hatch none 0.5)
		(connect_pads
			(clearance 0)
		)
		(min_thickness 0.25)
		(keepout
			(tracks not_allowed)
			(vias allowed)
			(pads allowed)
			(copperpour not_allowed)
			(footprints allowed)
		)
		(placement
			(enabled no)
			(sheetname "")
		)
		(fill yes
			(thermal_gap 0.5)
			(thermal_bridge_width 0.5)
			(island_removal_mode 0)
		)
		(polygon
			(pts
				(arc
					(start 89.499948 -407.00452)
					(mid 88.796368 -407.00452)
					(end 89.499948 -407.00452)
				)
			)
		)
	)
	(zone
		(layers "B.Cu" "In4.Cu" "In6.Cu" "In11.Cu" "In13.Cu" "In15.Cu")
		(hatch none 0.5)
		(connect_pads
			(clearance 0)
		)
		(min_thickness 0.25)
		(keepout
			(tracks not_allowed)
			(vias allowed)
			(pads allowed)
			(copperpour not_allowed)
			(footprints allowed)
		)
		(placement
			(enabled no)
			(sheetname "")
		)
		(fill yes
			(thermal_gap 0.5)
			(thermal_bridge_width 0.5)
			(island_removal_mode 0)
		)
		(polygon
			(pts
				(arc
					(start 177.222404 -289.11677)
					(mid 176.569624 -289.11677)
					(end 177.222404 -289.11677)
				)
			)
		)
	)
	(zone
		(layers "B.Cu" "In4.Cu" "In6.Cu" "In11.Cu" "In13.Cu" "In15.Cu")
		(hatch none 0.5)
		(connect_pads
			(clearance 0)
		)
		(min_thickness 0.25)
		(keepout
			(tracks not_allowed)
			(vias allowed)
			(pads allowed)
			(copperpour not_allowed)
			(footprints allowed)
		)
		(placement
			(enabled no)
			(sheetname "")
		)
		(fill yes
			(thermal_gap 0.5)
			(thermal_bridge_width 0.5)
			(island_removal_mode 0)
		)
		(polygon
			(pts
				(arc
					(start 381.992124 -246.364506)
					(mid 381.339344 -246.364506)
					(end 381.992124 -246.364506)
				)
			)
		)
	)
	(zone
		(layers "B.Cu" "In4.Cu" "In6.Cu" "In11.Cu" "In13.Cu" "In15.Cu")
		(hatch none 0.5)
		(connect_pads
			(clearance 0)
		)
		(min_thickness 0.25)
		(keepout
			(tracks not_allowed)
			(vias allowed)
			(pads allowed)
			(copperpour not_allowed)
			(footprints allowed)
		)
		(placement
			(enabled no)
			(sheetname "")
		)
		(fill yes
			(thermal_gap 0.5)
			(thermal_bridge_width 0.5)
			(island_removal_mode 0)
		)
		(polygon
			(pts
				(arc
					(start 177.222404 -276.366732)
					(mid 176.569624 -276.366732)
					(end 177.222404 -276.366732)
				)
			)
		)
	)
	(zone
		(layers "B.Cu" "In4.Cu" "In6.Cu" "In11.Cu" "In13.Cu" "In15.Cu")
		(hatch none 0.5)
		(connect_pads
			(clearance 0)
		)
		(min_thickness 0.25)
		(keepout
			(tracks not_allowed)
			(vias allowed)
			(pads allowed)
			(copperpour not_allowed)
			(footprints allowed)
		)
		(placement
			(enabled no)
			(sheetname "")
		)
		(fill yes
			(thermal_gap 0.5)
			(thermal_bridge_width 0.5)
			(island_removal_mode 0)
		)
		(polygon
			(pts
				(arc
					(start 338.291424 -227.64496)
					(mid 337.638644 -227.64496)
					(end 338.291424 -227.64496)
				)
			)
		)
	)
	(zone
		(layers "B.Cu" "In4.Cu" "In6.Cu" "In11.Cu" "In13.Cu" "In15.Cu")
		(hatch none 0.5)
		(connect_pads
			(clearance 0)
		)
		(min_thickness 0.25)
		(keepout
			(tracks not_allowed)
			(vias allowed)
			(pads allowed)
			(copperpour not_allowed)
			(footprints allowed)
		)
		(placement
			(enabled no)
			(sheetname "")
		)
		(fill yes
			(thermal_gap 0.5)
			(thermal_bridge_width 0.5)
			(island_removal_mode 0)
		)
		(polygon
			(pts
				(arc
					(start 338.401152 -265.314176)
					(mid 337.748372 -265.314176)
					(end 338.401152 -265.314176)
				)
			)
		)
	)
	(zone
		(layers "B.Cu" "In4.Cu" "In6.Cu" "In11.Cu" "In13.Cu" "In15.Cu")
		(hatch none 0.5)
		(connect_pads
			(clearance 0)
		)
		(min_thickness 0.25)
		(keepout
			(tracks not_allowed)
			(vias allowed)
			(pads allowed)
			(copperpour not_allowed)
			(footprints allowed)
		)
		(placement
			(enabled no)
			(sheetname "")
		)
		(fill yes
			(thermal_gap 0.5)
			(thermal_bridge_width 0.5)
			(island_removal_mode 0)
		)
		(polygon
			(pts
				(arc
					(start 107.737402 -223.575626)
					(mid 107.084622 -223.575626)
					(end 107.737402 -223.575626)
				)
			)
		)
	)
	(zone
		(layers "B.Cu" "In4.Cu" "In6.Cu" "In11.Cu" "In13.Cu" "In15.Cu")
		(hatch none 0.5)
		(connect_pads
			(clearance 0)
		)
		(min_thickness 0.25)
		(keepout
			(tracks not_allowed)
			(vias allowed)
			(pads allowed)
			(copperpour not_allowed)
			(footprints allowed)
		)
		(placement
			(enabled no)
			(sheetname "")
		)
		(fill yes
			(thermal_gap 0.5)
			(thermal_bridge_width 0.5)
			(island_removal_mode 0)
		)
		(polygon
			(pts
				(arc
					(start 103.618538 -286.475424)
					(mid 102.965758 -286.475424)
					(end 103.618538 -286.475424)
				)
			)
		)
	)
	(zone
		(layers "B.Cu" "In4.Cu" "In6.Cu" "In11.Cu" "In13.Cu" "In15.Cu")
		(hatch none 0.5)
		(connect_pads
			(clearance 0)
		)
		(min_thickness 0.25)
		(keepout
			(tracks not_allowed)
			(vias allowed)
			(pads allowed)
			(copperpour not_allowed)
			(footprints allowed)
		)
		(placement
			(enabled no)
			(sheetname "")
		)
		(fill yes
			(thermal_gap 0.5)
			(thermal_bridge_width 0.5)
			(island_removal_mode 0)
		)
		(polygon
			(pts
				(arc
					(start 308.258718 -400.858228)
					(mid 307.555138 -400.858228)
					(end 308.258718 -400.858228)
				)
			)
		)
	)
	(zone
		(layers "B.Cu" "In4.Cu" "In6.Cu" "In11.Cu" "In13.Cu" "In15.Cu")
		(hatch none 0.5)
		(connect_pads
			(clearance 0)
		)
		(min_thickness 0.25)
		(keepout
			(tracks not_allowed)
			(vias allowed)
			(pads allowed)
			(copperpour not_allowed)
			(footprints allowed)
		)
		(placement
			(enabled no)
			(sheetname "")
		)
		(fill yes
			(thermal_gap 0.5)
			(thermal_bridge_width 0.5)
			(island_removal_mode 0)
		)
		(polygon
			(pts
				(arc
					(start 373.12092 -407.00452)
					(mid 372.41734 -407.00452)
					(end 373.12092 -407.00452)
				)
			)
		)
	)
	(zone
		(layers "B.Cu" "In4.Cu" "In6.Cu" "In11.Cu" "In13.Cu" "In15.Cu")
		(hatch none 0.5)
		(connect_pads
			(clearance 0)
		)
		(min_thickness 0.25)
		(keepout
			(tracks not_allowed)
			(vias allowed)
			(pads allowed)
			(copperpour not_allowed)
			(footprints allowed)
		)
		(placement
			(enabled no)
			(sheetname "")
		)
		(fill yes
			(thermal_gap 0.5)
			(thermal_bridge_width 0.5)
			(island_removal_mode 0)
		)
		(polygon
			(pts
				(arc
					(start 299.330872 -209.216752)
					(mid 298.678092 -209.216752)
					(end 299.330872 -209.216752)
				)
			)
		)
	)
	(zone
		(layers "B.Cu" "In4.Cu" "In6.Cu" "In11.Cu" "In13.Cu" "In15.Cu")
		(hatch none 0.5)
		(connect_pads
			(clearance 0)
		)
		(min_thickness 0.25)
		(keepout
			(tracks not_allowed)
			(vias allowed)
			(pads allowed)
			(copperpour not_allowed)
			(footprints allowed)
		)
		(placement
			(enabled no)
			(sheetname "")
		)
		(fill yes
			(thermal_gap 0.5)
			(thermal_bridge_width 0.5)
			(island_removal_mode 0)
		)
		(polygon
			(pts
				(arc
					(start 47.290736 -266.1666)
					(mid 46.637956 -266.1666)
					(end 47.290736 -266.1666)
				)
			)
		)
	)
	(zone
		(layers "B.Cu" "In4.Cu" "In6.Cu" "In11.Cu" "In13.Cu" "In15.Cu")
		(hatch none 0.5)
		(connect_pads
			(clearance 0)
		)
		(min_thickness 0.25)
		(keepout
			(tracks not_allowed)
			(vias allowed)
			(pads allowed)
			(copperpour not_allowed)
			(footprints allowed)
		)
		(placement
			(enabled no)
			(sheetname "")
		)
		(fill yes
			(thermal_gap 0.5)
			(thermal_bridge_width 0.5)
			(island_removal_mode 0)
		)
		(polygon
			(pts
				(arc
					(start 162.109404 -301.866554)
					(mid 161.456624 -301.866554)
					(end 162.109404 -301.866554)
				)
			)
		)
	)
	(zone
		(layers "B.Cu" "In4.Cu" "In6.Cu" "In11.Cu" "In13.Cu" "In15.Cu")
		(hatch none 0.5)
		(connect_pads
			(clearance 0)
		)
		(min_thickness 0.25)
		(keepout
			(tracks not_allowed)
			(vias allowed)
			(pads allowed)
			(copperpour not_allowed)
			(footprints allowed)
		)
		(placement
			(enabled no)
			(sheetname "")
		)
		(fill yes
			(thermal_gap 0.5)
			(thermal_bridge_width 0.5)
			(island_removal_mode 0)
		)
		(polygon
			(pts
				(arc
					(start 177.222404 -295.06672)
					(mid 176.569624 -295.06672)
					(end 177.222404 -295.06672)
				)
			)
		)
	)
	(zone
		(layers "B.Cu" "In4.Cu" "In6.Cu" "In11.Cu" "In13.Cu" "In15.Cu")
		(hatch none 0.5)
		(connect_pads
			(clearance 0)
		)
		(min_thickness 0.25)
		(keepout
			(tracks not_allowed)
			(vias allowed)
			(pads allowed)
			(copperpour not_allowed)
			(footprints allowed)
		)
		(placement
			(enabled no)
			(sheetname "")
		)
		(fill yes
			(thermal_gap 0.5)
			(thermal_bridge_width 0.5)
			(island_removal_mode 0)
		)
		(polygon
			(pts
				(arc
					(start 177.222404 -220.266768)
					(mid 176.569624 -220.266768)
					(end 177.222404 -220.266768)
				)
			)
		)
	)
	(zone
		(layers "B.Cu" "In4.Cu" "In6.Cu" "In11.Cu" "In13.Cu" "In15.Cu")
		(hatch none 0.5)
		(connect_pads
			(clearance 0)
		)
		(min_thickness 0.25)
		(keepout
			(tracks not_allowed)
			(vias allowed)
			(pads allowed)
			(copperpour not_allowed)
			(footprints allowed)
		)
		(placement
			(enabled no)
			(sheetname "")
		)
		(fill yes
			(thermal_gap 0.5)
			(thermal_bridge_width 0.5)
			(island_removal_mode 0)
		)
		(polygon
			(pts
				(arc
					(start 299.356272 -311.216802)
					(mid 298.703492 -311.216802)
					(end 299.356272 -311.216802)
				)
			)
		)
	)
	(zone
		(layers "B.Cu" "In4.Cu" "In6.Cu" "In11.Cu" "In13.Cu" "In15.Cu")
		(hatch none 0.5)
		(connect_pads
			(clearance 0)
		)
		(min_thickness 0.25)
		(keepout
			(tracks not_allowed)
			(vias allowed)
			(pads allowed)
			(copperpour not_allowed)
			(footprints allowed)
		)
		(placement
			(enabled no)
			(sheetname "")
		)
		(fill yes
			(thermal_gap 0.5)
			(thermal_bridge_width 0.5)
			(island_removal_mode 0)
		)
		(polygon
			(pts
				(arc
					(start 347.329252 -285.661354)
					(mid 346.676472 -285.661354)
					(end 347.329252 -285.661354)
				)
			)
		)
	)
	(zone
		(layers "B.Cu" "In4.Cu" "In6.Cu" "In11.Cu" "In13.Cu" "In15.Cu")
		(hatch none 0.5)
		(connect_pads
			(clearance 0)
		)
		(min_thickness 0.25)
		(keepout
			(tracks not_allowed)
			(vias allowed)
			(pads allowed)
			(copperpour not_allowed)
			(footprints allowed)
		)
		(placement
			(enabled no)
			(sheetname "")
		)
		(fill yes
			(thermal_gap 0.5)
			(thermal_bridge_width 0.5)
			(island_removal_mode 0)
		)
		(polygon
			(pts
				(arc
					(start 22.337268 -17.61236)
					(mid 21.633688 -17.61236)
					(end 22.337268 -17.61236)
				)
			)
		)
	)
	(zone
		(layers "B.Cu" "In4.Cu" "In6.Cu" "In11.Cu" "In13.Cu" "In15.Cu")
		(hatch none 0.5)
		(connect_pads
			(clearance 0)
		)
		(min_thickness 0.25)
		(keepout
			(tracks not_allowed)
			(vias allowed)
			(pads allowed)
			(copperpour not_allowed)
			(footprints allowed)
		)
		(placement
			(enabled no)
			(sheetname "")
		)
		(fill yes
			(thermal_gap 0.5)
			(thermal_bridge_width 0.5)
			(island_removal_mode 0)
		)
		(polygon
			(pts
				(arc
					(start 89.051384 -271.011396)
					(mid 88.398604 -271.011396)
					(end 89.051384 -271.011396)
				)
			)
		)
	)
	(zone
		(layers "B.Cu" "In4.Cu" "In6.Cu" "In11.Cu" "In13.Cu" "In15.Cu")
		(hatch none 0.5)
		(connect_pads
			(clearance 0)
		)
		(min_thickness 0.25)
		(keepout
			(tracks not_allowed)
			(vias allowed)
			(pads allowed)
			(copperpour not_allowed)
			(footprints allowed)
		)
		(placement
			(enabled no)
			(sheetname "")
		)
		(fill yes
			(thermal_gap 0.5)
			(thermal_bridge_width 0.5)
			(island_removal_mode 0)
		)
		(polygon
			(pts
				(arc
					(start 88.941402 -243.108988)
					(mid 88.288622 -243.108988)
					(end 88.941402 -243.108988)
				)
			)
		)
	)
	(zone
		(layers "B.Cu" "In4.Cu" "In6.Cu" "In11.Cu" "In13.Cu" "In15.Cu")
		(hatch none 0.5)
		(connect_pads
			(clearance 0)
		)
		(min_thickness 0.25)
		(keepout
			(tracks not_allowed)
			(vias allowed)
			(pads allowed)
			(copperpour not_allowed)
			(footprints allowed)
		)
		(placement
			(enabled no)
			(sheetname "")
		)
		(fill yes
			(thermal_gap 0.5)
			(thermal_bridge_width 0.5)
			(island_removal_mode 0)
		)
		(polygon
			(pts
				(arc
					(start 338.76107 -233.34218)
					(mid 338.10829 -233.34218)
					(end 338.76107 -233.34218)
				)
			)
		)
	)
	(zone
		(layers "B.Cu" "In4.Cu" "In6.Cu" "In11.Cu" "In13.Cu" "In15.Cu")
		(hatch none 0.5)
		(connect_pads
			(clearance 0)
		)
		(min_thickness 0.25)
		(keepout
			(tracks not_allowed)
			(vias allowed)
			(pads allowed)
			(copperpour not_allowed)
			(footprints allowed)
		)
		(placement
			(enabled no)
			(sheetname "")
		)
		(fill yes
			(thermal_gap 0.5)
			(thermal_bridge_width 0.5)
			(island_removal_mode 0)
		)
		(polygon
			(pts
				(arc
					(start 383.981452 -262.872474)
					(mid 383.328672 -262.872474)
					(end 383.981452 -262.872474)
				)
			)
		)
	)
	(zone
		(layers "B.Cu" "In4.Cu" "In6.Cu" "In11.Cu" "In13.Cu" "In15.Cu")
		(hatch none 0.5)
		(connect_pads
			(clearance 0)
		)
		(min_thickness 0.25)
		(keepout
			(tracks not_allowed)
			(vias allowed)
			(pads allowed)
			(copperpour not_allowed)
			(footprints allowed)
		)
		(placement
			(enabled no)
			(sheetname "")
		)
		(fill yes
			(thermal_gap 0.5)
			(thermal_bridge_width 0.5)
			(island_removal_mode 0)
		)
		(polygon
			(pts
				(arc
					(start 425.162472 -309.516526)
					(mid 424.509692 -309.516526)
					(end 425.162472 -309.516526)
				)
			)
		)
	)
	(zone
		(layers "B.Cu" "In4.Cu" "In6.Cu" "In11.Cu" "In13.Cu" "In15.Cu")
		(hatch none 0.5)
		(connect_pads
			(clearance 0)
		)
		(min_thickness 0.25)
		(keepout
			(tracks not_allowed)
			(vias allowed)
			(pads allowed)
			(copperpour not_allowed)
			(footprints allowed)
		)
		(placement
			(enabled no)
			(sheetname "")
		)
		(fill yes
			(thermal_gap 0.5)
			(thermal_bridge_width 0.5)
			(island_removal_mode 0)
		)
		(polygon
			(pts
				(arc
					(start 140.232384 -407.00452)
					(mid 139.528804 -407.00452)
					(end 140.232384 -407.00452)
				)
			)
		)
	)
	(zone
		(layers "B.Cu" "In4.Cu" "In6.Cu" "In11.Cu" "In13.Cu" "In15.Cu")
		(hatch none 0.5)
		(connect_pads
			(clearance 0)
		)
		(min_thickness 0.25)
		(keepout
			(tracks not_allowed)
			(vias allowed)
			(pads allowed)
			(copperpour not_allowed)
			(footprints allowed)
		)
		(placement
			(enabled no)
			(sheetname "")
		)
		(fill yes
			(thermal_gap 0.5)
			(thermal_bridge_width 0.5)
			(island_removal_mode 0)
		)
		(polygon
			(pts
				(arc
					(start 381.162052 -267.755878)
					(mid 380.509272 -267.755878)
					(end 381.162052 -267.755878)
				)
			)
		)
	)
	(zone
		(layers "B.Cu" "In4.Cu" "In6.Cu" "In11.Cu" "In13.Cu" "In15.Cu")
		(hatch none 0.5)
		(connect_pads
			(clearance 0)
		)
		(min_thickness 0.25)
		(keepout
			(tracks not_allowed)
			(vias allowed)
			(pads allowed)
			(copperpour not_allowed)
			(footprints allowed)
		)
		(placement
			(enabled no)
			(sheetname "")
		)
		(fill yes
			(thermal_gap 0.5)
			(thermal_bridge_width 0.5)
			(island_removal_mode 0)
		)
		(polygon
			(pts
				(arc
					(start 133.221984 -262.872474)
					(mid 132.569204 -262.872474)
					(end 133.221984 -262.872474)
				)
			)
		)
	)
	(zone
		(layers "B.Cu" "In4.Cu" "In6.Cu" "In11.Cu" "In13.Cu" "In15.Cu")
		(hatch none 0.5)
		(connect_pads
			(clearance 0)
		)
		(min_thickness 0.25)
		(keepout
			(tracks not_allowed)
			(vias allowed)
			(pads allowed)
			(copperpour not_allowed)
			(footprints allowed)
		)
		(placement
			(enabled no)
			(sheetname "")
		)
		(fill yes
			(thermal_gap 0.5)
			(thermal_bridge_width 0.5)
			(island_removal_mode 0)
		)
		(polygon
			(pts
				(arc
					(start 402.432774 -17.601438)
					(mid 401.729194 -17.601438)
					(end 402.432774 -17.601438)
				)
			)
		)
	)
	(zone
		(layers "B.Cu" "In4.Cu" "In6.Cu" "In11.Cu" "In13.Cu" "In15.Cu")
		(hatch none 0.5)
		(connect_pads
			(clearance 0)
		)
		(min_thickness 0.25)
		(keepout
			(tracks not_allowed)
			(vias allowed)
			(pads allowed)
			(copperpour not_allowed)
			(footprints allowed)
		)
		(placement
			(enabled no)
			(sheetname "")
		)
		(fill yes
			(thermal_gap 0.5)
			(thermal_bridge_width 0.5)
			(island_removal_mode 0)
		)
		(polygon
			(pts
				(arc
					(start 381.162052 -262.872474)
					(mid 380.509272 -262.872474)
					(end 381.162052 -262.872474)
				)
			)
		)
	)
	(zone
		(layers "B.Cu" "In4.Cu" "In6.Cu" "In11.Cu" "In13.Cu" "In15.Cu")
		(hatch none 0.5)
		(connect_pads
			(clearance 0)
		)
		(min_thickness 0.25)
		(keepout
			(tracks not_allowed)
			(vias allowed)
			(pads allowed)
			(copperpour not_allowed)
			(footprints allowed)
		)
		(placement
			(enabled no)
			(sheetname "")
		)
		(fill yes
			(thermal_gap 0.5)
			(thermal_bridge_width 0.5)
			(island_removal_mode 0)
		)
		(polygon
			(pts
				(arc
					(start 133.582156 -230.900478)
					(mid 132.929376 -230.900478)
					(end 133.582156 -230.900478)
				)
			)
		)
	)
	(zone
		(layers "B.Cu" "In4.Cu" "In6.Cu" "In11.Cu" "In13.Cu" "In15.Cu")
		(hatch none 0.5)
		(connect_pads
			(clearance 0)
		)
		(min_thickness 0.25)
		(keepout
			(tracks not_allowed)
			(vias allowed)
			(pads allowed)
			(copperpour not_allowed)
			(footprints allowed)
		)
		(placement
			(enabled no)
			(sheetname "")
		)
		(fill yes
			(thermal_gap 0.5)
			(thermal_bridge_width 0.5)
			(island_removal_mode 0)
		)
		(polygon
			(pts
				(arc
					(start 425.162472 -312.066686)
					(mid 424.509692 -312.066686)
					(end 425.162472 -312.066686)
				)
			)
		)
	)
	(zone
		(layers "B.Cu" "In4.Cu" "In6.Cu" "In11.Cu" "In13.Cu" "In15.Cu")
		(hatch none 0.5)
		(connect_pads
			(clearance 0)
		)
		(min_thickness 0.25)
		(keepout
			(tracks not_allowed)
			(vias allowed)
			(pads allowed)
			(copperpour not_allowed)
			(footprints allowed)
		)
		(placement
			(enabled no)
			(sheetname "")
		)
		(fill yes
			(thermal_gap 0.5)
			(thermal_bridge_width 0.5)
			(island_removal_mode 0)
		)
		(polygon
			(pts
				(arc
					(start 105.857802 -223.575626)
					(mid 105.205022 -223.575626)
					(end 105.857802 -223.575626)
				)
			)
		)
	)
	(zone
		(layers "B.Cu" "In4.Cu" "In6.Cu" "In11.Cu" "In13.Cu" "In15.Cu")
		(hatch none 0.5)
		(connect_pads
			(clearance 0)
		)
		(min_thickness 0.25)
		(keepout
			(tracks not_allowed)
			(vias allowed)
			(pads allowed)
			(copperpour not_allowed)
			(footprints allowed)
		)
		(placement
			(enabled no)
			(sheetname "")
		)
		(fill yes
			(thermal_gap 0.5)
			(thermal_bridge_width 0.5)
			(island_removal_mode 0)
		)
		(polygon
			(pts
				(arc
					(start 429.849026 -17.601438)
					(mid 429.145446 -17.601438)
					(end 429.849026 -17.601438)
				)
			)
		)
	)
	(zone
		(layers "B.Cu" "In4.Cu" "In6.Cu" "In11.Cu" "In13.Cu" "In15.Cu")
		(hatch none 0.5)
		(connect_pads
			(clearance 0)
		)
		(min_thickness 0.25)
		(keepout
			(tracks not_allowed)
			(vias allowed)
			(pads allowed)
			(copperpour not_allowed)
			(footprints allowed)
		)
		(placement
			(enabled no)
			(sheetname "")
		)
		(fill yes
			(thermal_gap 0.5)
			(thermal_bridge_width 0.5)
			(island_removal_mode 0)
		)
		(polygon
			(pts
				(arc
					(start 341.58047 -249.620024)
					(mid 340.92769 -249.620024)
					(end 341.58047 -249.620024)
				)
			)
		)
	)
	(zone
		(layers "B.Cu" "In4.Cu" "In6.Cu" "In11.Cu" "In13.Cu" "In15.Cu")
		(hatch none 0.5)
		(connect_pads
			(clearance 0)
		)
		(min_thickness 0.25)
		(keepout
			(tracks not_allowed)
			(vias allowed)
			(pads allowed)
			(copperpour not_allowed)
			(footprints allowed)
		)
		(placement
			(enabled no)
			(sheetname "")
		)
		(fill yes
			(thermal_gap 0.5)
			(thermal_bridge_width 0.5)
			(island_removal_mode 0)
		)
		(polygon
			(pts
				(arc
					(start 404.363174 -19.125438)
					(mid 403.659594 -19.125438)
					(end 404.363174 -19.125438)
				)
			)
		)
	)
	(zone
		(layers "B.Cu" "In4.Cu" "In6.Cu" "In11.Cu" "In13.Cu" "In15.Cu")
		(hatch none 0.5)
		(connect_pads
			(clearance 0)
		)
		(min_thickness 0.25)
		(keepout
			(tracks not_allowed)
			(vias allowed)
			(pads allowed)
			(copperpour not_allowed)
			(footprints allowed)
		)
		(placement
			(enabled no)
			(sheetname "")
		)
		(fill yes
			(thermal_gap 0.5)
			(thermal_bridge_width 0.5)
			(island_removal_mode 0)
		)
		(polygon
			(pts
				(arc
					(start 421.062404 -237.266734)
					(mid 420.409624 -237.266734)
					(end 421.062404 -237.266734)
				)
			)
		)
	)
	(zone
		(layers "B.Cu" "In4.Cu" "In6.Cu" "In11.Cu" "In13.Cu" "In15.Cu")
		(hatch none 0.5)
		(connect_pads
			(clearance 0)
		)
		(min_thickness 0.25)
		(keepout
			(tracks not_allowed)
			(vias allowed)
			(pads allowed)
			(copperpour not_allowed)
			(footprints allowed)
		)
		(placement
			(enabled no)
			(sheetname "")
		)
		(fill yes
			(thermal_gap 0.5)
			(thermal_bridge_width 0.5)
			(island_removal_mode 0)
		)
		(polygon
			(pts
				(arc
					(start 338.291424 -226.017328)
					(mid 337.638644 -226.017328)
					(end 338.291424 -226.017328)
				)
			)
		)
	)
	(zone
		(layers "B.Cu" "In4.Cu" "In6.Cu" "In11.Cu" "In13.Cu" "In15.Cu")
		(hatch none 0.5)
		(connect_pads
			(clearance 0)
		)
		(min_thickness 0.25)
		(keepout
			(tracks not_allowed)
			(vias allowed)
			(pads allowed)
			(copperpour not_allowed)
			(footprints allowed)
		)
		(placement
			(enabled no)
			(sheetname "")
		)
		(fill yes
			(thermal_gap 0.5)
			(thermal_bridge_width 0.5)
			(island_removal_mode 0)
		)
		(polygon
			(pts
				(arc
					(start 115.725956 -224.389442)
					(mid 115.073176 -224.389442)
					(end 115.725956 -224.389442)
				)
			)
		)
	)
	(zone
		(layers "B.Cu" "In4.Cu" "In6.Cu" "In11.Cu" "In13.Cu" "In15.Cu")
		(hatch none 0.5)
		(connect_pads
			(clearance 0)
		)
		(min_thickness 0.25)
		(keepout
			(tracks not_allowed)
			(vias allowed)
			(pads allowed)
			(copperpour not_allowed)
			(footprints allowed)
		)
		(placement
			(enabled no)
			(sheetname "")
		)
		(fill yes
			(thermal_gap 0.5)
			(thermal_bridge_width 0.5)
			(island_removal_mode 0)
		)
		(polygon
			(pts
				(arc
					(start 299.356272 -292.516814)
					(mid 298.703492 -292.516814)
					(end 299.356272 -292.516814)
				)
			)
		)
	)
	(zone
		(layers "B.Cu" "In4.Cu" "In6.Cu" "In11.Cu" "In13.Cu" "In15.Cu")
		(hatch none 0.5)
		(connect_pads
			(clearance 0)
		)
		(min_thickness 0.25)
		(keepout
			(tracks not_allowed)
			(vias allowed)
			(pads allowed)
			(copperpour not_allowed)
			(footprints allowed)
		)
		(placement
			(enabled no)
			(sheetname "")
		)
		(fill yes
			(thermal_gap 0.5)
			(thermal_bridge_width 0.5)
			(island_removal_mode 0)
		)
		(polygon
			(pts
				(arc
					(start 378.812806 -257.175254)
					(mid 378.160026 -257.175254)
					(end 378.812806 -257.175254)
				)
			)
		)
	)
	(zone
		(layers "B.Cu" "In4.Cu" "In6.Cu" "In11.Cu" "In13.Cu" "In15.Cu")
		(hatch none 0.5)
		(connect_pads
			(clearance 0)
		)
		(min_thickness 0.25)
		(keepout
			(tracks not_allowed)
			(vias allowed)
			(pads allowed)
			(copperpour not_allowed)
			(footprints allowed)
		)
		(placement
			(enabled no)
			(sheetname "")
		)
		(fill yes
			(thermal_gap 0.5)
			(thermal_bridge_width 0.5)
			(island_removal_mode 0)
		)
		(polygon
			(pts
				(arc
					(start 372.234206 -286.475424)
					(mid 371.581426 -286.475424)
					(end 372.234206 -286.475424)
				)
			)
		)
	)
	(zone
		(layers "B.Cu" "In4.Cu" "In6.Cu" "In11.Cu" "In13.Cu" "In15.Cu")
		(hatch none 0.5)
		(connect_pads
			(clearance 0)
		)
		(min_thickness 0.25)
		(keepout
			(tracks not_allowed)
			(vias allowed)
			(pads allowed)
			(copperpour not_allowed)
			(footprints allowed)
		)
		(placement
			(enabled no)
			(sheetname "")
		)
		(fill yes
			(thermal_gap 0.5)
			(thermal_bridge_width 0.5)
			(island_removal_mode 0)
		)
		(polygon
			(pts
				(arc
					(start 21.473668 -17.61236)
					(mid 20.770088 -17.61236)
					(end 21.473668 -17.61236)
				)
			)
		)
	)
	(zone
		(layers "B.Cu" "In4.Cu" "In6.Cu" "In11.Cu" "In13.Cu" "In15.Cu")
		(hatch none 0.5)
		(connect_pads
			(clearance 0)
		)
		(min_thickness 0.25)
		(keepout
			(tracks not_allowed)
			(vias allowed)
			(pads allowed)
			(copperpour not_allowed)
			(footprints allowed)
		)
		(placement
			(enabled no)
			(sheetname "")
		)
		(fill yes
			(thermal_gap 0.5)
			(thermal_bridge_width 0.5)
			(island_removal_mode 0)
		)
		(polygon
			(pts
				(arc
					(start 173.122336 -216.866724)
					(mid 172.469556 -216.866724)
					(end 173.122336 -216.866724)
				)
			)
		)
	)
	(zone
		(layers "B.Cu" "In4.Cu" "In6.Cu" "In11.Cu" "In13.Cu" "In15.Cu")
		(hatch none 0.5)
		(connect_pads
			(clearance 0)
		)
		(min_thickness 0.25)
		(keepout
			(tracks not_allowed)
			(vias allowed)
			(pads allowed)
			(copperpour not_allowed)
			(footprints allowed)
		)
		(placement
			(enabled no)
			(sheetname "")
		)
		(fill yes
			(thermal_gap 0.5)
			(thermal_bridge_width 0.5)
			(island_removal_mode 0)
		)
		(polygon
			(pts
				(arc
					(start 381.992124 -238.225584)
					(mid 381.339344 -238.225584)
					(end 381.992124 -238.225584)
				)
			)
		)
	)
	(zone
		(layers "B.Cu" "In4.Cu" "In6.Cu" "In11.Cu" "In13.Cu" "In15.Cu")
		(hatch none 0.5)
		(connect_pads
			(clearance 0)
		)
		(min_thickness 0.25)
		(keepout
			(tracks not_allowed)
			(vias allowed)
			(pads allowed)
			(copperpour not_allowed)
			(footprints allowed)
		)
		(placement
			(enabled no)
			(sheetname "")
		)
		(fill yes
			(thermal_gap 0.5)
			(thermal_bridge_width 0.5)
			(island_removal_mode 0)
		)
		(polygon
			(pts
				(arc
					(start 341.090758 -400.858228)
					(mid 340.387178 -400.858228)
					(end 341.090758 -400.858228)
				)
			)
		)
	)
	(zone
		(layers "B.Cu" "In4.Cu" "In6.Cu" "In11.Cu" "In13.Cu" "In15.Cu")
		(hatch none 0.5)
		(connect_pads
			(clearance 0)
		)
		(min_thickness 0.25)
		(keepout
			(tracks not_allowed)
			(vias allowed)
			(pads allowed)
			(copperpour not_allowed)
			(footprints allowed)
		)
		(placement
			(enabled no)
			(sheetname "")
		)
		(fill yes
			(thermal_gap 0.5)
			(thermal_bridge_width 0.5)
			(island_removal_mode 0)
		)
		(polygon
			(pts
				(arc
					(start 381.992124 -234.970066)
					(mid 381.339344 -234.970066)
					(end 381.992124 -234.970066)
				)
			)
		)
	)
	(zone
		(layers "B.Cu" "In4.Cu" "In6.Cu" "In11.Cu" "In13.Cu" "In15.Cu")
		(hatch none 0.5)
		(connect_pads
			(clearance 0)
		)
		(min_thickness 0.25)
		(keepout
			(tracks not_allowed)
			(vias allowed)
			(pads allowed)
			(copperpour not_allowed)
			(footprints allowed)
		)
		(placement
			(enabled no)
			(sheetname "")
		)
		(fill yes
			(thermal_gap 0.5)
			(thermal_bridge_width 0.5)
			(island_removal_mode 0)
		)
		(polygon
			(pts
				(arc
					(start 119.015002 -223.575626)
					(mid 118.362222 -223.575626)
					(end 119.015002 -223.575626)
				)
			)
		)
	)
	(zone
		(layers "B.Cu" "In4.Cu" "In6.Cu" "In11.Cu" "In13.Cu" "In15.Cu")
		(hatch none 0.5)
		(connect_pads
			(clearance 0)
		)
		(min_thickness 0.25)
		(keepout
			(tracks not_allowed)
			(vias allowed)
			(pads allowed)
			(copperpour not_allowed)
			(footprints allowed)
		)
		(placement
			(enabled no)
			(sheetname "")
		)
		(fill yes
			(thermal_gap 0.5)
			(thermal_bridge_width 0.5)
			(island_removal_mode 0)
		)
		(polygon
			(pts
				(arc
					(start 366.95507 -223.575626)
					(mid 366.30229 -223.575626)
					(end 366.95507 -223.575626)
				)
			)
		)
	)
	(zone
		(layers "B.Cu" "In4.Cu" "In6.Cu" "In11.Cu" "In13.Cu" "In15.Cu")
		(hatch none 0.5)
		(connect_pads
			(clearance 0)
		)
		(min_thickness 0.25)
		(keepout
			(tracks not_allowed)
			(vias allowed)
			(pads allowed)
			(copperpour not_allowed)
			(footprints allowed)
		)
		(placement
			(enabled no)
			(sheetname "")
		)
		(fill yes
			(thermal_gap 0.5)
			(thermal_bridge_width 0.5)
			(island_removal_mode 0)
		)
		(polygon
			(pts
				(arc
					(start 88.581484 -270.19758)
					(mid 87.928704 -270.19758)
					(end 88.581484 -270.19758)
				)
			)
		)
	)
	(zone
		(layers "B.Cu" "In6.Cu" "In11.Cu" "In13.Cu" "In15.Cu")
		(hatch none 0.5)
		(connect_pads
			(clearance 0)
		)
		(min_thickness 0.25)
		(keepout
			(tracks not_allowed)
			(vias allowed)
			(pads allowed)
			(copperpour not_allowed)
			(footprints allowed)
		)
		(placement
			(enabled no)
			(sheetname "")
		)
		(fill yes
			(thermal_gap 0.5)
			(thermal_bridge_width 0.5)
			(island_removal_mode 0)
		)
		(polygon
			(pts
				(arc
					(start 360.37647 -218.692222)
					(mid 359.72369 -218.692222)
					(end 360.37647 -218.692222)
				)
			)
		)
	)
	(zone
		(layers "B.Cu" "In6.Cu" "In11.Cu" "In13.Cu" "In15.Cu")
		(hatch none 0.5)
		(connect_pads
			(clearance 0)
		)
		(min_thickness 0.25)
		(keepout
			(tracks not_allowed)
			(vias allowed)
			(pads allowed)
			(copperpour not_allowed)
			(footprints allowed)
		)
		(placement
			(enabled no)
			(sheetname "")
		)
		(fill yes
			(thermal_gap 0.5)
			(thermal_bridge_width 0.5)
			(island_removal_mode 0)
		)
		(polygon
			(pts
				(arc
					(start 440.250072 -240.666778)
					(mid 439.597292 -240.666778)
					(end 440.250072 -240.666778)
				)
			)
		)
	)
	(zone
		(layers "B.Cu" "In6.Cu" "In11.Cu" "In13.Cu" "In15.Cu")
		(hatch none 0.5)
		(connect_pads
			(clearance 0)
		)
		(min_thickness 0.25)
		(keepout
			(tracks not_allowed)
			(vias allowed)
			(pads allowed)
			(copperpour not_allowed)
			(footprints allowed)
		)
		(placement
			(enabled no)
			(sheetname "")
		)
		(fill yes
			(thermal_gap 0.5)
			(thermal_bridge_width 0.5)
			(island_removal_mode 0)
		)
		(polygon
			(pts
				(arc
					(start 241.015774 -57.43829)
					(mid 240.312194 -57.43829)
					(end 241.015774 -57.43829)
				)
			)
		)
	)
	(zone
		(layers "B.Cu" "In6.Cu" "In11.Cu" "In13.Cu" "In15.Cu")
		(hatch none 0.5)
		(connect_pads
			(clearance 0)
		)
		(min_thickness 0.25)
		(keepout
			(tracks not_allowed)
			(vias allowed)
			(pads allowed)
			(copperpour not_allowed)
			(footprints allowed)
		)
		(placement
			(enabled no)
			(sheetname "")
		)
		(fill yes
			(thermal_gap 0.5)
			(thermal_bridge_width 0.5)
			(island_removal_mode 0)
		)
		(polygon
			(pts
				(arc
					(start 272.599404 -267.866622)
					(mid 271.946624 -267.866622)
					(end 272.599404 -267.866622)
				)
			)
		)
	)
	(zone
		(layers "B.Cu" "In6.Cu" "In11.Cu" "In13.Cu" "In15.Cu")
		(hatch none 0.5)
		(connect_pads
			(clearance 0)
		)
		(min_thickness 0.25)
		(keepout
			(tracks not_allowed)
			(vias allowed)
			(pads allowed)
			(copperpour not_allowed)
			(footprints allowed)
		)
		(placement
			(enabled no)
			(sheetname "")
		)
		(fill yes
			(thermal_gap 0.5)
			(thermal_bridge_width 0.5)
			(island_removal_mode 0)
		)
		(polygon
			(pts
				(arc
					(start 379.642624 -242.294918)
					(mid 378.989844 -242.294918)
					(end 379.642624 -242.294918)
				)
			)
		)
	)
	(zone
		(layers "B.Cu" "In6.Cu" "In11.Cu" "In13.Cu" "In15.Cu")
		(hatch none 0.5)
		(connect_pads
			(clearance 0)
		)
		(min_thickness 0.25)
		(keepout
			(tracks not_allowed)
			(vias allowed)
			(pads allowed)
			(copperpour not_allowed)
			(footprints allowed)
		)
		(placement
			(enabled no)
			(sheetname "")
		)
		(fill yes
			(thermal_gap 0.5)
			(thermal_bridge_width 0.5)
			(island_removal_mode 0)
		)
		(polygon
			(pts
				(arc
					(start 350.508824 -217.878406)
					(mid 349.856044 -217.878406)
					(end 350.508824 -217.878406)
				)
			)
		)
	)
	(zone
		(layers "B.Cu" "In6.Cu" "In11.Cu" "In13.Cu" "In15.Cu")
		(hatch none 0.5)
		(connect_pads
			(clearance 0)
		)
		(min_thickness 0.25)
		(keepout
			(tracks not_allowed)
			(vias allowed)
			(pads allowed)
			(copperpour not_allowed)
			(footprints allowed)
		)
		(placement
			(enabled no)
			(sheetname "")
		)
		(fill yes
			(thermal_gap 0.5)
			(thermal_bridge_width 0.5)
			(island_removal_mode 0)
		)
		(polygon
			(pts
				(arc
					(start 131.702556 -227.64496)
					(mid 131.049776 -227.64496)
					(end 131.702556 -227.64496)
				)
			)
		)
	)
	(zone
		(layers "B.Cu" "In6.Cu" "In11.Cu" "In13.Cu" "In15.Cu")
		(hatch none 0.5)
		(connect_pads
			(clearance 0)
		)
		(min_thickness 0.25)
		(keepout
			(tracks not_allowed)
			(vias allowed)
			(pads allowed)
			(copperpour not_allowed)
			(footprints allowed)
		)
		(placement
			(enabled no)
			(sheetname "")
		)
		(fill yes
			(thermal_gap 0.5)
			(thermal_bridge_width 0.5)
			(island_removal_mode 0)
		)
		(polygon
			(pts
				(arc
					(start 92.230956 -239.0394)
					(mid 91.578176 -239.0394)
					(end 92.230956 -239.0394)
				)
			)
		)
	)
	(zone
		(layers "B.Cu" "In6.Cu" "In11.Cu" "In13.Cu" "In15.Cu")
		(hatch none 0.5)
		(connect_pads
			(clearance 0)
		)
		(min_thickness 0.25)
		(keepout
			(tracks not_allowed)
			(vias allowed)
			(pads allowed)
			(copperpour not_allowed)
			(footprints allowed)
		)
		(placement
			(enabled no)
			(sheetname "")
		)
		(fill yes
			(thermal_gap 0.5)
			(thermal_bridge_width 0.5)
			(island_removal_mode 0)
		)
		(polygon
			(pts
				(arc
					(start 280.143204 -264.466578)
					(mid 279.490424 -264.466578)
					(end 280.143204 -264.466578)
				)
			)
		)
	)
	(zone
		(layers "B.Cu" "In6.Cu" "In11.Cu" "In13.Cu" "In15.Cu")
		(hatch none 0.5)
		(connect_pads
			(clearance 0)
		)
		(min_thickness 0.25)
		(keepout
			(tracks not_allowed)
			(vias allowed)
			(pads allowed)
			(copperpour not_allowed)
			(footprints allowed)
		)
		(placement
			(enabled no)
			(sheetname "")
		)
		(fill yes
			(thermal_gap 0.5)
			(thermal_bridge_width 0.5)
			(island_removal_mode 0)
		)
		(polygon
			(pts
				(arc
					(start 94.690438 -288.917126)
					(mid 94.037658 -288.917126)
					(end 94.690438 -288.917126)
				)
			)
		)
	)
	(zone
		(layers "B.Cu" "In6.Cu" "In11.Cu" "In13.Cu" "In15.Cu")
		(hatch none 0.5)
		(connect_pads
			(clearance 0)
		)
		(min_thickness 0.25)
		(keepout
			(tracks not_allowed)
			(vias allowed)
			(pads allowed)
			(copperpour not_allowed)
			(footprints allowed)
		)
		(placement
			(enabled no)
			(sheetname "")
		)
		(fill yes
			(thermal_gap 0.5)
			(thermal_bridge_width 0.5)
			(island_removal_mode 0)
		)
		(polygon
			(pts
				(arc
					(start 376.933206 -288.103056)
					(mid 376.280426 -288.103056)
					(end 376.933206 -288.103056)
				)
			)
		)
	)
	(zone
		(layers "B.Cu" "In6.Cu" "In11.Cu" "In13.Cu" "In15.Cu")
		(hatch none 0.5)
		(connect_pads
			(clearance 0)
		)
		(min_thickness 0.25)
		(keepout
			(tracks not_allowed)
			(vias allowed)
			(pads allowed)
			(copperpour not_allowed)
			(footprints allowed)
		)
		(placement
			(enabled no)
			(sheetname "")
		)
		(fill yes
			(thermal_gap 0.5)
			(thermal_bridge_width 0.5)
			(island_removal_mode 0)
		)
		(polygon
			(pts
				(arc
					(start 440.250072 -296.766742)
					(mid 439.597292 -296.766742)
					(end 440.250072 -296.766742)
				)
			)
		)
	)
	(zone
		(layers "B.Cu" "In6.Cu" "In11.Cu" "In13.Cu" "In15.Cu")
		(hatch none 0.5)
		(connect_pads
			(clearance 0)
		)
		(min_thickness 0.25)
		(keepout
			(tracks not_allowed)
			(vias allowed)
			(pads allowed)
			(copperpour not_allowed)
			(footprints allowed)
		)
		(placement
			(enabled no)
			(sheetname "")
		)
		(fill yes
			(thermal_gap 0.5)
			(thermal_bridge_width 0.5)
			(island_removal_mode 0)
		)
		(polygon
			(pts
				(arc
					(start 284.243272 -250.016772)
					(mid 283.590492 -250.016772)
					(end 284.243272 -250.016772)
				)
			)
		)
	)
	(zone
		(layers "B.Cu" "In6.Cu" "In11.Cu" "In13.Cu" "In15.Cu")
		(hatch none 0.5)
		(connect_pads
			(clearance 0)
		)
		(min_thickness 0.25)
		(keepout
			(tracks not_allowed)
			(vias allowed)
			(pads allowed)
			(copperpour not_allowed)
			(footprints allowed)
		)
		(placement
			(enabled no)
			(sheetname "")
		)
		(fill yes
			(thermal_gap 0.5)
			(thermal_bridge_width 0.5)
			(island_removal_mode 0)
		)
		(polygon
			(pts
				(arc
					(start 130.762756 -237.411514)
					(mid 130.109976 -237.411514)
					(end 130.762756 -237.411514)
				)
			)
		)
	)
	(zone
		(layers "B.Cu" "In6.Cu" "In11.Cu" "In13.Cu" "In15.Cu")
		(hatch none 0.5)
		(connect_pads
			(clearance 0)
		)
		(min_thickness 0.25)
		(keepout
			(tracks not_allowed)
			(vias allowed)
			(pads allowed)
			(copperpour not_allowed)
			(footprints allowed)
		)
		(placement
			(enabled no)
			(sheetname "")
		)
		(fill yes
			(thermal_gap 0.5)
			(thermal_bridge_width 0.5)
			(island_removal_mode 0)
		)
		(polygon
			(pts
				(arc
					(start 127.473202 -249.620024)
					(mid 126.820422 -249.620024)
					(end 127.473202 -249.620024)
				)
			)
		)
	)
	(zone
		(layers "B.Cu" "In6.Cu" "In11.Cu" "In13.Cu" "In15.Cu")
		(hatch none 0.5)
		(connect_pads
			(clearance 0)
		)
		(min_thickness 0.25)
		(keepout
			(tracks not_allowed)
			(vias allowed)
			(pads allowed)
			(copperpour not_allowed)
			(footprints allowed)
		)
		(placement
			(enabled no)
			(sheetname "")
		)
		(fill yes
			(thermal_gap 0.5)
			(thermal_bridge_width 0.5)
			(island_removal_mode 0)
		)
		(polygon
			(pts
				(arc
					(start 284.243272 -313.766708)
					(mid 283.590492 -313.766708)
					(end 284.243272 -313.766708)
				)
			)
		)
	)
	(zone
		(layers "B.Cu" "In6.Cu" "In11.Cu" "In13.Cu" "In15.Cu")
		(hatch none 0.5)
		(connect_pads
			(clearance 0)
		)
		(min_thickness 0.25)
		(keepout
			(tracks not_allowed)
			(vias allowed)
			(pads allowed)
			(copperpour not_allowed)
			(footprints allowed)
		)
		(placement
			(enabled no)
			(sheetname "")
		)
		(fill yes
			(thermal_gap 0.5)
			(thermal_bridge_width 0.5)
			(island_removal_mode 0)
		)
		(polygon
			(pts
				(arc
					(start 284.243272 -312.066686)
					(mid 283.590492 -312.066686)
					(end 284.243272 -312.066686)
				)
			)
		)
	)
	(zone
		(layers "B.Cu" "In6.Cu" "In11.Cu" "In13.Cu" "In15.Cu")
		(hatch none 0.5)
		(connect_pads
			(clearance 0)
		)
		(min_thickness 0.25)
		(keepout
			(tracks not_allowed)
			(vias allowed)
			(pads allowed)
			(copperpour not_allowed)
			(footprints allowed)
		)
		(placement
			(enabled no)
			(sheetname "")
		)
		(fill yes
			(thermal_gap 0.5)
			(thermal_bridge_width 0.5)
			(island_removal_mode 0)
		)
		(polygon
			(pts
				(arc
					(start 173.122336 -284.016704)
					(mid 172.469556 -284.016704)
					(end 173.122336 -284.016704)
				)
			)
		)
	)
	(zone
		(layers "B.Cu" "In6.Cu" "In11.Cu" "In13.Cu" "In15.Cu")
		(hatch none 0.5)
		(connect_pads
			(clearance 0)
		)
		(min_thickness 0.25)
		(keepout
			(tracks not_allowed)
			(vias allowed)
			(pads allowed)
			(copperpour not_allowed)
			(footprints allowed)
		)
		(placement
			(enabled no)
			(sheetname "")
		)
		(fill yes
			(thermal_gap 0.5)
			(thermal_bridge_width 0.5)
			(island_removal_mode 0)
		)
		(polygon
			(pts
				(arc
					(start 127.473202 -218.692222)
					(mid 126.820422 -218.692222)
					(end 127.473202 -218.692222)
				)
			)
		)
	)
	(zone
		(layers "B.Cu" "In6.Cu" "In11.Cu" "In13.Cu" "In15.Cu")
		(hatch none 0.5)
		(connect_pads
			(clearance 0)
		)
		(min_thickness 0.25)
		(keepout
			(tracks not_allowed)
			(vias allowed)
			(pads allowed)
			(copperpour not_allowed)
			(footprints allowed)
		)
		(placement
			(enabled no)
			(sheetname "")
		)
		(fill yes
			(thermal_gap 0.5)
			(thermal_bridge_width 0.5)
			(island_removal_mode 0)
		)
		(polygon
			(pts
				(arc
					(start 370.354352 -289.807142)
					(mid 369.701572 -289.807142)
					(end 370.354352 -289.807142)
				)
			)
		)
	)
	(zone
		(layers "B.Cu" "In6.Cu" "In11.Cu" "In13.Cu" "In15.Cu")
		(hatch none 0.5)
		(connect_pads
			(clearance 0)
		)
		(min_thickness 0.25)
		(keepout
			(tracks not_allowed)
			(vias allowed)
			(pads allowed)
			(copperpour not_allowed)
			(footprints allowed)
		)
		(placement
			(enabled no)
			(sheetname "")
		)
		(fill yes
			(thermal_gap 0.5)
			(thermal_bridge_width 0.5)
			(island_removal_mode 0)
		)
		(polygon
			(pts
				(arc
					(start 378.812806 -288.103056)
					(mid 378.160026 -288.103056)
					(end 378.812806 -288.103056)
				)
			)
		)
	)
	(zone
		(layers "B.Cu" "In6.Cu" "In11.Cu" "In13.Cu" "In15.Cu")
		(hatch none 0.5)
		(connect_pads
			(clearance 0)
		)
		(min_thickness 0.25)
		(keepout
			(tracks not_allowed)
			(vias allowed)
			(pads allowed)
			(copperpour not_allowed)
			(footprints allowed)
		)
		(placement
			(enabled no)
			(sheetname "")
		)
		(fill yes
			(thermal_gap 0.5)
			(thermal_bridge_width 0.5)
			(island_removal_mode 0)
		)
		(polygon
			(pts
				(arc
					(start 92.340938 -262.058658)
					(mid 91.688158 -262.058658)
					(end 92.340938 -262.058658)
				)
			)
		)
	)
	(zone
		(layers "B.Cu" "In6.Cu" "In11.Cu" "In13.Cu" "In15.Cu")
		(hatch none 0.5)
		(connect_pads
			(clearance 0)
		)
		(min_thickness 0.25)
		(keepout
			(tracks not_allowed)
			(vias allowed)
			(pads allowed)
			(copperpour not_allowed)
			(footprints allowed)
		)
		(placement
			(enabled no)
			(sheetname "")
		)
		(fill yes
			(thermal_gap 0.5)
			(thermal_bridge_width 0.5)
			(island_removal_mode 0)
		)
		(polygon
			(pts
				(arc
					(start 335.002124 -225.203258)
					(mid 334.349344 -225.203258)
					(end 335.002124 -225.203258)
				)
			)
		)
	)
	(zone
		(layers "B.Cu" "In6.Cu" "In11.Cu" "In13.Cu" "In15.Cu")
		(hatch none 0.5)
		(connect_pads
			(clearance 0)
		)
		(min_thickness 0.25)
		(keepout
			(tracks not_allowed)
			(vias allowed)
			(pads allowed)
			(copperpour not_allowed)
			(footprints allowed)
		)
		(placement
			(enabled no)
			(sheetname "")
		)
		(fill yes
			(thermal_gap 0.5)
			(thermal_bridge_width 0.5)
			(island_removal_mode 0)
		)
		(polygon
			(pts
				(arc
					(start 436.150004 -210.066636)
					(mid 435.497224 -210.066636)
					(end 436.150004 -210.066636)
				)
			)
		)
	)
	(zone
		(layers "B.Cu" "In6.Cu" "In11.Cu" "In13.Cu" "In15.Cu")
		(hatch none 0.5)
		(connect_pads
			(clearance 0)
		)
		(min_thickness 0.25)
		(keepout
			(tracks not_allowed)
			(vias allowed)
			(pads allowed)
			(copperpour not_allowed)
			(footprints allowed)
		)
		(placement
			(enabled no)
			(sheetname "")
		)
		(fill yes
			(thermal_gap 0.5)
			(thermal_bridge_width 0.5)
			(island_removal_mode 0)
		)
		(polygon
			(pts
				(arc
					(start 440.250072 -267.016738)
					(mid 439.597292 -267.016738)
					(end 440.250072 -267.016738)
				)
			)
		)
	)
	(zone
		(layers "B.Cu" "In6.Cu" "In11.Cu" "In13.Cu" "In15.Cu")
		(hatch none 0.5)
		(connect_pads
			(clearance 0)
		)
		(min_thickness 0.25)
		(keepout
			(tracks not_allowed)
			(vias allowed)
			(pads allowed)
			(copperpour not_allowed)
			(footprints allowed)
		)
		(placement
			(enabled no)
			(sheetname "")
		)
		(fill yes
			(thermal_gap 0.5)
			(thermal_bridge_width 0.5)
			(island_removal_mode 0)
		)
		(polygon
			(pts
				(arc
					(start 92.230956 -230.900478)
					(mid 91.578176 -230.900478)
					(end 92.230956 -230.900478)
				)
			)
		)
	)
	(zone
		(layers "B.Cu" "In6.Cu" "In11.Cu" "In13.Cu" "In15.Cu")
		(hatch none 0.5)
		(connect_pads
			(clearance 0)
		)
		(min_thickness 0.25)
		(keepout
			(tracks not_allowed)
			(vias allowed)
			(pads allowed)
			(copperpour not_allowed)
			(footprints allowed)
		)
		(placement
			(enabled no)
			(sheetname "")
		)
		(fill yes
			(thermal_gap 0.5)
			(thermal_bridge_width 0.5)
			(island_removal_mode 0)
		)
		(polygon
			(pts
				(arc
					(start 177.222404 -197.316598)
					(mid 176.569624 -197.316598)
					(end 177.222404 -197.316598)
				)
			)
		)
	)
	(zone
		(layers "B.Cu" "In6.Cu" "In11.Cu" "In13.Cu" "In15.Cu")
		(hatch none 0.5)
		(connect_pads
			(clearance 0)
		)
		(min_thickness 0.25)
		(keepout
			(tracks not_allowed)
			(vias allowed)
			(pads allowed)
			(copperpour not_allowed)
			(footprints allowed)
		)
		(placement
			(enabled no)
			(sheetname "")
		)
		(fill yes
			(thermal_gap 0.5)
			(thermal_bridge_width 0.5)
			(island_removal_mode 0)
		)
		(polygon
			(pts
				(arc
					(start 92.810584 -259.616956)
					(mid 92.157804 -259.616956)
					(end 92.810584 -259.616956)
				)
			)
		)
	)
	(zone
		(layers "B.Cu" "In6.Cu" "In11.Cu" "In13.Cu" "In15.Cu")
		(hatch none 0.5)
		(connect_pads
			(clearance 0)
		)
		(min_thickness 0.25)
		(keepout
			(tracks not_allowed)
			(vias allowed)
			(pads allowed)
			(copperpour not_allowed)
			(footprints allowed)
		)
		(placement
			(enabled no)
			(sheetname "")
		)
		(fill yes
			(thermal_gap 0.5)
			(thermal_bridge_width 0.5)
			(island_removal_mode 0)
		)
		(polygon
			(pts
				(arc
					(start 173.122336 -226.216718)
					(mid 172.469556 -226.216718)
					(end 173.122336 -226.216718)
				)
			)
		)
	)
	(zone
		(layers "B.Cu" "In6.Cu" "In11.Cu" "In13.Cu" "In15.Cu")
		(hatch none 0.5)
		(connect_pads
			(clearance 0)
		)
		(min_thickness 0.25)
		(keepout
			(tracks not_allowed)
			(vias allowed)
			(pads allowed)
			(copperpour not_allowed)
			(footprints allowed)
		)
		(placement
			(enabled no)
			(sheetname "")
		)
		(fill yes
			(thermal_gap 0.5)
			(thermal_bridge_width 0.5)
			(island_removal_mode 0)
		)
		(polygon
			(pts
				(arc
					(start 380.11227 -228.45903)
					(mid 379.45949 -228.45903)
					(end 380.11227 -228.45903)
				)
			)
		)
	)
	(zone
		(layers "B.Cu" "In6.Cu" "In11.Cu" "In13.Cu" "In15.Cu")
		(hatch none 0.5)
		(connect_pads
			(clearance 0)
		)
		(min_thickness 0.25)
		(keepout
			(tracks not_allowed)
			(vias allowed)
			(pads allowed)
			(copperpour not_allowed)
			(footprints allowed)
		)
		(placement
			(enabled no)
			(sheetname "")
		)
		(fill yes
			(thermal_gap 0.5)
			(thermal_bridge_width 0.5)
			(island_removal_mode 0)
		)
		(polygon
			(pts
				(arc
					(start 95.160338 -288.103056)
					(mid 94.507558 -288.103056)
					(end 95.160338 -288.103056)
				)
			)
		)
	)
	(zone
		(layers "B.Cu" "In6.Cu" "In11.Cu" "In13.Cu" "In15.Cu")
		(hatch none 0.5)
		(connect_pads
			(clearance 0)
		)
		(min_thickness 0.25)
		(keepout
			(tracks not_allowed)
			(vias allowed)
			(pads allowed)
			(copperpour not_allowed)
			(footprints allowed)
		)
		(placement
			(enabled no)
			(sheetname "")
		)
		(fill yes
			(thermal_gap 0.5)
			(thermal_bridge_width 0.5)
			(island_removal_mode 0)
		)
		(polygon
			(pts
				(arc
					(start 378.812806 -268.569694)
					(mid 378.160026 -268.569694)
					(end 378.812806 -268.569694)
				)
			)
		)
	)
	(zone
		(layers "B.Cu" "In6.Cu" "In11.Cu" "In13.Cu" "In15.Cu")
		(hatch none 0.5)
		(connect_pads
			(clearance 0)
		)
		(min_thickness 0.25)
		(keepout
			(tracks not_allowed)
			(vias allowed)
			(pads allowed)
			(copperpour not_allowed)
			(footprints allowed)
		)
		(placement
			(enabled no)
			(sheetname "")
		)
		(fill yes
			(thermal_gap 0.5)
			(thermal_bridge_width 0.5)
			(island_removal_mode 0)
		)
		(polygon
			(pts
				(arc
					(start 342.050624 -229.272846)
					(mid 341.397844 -229.272846)
					(end 342.050624 -229.272846)
				)
			)
		)
	)
	(zone
		(layers "B.Cu" "In6.Cu" "In11.Cu" "In13.Cu" "In15.Cu")
		(hatch none 0.5)
		(connect_pads
			(clearance 0)
		)
		(min_thickness 0.25)
		(keepout
			(tracks not_allowed)
			(vias allowed)
			(pads allowed)
			(copperpour not_allowed)
			(footprints allowed)
		)
		(placement
			(enabled no)
			(sheetname "")
		)
		(fill yes
			(thermal_gap 0.5)
			(thermal_bridge_width 0.5)
			(island_removal_mode 0)
		)
		(polygon
			(pts
				(arc
					(start 342.050624 -245.55069)
					(mid 341.397844 -245.55069)
					(end 342.050624 -245.55069)
				)
			)
		)
	)
	(zone
		(layers "B.Cu" "In6.Cu" "In11.Cu" "In13.Cu" "In15.Cu")
		(hatch none 0.5)
		(connect_pads
			(clearance 0)
		)
		(min_thickness 0.25)
		(keepout
			(tracks not_allowed)
			(vias allowed)
			(pads allowed)
			(copperpour not_allowed)
			(footprints allowed)
		)
		(placement
			(enabled no)
			(sheetname "")
		)
		(fill yes
			(thermal_gap 0.5)
			(thermal_bridge_width 0.5)
			(island_removal_mode 0)
		)
		(polygon
			(pts
				(arc
					(start 130.872738 -260.430772)
					(mid 130.219958 -260.430772)
					(end 130.872738 -260.430772)
				)
			)
		)
	)
	(zone
		(layers "B.Cu" "In6.Cu" "In11.Cu" "In13.Cu" "In15.Cu")
		(hatch none 0.5)
		(connect_pads
			(clearance 0)
		)
		(min_thickness 0.25)
		(keepout
			(tracks not_allowed)
			(vias allowed)
			(pads allowed)
			(copperpour not_allowed)
			(footprints allowed)
		)
		(placement
			(enabled no)
			(sheetname "")
		)
		(fill yes
			(thermal_gap 0.5)
			(thermal_bridge_width 0.5)
			(island_removal_mode 0)
		)
		(polygon
			(pts
				(arc
					(start 28.759404 -267.016738)
					(mid 28.106624 -267.016738)
					(end 28.759404 -267.016738)
				)
			)
		)
	)
	(zone
		(layers "B.Cu" "In6.Cu" "In11.Cu" "In13.Cu" "In15.Cu")
		(hatch none 0.5)
		(connect_pads
			(clearance 0)
		)
		(min_thickness 0.25)
		(keepout
			(tracks not_allowed)
			(vias allowed)
			(pads allowed)
			(copperpour not_allowed)
			(footprints allowed)
		)
		(placement
			(enabled no)
			(sheetname "")
		)
		(fill yes
			(thermal_gap 0.5)
			(thermal_bridge_width 0.5)
			(island_removal_mode 0)
		)
		(polygon
			(pts
				(arc
					(start 24.659336 -245.76659)
					(mid 24.006556 -245.76659)
					(end 24.659336 -245.76659)
				)
			)
		)
	)
	(zone
		(layers "B.Cu" "In6.Cu" "In11.Cu" "In13.Cu" "In15.Cu")
		(hatch none 0.5)
		(connect_pads
			(clearance 0)
		)
		(min_thickness 0.25)
		(keepout
			(tracks not_allowed)
			(vias allowed)
			(pads allowed)
			(copperpour not_allowed)
			(footprints allowed)
		)
		(placement
			(enabled no)
			(sheetname "")
		)
		(fill yes
			(thermal_gap 0.5)
			(thermal_bridge_width 0.5)
			(island_removal_mode 0)
		)
		(polygon
			(pts
				(arc
					(start 111.496856 -217.064336)
					(mid 110.844076 -217.064336)
					(end 111.496856 -217.064336)
				)
			)
		)
	)
	(zone
		(layers "B.Cu" "In6.Cu" "In11.Cu" "In13.Cu" "In15.Cu")
		(hatch none 0.5)
		(connect_pads
			(clearance 0)
		)
		(min_thickness 0.25)
		(keepout
			(tracks not_allowed)
			(vias allowed)
			(pads allowed)
			(copperpour not_allowed)
			(footprints allowed)
		)
		(placement
			(enabled no)
			(sheetname "")
		)
		(fill yes
			(thermal_gap 0.5)
			(thermal_bridge_width 0.5)
			(island_removal_mode 0)
		)
		(polygon
			(pts
				(arc
					(start 376.823224 -248.806208)
					(mid 376.170444 -248.806208)
					(end 376.823224 -248.806208)
				)
			)
		)
	)
	(zone
		(layers "B.Cu" "In6.Cu" "In11.Cu" "In13.Cu" "In15.Cu")
		(hatch none 0.5)
		(connect_pads
			(clearance 0)
		)
		(min_thickness 0.25)
		(keepout
			(tracks not_allowed)
			(vias allowed)
			(pads allowed)
			(copperpour not_allowed)
			(footprints allowed)
		)
		(placement
			(enabled no)
			(sheetname "")
		)
		(fill yes
			(thermal_gap 0.5)
			(thermal_bridge_width 0.5)
			(island_removal_mode 0)
		)
		(polygon
			(pts
				(arc
					(start 335.002124 -223.575626)
					(mid 334.349344 -223.575626)
					(end 335.002124 -223.575626)
				)
			)
		)
	)
	(zone
		(layers "B.Cu" "In6.Cu" "In11.Cu" "In13.Cu" "In15.Cu")
		(hatch none 0.5)
		(connect_pads
			(clearance 0)
		)
		(min_thickness 0.25)
		(keepout
			(tracks not_allowed)
			(vias allowed)
			(pads allowed)
			(copperpour not_allowed)
			(footprints allowed)
		)
		(placement
			(enabled no)
			(sheetname "")
		)
		(fill yes
			(thermal_gap 0.5)
			(thermal_bridge_width 0.5)
			(island_removal_mode 0)
		)
		(polygon
			(pts
				(arc
					(start 36.303204 -311.216802)
					(mid 35.650424 -311.216802)
					(end 36.303204 -311.216802)
				)
			)
		)
	)
	(zone
		(layers "B.Cu" "In6.Cu" "In11.Cu" "In13.Cu" "In15.Cu")
		(hatch none 0.5)
		(connect_pads
			(clearance 0)
		)
		(min_thickness 0.25)
		(keepout
			(tracks not_allowed)
			(vias allowed)
			(pads allowed)
			(copperpour not_allowed)
			(footprints allowed)
		)
		(placement
			(enabled no)
			(sheetname "")
		)
		(fill yes
			(thermal_gap 0.5)
			(thermal_bridge_width 0.5)
			(island_removal_mode 0)
		)
		(polygon
			(pts
				(arc
					(start 421.062404 -284.016704)
					(mid 420.409624 -284.016704)
					(end 421.062404 -284.016704)
				)
			)
		)
	)
	(zone
		(layers "B.Cu" "In6.Cu" "In11.Cu" "In13.Cu" "In15.Cu")
		(hatch none 0.5)
		(connect_pads
			(clearance 0)
		)
		(min_thickness 0.25)
		(keepout
			(tracks not_allowed)
			(vias allowed)
			(pads allowed)
			(copperpour not_allowed)
			(footprints allowed)
		)
		(placement
			(enabled no)
			(sheetname "")
		)
		(fill yes
			(thermal_gap 0.5)
			(thermal_bridge_width 0.5)
			(island_removal_mode 0)
		)
		(polygon
			(pts
				(arc
					(start 127.583184 -256.361438)
					(mid 126.930404 -256.361438)
					(end 127.583184 -256.361438)
				)
			)
		)
	)
	(zone
		(layers "B.Cu" "In6.Cu" "In11.Cu" "In13.Cu" "In15.Cu")
		(hatch none 0.5)
		(connect_pads
			(clearance 0)
		)
		(min_thickness 0.25)
		(keepout
			(tracks not_allowed)
			(vias allowed)
			(pads allowed)
			(copperpour not_allowed)
			(footprints allowed)
		)
		(placement
			(enabled no)
			(sheetname "")
		)
		(fill yes
			(thermal_gap 0.5)
			(thermal_bridge_width 0.5)
			(island_removal_mode 0)
		)
		(polygon
			(pts
				(arc
					(start 295.230804 -286.56661)
					(mid 294.578024 -286.56661)
					(end 295.230804 -286.56661)
				)
			)
		)
	)
	(zone
		(layers "B.Cu" "In6.Cu" "In11.Cu" "In13.Cu" "In15.Cu")
		(hatch none 0.5)
		(connect_pads
			(clearance 0)
		)
		(min_thickness 0.25)
		(keepout
			(tracks not_allowed)
			(vias allowed)
			(pads allowed)
			(copperpour not_allowed)
			(footprints allowed)
		)
		(placement
			(enabled no)
			(sheetname "")
		)
		(fill yes
			(thermal_gap 0.5)
			(thermal_bridge_width 0.5)
			(island_removal_mode 0)
		)
		(polygon
			(pts
				(arc
					(start 36.303204 -212.616796)
					(mid 35.650424 -212.616796)
					(end 36.303204 -212.616796)
				)
			)
		)
	)
	(zone
		(layers "B.Cu" "In6.Cu" "In11.Cu" "In13.Cu" "In15.Cu")
		(hatch none 0.5)
		(connect_pads
			(clearance 0)
		)
		(min_thickness 0.25)
		(keepout
			(tracks not_allowed)
			(vias allowed)
			(pads allowed)
			(copperpour not_allowed)
			(footprints allowed)
		)
		(placement
			(enabled no)
			(sheetname "")
		)
		(fill yes
			(thermal_gap 0.5)
			(thermal_bridge_width 0.5)
			(island_removal_mode 0)
		)
		(polygon
			(pts
				(arc
					(start 375.053606 -258.80314)
					(mid 374.400826 -258.80314)
					(end 375.053606 -258.80314)
				)
			)
		)
	)
	(zone
		(layers "B.Cu" "In6.Cu" "In11.Cu" "In13.Cu" "In15.Cu")
		(hatch none 0.5)
		(connect_pads
			(clearance 0)
		)
		(min_thickness 0.25)
		(keepout
			(tracks not_allowed)
			(vias allowed)
			(pads allowed)
			(copperpour not_allowed)
			(footprints allowed)
		)
		(placement
			(enabled no)
			(sheetname "")
		)
		(fill yes
			(thermal_gap 0.5)
			(thermal_bridge_width 0.5)
			(island_removal_mode 0)
		)
		(polygon
			(pts
				(arc
					(start 195.753736 -267.866622)
					(mid 195.100956 -267.866622)
					(end 195.753736 -267.866622)
				)
			)
		)
	)
	(zone
		(layers "B.Cu" "In6.Cu" "In11.Cu" "In13.Cu" "In15.Cu")
		(hatch none 0.5)
		(connect_pads
			(clearance 0)
		)
		(min_thickness 0.25)
		(keepout
			(tracks not_allowed)
			(vias allowed)
			(pads allowed)
			(copperpour not_allowed)
			(footprints allowed)
		)
		(placement
			(enabled no)
			(sheetname "")
		)
		(fill yes
			(thermal_gap 0.5)
			(thermal_bridge_width 0.5)
			(island_removal_mode 0)
		)
		(polygon
			(pts
				(arc
					(start 341.156798 5.895594)
					(mid 340.453218 5.895594)
					(end 341.156798 5.895594)
				)
			)
		)
	)
	(zone
		(layers "B.Cu" "In6.Cu" "In11.Cu" "In13.Cu" "In15.Cu")
		(hatch none 0.5)
		(connect_pads
			(clearance 0)
		)
		(min_thickness 0.25)
		(keepout
			(tracks not_allowed)
			(vias allowed)
			(pads allowed)
			(copperpour not_allowed)
			(footprints allowed)
		)
		(placement
			(enabled no)
			(sheetname "")
		)
		(fill yes
			(thermal_gap 0.5)
			(thermal_bridge_width 0.5)
			(island_removal_mode 0)
		)
		(polygon
			(pts
				(arc
					(start 122.774202 -217.064336)
					(mid 122.121422 -217.064336)
					(end 122.774202 -217.064336)
				)
			)
		)
	)
	(zone
		(layers "B.Cu" "In6.Cu" "In11.Cu" "In13.Cu" "In15.Cu")
		(hatch none 0.5)
		(connect_pads
			(clearance 0)
		)
		(min_thickness 0.25)
		(keepout
			(tracks not_allowed)
			(vias allowed)
			(pads allowed)
			(copperpour not_allowed)
			(footprints allowed)
		)
		(placement
			(enabled no)
			(sheetname "")
		)
		(fill yes
			(thermal_gap 0.5)
			(thermal_bridge_width 0.5)
			(island_removal_mode 0)
		)
		(polygon
			(pts
				(arc
					(start 20.19427 -384.920744)
					(mid 19.49069 -384.920744)
					(end 20.19427 -384.920744)
				)
			)
		)
	)
	(zone
		(layers "B.Cu" "In6.Cu" "In11.Cu" "In13.Cu" "In15.Cu")
		(hatch none 0.5)
		(connect_pads
			(clearance 0)
		)
		(min_thickness 0.25)
		(keepout
			(tracks not_allowed)
			(vias allowed)
			(pads allowed)
			(copperpour not_allowed)
			(footprints allowed)
		)
		(placement
			(enabled no)
			(sheetname "")
		)
		(fill yes
			(thermal_gap 0.5)
			(thermal_bridge_width 0.5)
			(island_removal_mode 0)
		)
		(polygon
			(pts
				(arc
					(start 284.243272 -208.366614)
					(mid 283.590492 -208.366614)
					(end 284.243272 -208.366614)
				)
			)
		)
	)
	(zone
		(layers "B.Cu" "In6.Cu" "In11.Cu" "In13.Cu" "In15.Cu")
		(hatch none 0.5)
		(connect_pads
			(clearance 0)
		)
		(min_thickness 0.25)
		(keepout
			(tracks not_allowed)
			(vias allowed)
			(pads allowed)
			(copperpour not_allowed)
			(footprints allowed)
		)
		(placement
			(enabled no)
			(sheetname "")
		)
		(fill yes
			(thermal_gap 0.5)
			(thermal_bridge_width 0.5)
			(island_removal_mode 0)
		)
		(polygon
			(pts
				(arc
					(start 122.884438 -288.917126)
					(mid 122.231658 -288.917126)
					(end 122.884438 -288.917126)
				)
			)
		)
	)
	(zone
		(layers "B.Cu" "In6.Cu" "In11.Cu" "In13.Cu" "In15.Cu")
		(hatch none 0.5)
		(connect_pads
			(clearance 0)
		)
		(min_thickness 0.25)
		(keepout
			(tracks not_allowed)
			(vias allowed)
			(pads allowed)
			(copperpour not_allowed)
			(footprints allowed)
		)
		(placement
			(enabled no)
			(sheetname "")
		)
		(fill yes
			(thermal_gap 0.5)
			(thermal_bridge_width 0.5)
			(island_removal_mode 0)
		)
		(polygon
			(pts
				(arc
					(start 130.762756 -230.900478)
					(mid 130.109976 -230.900478)
					(end 130.762756 -230.900478)
				)
			)
		)
	)
	(zone
		(layers "B.Cu" "In6.Cu" "In11.Cu" "In13.Cu" "In15.Cu")
		(hatch none 0.5)
		(connect_pads
			(clearance 0)
		)
		(min_thickness 0.25)
		(keepout
			(tracks not_allowed)
			(vias allowed)
			(pads allowed)
			(copperpour not_allowed)
			(footprints allowed)
		)
		(placement
			(enabled no)
			(sheetname "")
		)
		(fill yes
			(thermal_gap 0.5)
			(thermal_bridge_width 0.5)
			(island_removal_mode 0)
		)
		(polygon
			(pts
				(arc
					(start 132.752338 -288.103056)
					(mid 132.099558 -288.103056)
					(end 132.752338 -288.103056)
				)
			)
		)
	)
	(zone
		(layers "B.Cu" "In6.Cu" "In11.Cu" "In13.Cu" "In15.Cu")
		(hatch none 0.5)
		(connect_pads
			(clearance 0)
		)
		(min_thickness 0.25)
		(keepout
			(tracks not_allowed)
			(vias allowed)
			(pads allowed)
			(copperpour not_allowed)
			(footprints allowed)
		)
		(placement
			(enabled no)
			(sheetname "")
		)
		(fill yes
			(thermal_gap 0.5)
			(thermal_bridge_width 0.5)
			(island_removal_mode 0)
		)
		(polygon
			(pts
				(arc
					(start 339.70087 -234.970066)
					(mid 339.04809 -234.970066)
					(end 339.70087 -234.970066)
				)
			)
		)
	)
	(zone
		(layers "B.Cu" "In6.Cu" "In11.Cu" "In13.Cu" "In15.Cu")
		(hatch none 0.5)
		(connect_pads
			(clearance 0)
		)
		(min_thickness 0.25)
		(keepout
			(tracks not_allowed)
			(vias allowed)
			(pads allowed)
			(copperpour not_allowed)
			(footprints allowed)
		)
		(placement
			(enabled no)
			(sheetname "")
		)
		(fill yes
			(thermal_gap 0.5)
			(thermal_bridge_width 0.5)
			(island_removal_mode 0)
		)
		(polygon
			(pts
				(arc
					(start 295.230804 -305.266598)
					(mid 294.578024 -305.266598)
					(end 295.230804 -305.266598)
				)
			)
		)
	)
	(zone
		(layers "B.Cu" "In6.Cu" "In11.Cu" "In13.Cu" "In15.Cu")
		(hatch none 0.5)
		(connect_pads
			(clearance 0)
		)
		(min_thickness 0.25)
		(keepout
			(tracks not_allowed)
			(vias allowed)
			(pads allowed)
			(copperpour not_allowed)
			(footprints allowed)
		)
		(placement
			(enabled no)
			(sheetname "")
		)
		(fill yes
			(thermal_gap 0.5)
			(thermal_bridge_width 0.5)
			(island_removal_mode 0)
		)
		(polygon
			(pts
				(arc
					(start 340.281006 -263.686544)
					(mid 339.628226 -263.686544)
					(end 340.281006 -263.686544)
				)
			)
		)
	)
	(zone
		(layers "B.Cu" "In6.Cu" "In11.Cu" "In13.Cu" "In15.Cu")
		(hatch none 0.5)
		(connect_pads
			(clearance 0)
		)
		(min_thickness 0.25)
		(keepout
			(tracks not_allowed)
			(vias allowed)
			(pads allowed)
			(copperpour not_allowed)
			(footprints allowed)
		)
		(placement
			(enabled no)
			(sheetname "")
		)
		(fill yes
			(thermal_gap 0.5)
			(thermal_bridge_width 0.5)
			(island_removal_mode 0)
		)
		(polygon
			(pts
				(arc
					(start 440.250072 -250.016772)
					(mid 439.597292 -250.016772)
					(end 440.250072 -250.016772)
				)
			)
		)
	)
	(zone
		(layers "B.Cu" "In6.Cu" "In11.Cu" "In13.Cu" "In15.Cu")
		(hatch none 0.5)
		(connect_pads
			(clearance 0)
		)
		(min_thickness 0.25)
		(keepout
			(tracks not_allowed)
			(vias allowed)
			(pads allowed)
			(copperpour not_allowed)
			(footprints allowed)
		)
		(placement
			(enabled no)
			(sheetname "")
		)
		(fill yes
			(thermal_gap 0.5)
			(thermal_bridge_width 0.5)
			(island_removal_mode 0)
		)
		(polygon
			(pts
				(arc
					(start 106.797602 -218.692222)
					(mid 106.144822 -218.692222)
					(end 106.797602 -218.692222)
				)
			)
		)
	)
	(zone
		(layers "B.Cu" "In6.Cu" "In11.Cu" "In13.Cu" "In15.Cu")
		(hatch none 0.5)
		(connect_pads
			(clearance 0)
		)
		(min_thickness 0.25)
		(keepout
			(tracks not_allowed)
			(vias allowed)
			(pads allowed)
			(copperpour not_allowed)
			(footprints allowed)
		)
		(placement
			(enabled no)
			(sheetname "")
		)
		(fill yes
			(thermal_gap 0.5)
			(thermal_bridge_width 0.5)
			(island_removal_mode 0)
		)
		(polygon
			(pts
				(arc
					(start 87.531702 -226.017328)
					(mid 86.878922 -226.017328)
					(end 87.531702 -226.017328)
				)
			)
		)
	)
	(zone
		(layers "B.Cu" "In6.Cu" "In11.Cu" "In13.Cu" "In15.Cu")
		(hatch none 0.5)
		(connect_pads
			(clearance 0)
		)
		(min_thickness 0.25)
		(keepout
			(tracks not_allowed)
			(vias allowed)
			(pads allowed)
			(copperpour not_allowed)
			(footprints allowed)
		)
		(placement
			(enabled no)
			(sheetname "")
		)
		(fill yes
			(thermal_gap 0.5)
			(thermal_bridge_width 0.5)
			(island_removal_mode 0)
		)
		(polygon
			(pts
				(arc
					(start 440.250072 -210.916774)
					(mid 439.597292 -210.916774)
					(end 440.250072 -210.916774)
				)
			)
		)
	)
	(zone
		(layers "B.Cu" "In6.Cu" "In11.Cu" "In13.Cu" "In15.Cu")
		(hatch none 0.5)
		(connect_pads
			(clearance 0)
		)
		(min_thickness 0.25)
		(keepout
			(tracks not_allowed)
			(vias allowed)
			(pads allowed)
			(copperpour not_allowed)
			(footprints allowed)
		)
		(placement
			(enabled no)
			(sheetname "")
		)
		(fill yes
			(thermal_gap 0.5)
			(thermal_bridge_width 0.5)
			(island_removal_mode 0)
		)
		(polygon
			(pts
				(arc
					(start 343.100406 -288.103056)
					(mid 342.447626 -288.103056)
					(end 343.100406 -288.103056)
				)
			)
		)
	)
	(zone
		(layers "B.Cu" "In6.Cu" "In11.Cu" "In13.Cu" "In15.Cu")
		(hatch none 0.5)
		(connect_pads
			(clearance 0)
		)
		(min_thickness 0.25)
		(keepout
			(tracks not_allowed)
			(vias allowed)
			(pads allowed)
			(copperpour not_allowed)
			(footprints allowed)
		)
		(placement
			(enabled no)
			(sheetname "")
		)
		(fill yes
			(thermal_gap 0.5)
			(thermal_bridge_width 0.5)
			(island_removal_mode 0)
		)
		(polygon
			(pts
				(arc
					(start 92.810584 -272.639282)
					(mid 92.157804 -272.639282)
					(end 92.810584 -272.639282)
				)
			)
		)
	)
	(zone
		(layers "B.Cu" "In6.Cu" "In11.Cu" "In13.Cu" "In15.Cu")
		(hatch none 0.5)
		(connect_pads
			(clearance 0)
		)
		(min_thickness 0.25)
		(keepout
			(tracks not_allowed)
			(vias allowed)
			(pads allowed)
			(copperpour not_allowed)
			(footprints allowed)
		)
		(placement
			(enabled no)
			(sheetname "")
		)
		(fill yes
			(thermal_gap 0.5)
			(thermal_bridge_width 0.5)
			(island_removal_mode 0)
		)
		(polygon
			(pts
				(arc
					(start 104.448356 -217.878406)
					(mid 103.795576 -217.878406)
					(end 104.448356 -217.878406)
				)
			)
		)
	)
	(zone
		(layers "B.Cu" "In6.Cu" "In11.Cu" "In13.Cu" "In15.Cu")
		(hatch none 0.5)
		(connect_pads
			(clearance 0)
		)
		(min_thickness 0.25)
		(keepout
			(tracks not_allowed)
			(vias allowed)
			(pads allowed)
			(copperpour not_allowed)
			(footprints allowed)
		)
		(placement
			(enabled no)
			(sheetname "")
		)
		(fill yes
			(thermal_gap 0.5)
			(thermal_bridge_width 0.5)
			(island_removal_mode 0)
		)
		(polygon
			(pts
				(arc
					(start 284.243272 -309.51678)
					(mid 283.590492 -309.51678)
					(end 284.243272 -309.51678)
				)
			)
		)
	)
	(zone
		(layers "B.Cu" "In6.Cu" "In11.Cu" "In13.Cu" "In15.Cu")
		(hatch none 0.5)
		(connect_pads
			(clearance 0)
		)
		(min_thickness 0.25)
		(keepout
			(tracks not_allowed)
			(vias allowed)
			(pads allowed)
			(copperpour not_allowed)
			(footprints allowed)
		)
		(placement
			(enabled no)
			(sheetname "")
		)
		(fill yes
			(thermal_gap 0.5)
			(thermal_bridge_width 0.5)
			(island_removal_mode 0)
		)
		(polygon
			(pts
				(arc
					(start 377.403106 -288.917126)
					(mid 376.750326 -288.917126)
					(end 377.403106 -288.917126)
				)
			)
		)
	)
	(zone
		(layers "B.Cu" "In6.Cu" "In11.Cu" "In13.Cu" "In15.Cu")
		(hatch none 0.5)
		(connect_pads
			(clearance 0)
		)
		(min_thickness 0.25)
		(keepout
			(tracks not_allowed)
			(vias allowed)
			(pads allowed)
			(copperpour not_allowed)
			(footprints allowed)
		)
		(placement
			(enabled no)
			(sheetname "")
		)
		(fill yes
			(thermal_gap 0.5)
			(thermal_bridge_width 0.5)
			(island_removal_mode 0)
		)
		(polygon
			(pts
				(arc
					(start 126.643384 -257.98907)
					(mid 125.990604 -257.98907)
					(end 126.643384 -257.98907)
				)
			)
		)
	)
	(zone
		(layers "B.Cu" "In6.Cu" "In11.Cu" "In13.Cu" "In15.Cu")
		(hatch none 0.5)
		(connect_pads
			(clearance 0)
		)
		(min_thickness 0.25)
		(keepout
			(tracks not_allowed)
			(vias allowed)
			(pads allowed)
			(copperpour not_allowed)
			(footprints allowed)
		)
		(placement
			(enabled no)
			(sheetname "")
		)
		(fill yes
			(thermal_gap 0.5)
			(thermal_bridge_width 0.5)
			(island_removal_mode 0)
		)
		(polygon
			(pts
				(arc
					(start 350.97847 -218.692222)
					(mid 350.32569 -218.692222)
					(end 350.97847 -218.692222)
				)
			)
		)
	)
	(zone
		(layers "B.Cu" "In6.Cu" "In11.Cu" "In13.Cu" "In15.Cu")
		(hatch none 0.5)
		(connect_pads
			(clearance 0)
		)
		(min_thickness 0.25)
		(keepout
			(tracks not_allowed)
			(vias allowed)
			(pads allowed)
			(copperpour not_allowed)
			(footprints allowed)
		)
		(placement
			(enabled no)
			(sheetname "")
		)
		(fill yes
			(thermal_gap 0.5)
			(thermal_bridge_width 0.5)
			(island_removal_mode 0)
		)
		(polygon
			(pts
				(arc
					(start 351.91827 -217.064336)
					(mid 351.26549 -217.064336)
					(end 351.91827 -217.064336)
				)
			)
		)
	)
	(zone
		(layers "B.Cu" "In6.Cu" "In11.Cu" "In13.Cu" "In15.Cu")
		(hatch none 0.5)
		(connect_pads
			(clearance 0)
		)
		(min_thickness 0.25)
		(keepout
			(tracks not_allowed)
			(vias allowed)
			(pads allowed)
			(copperpour not_allowed)
			(footprints allowed)
		)
		(placement
			(enabled no)
			(sheetname "")
		)
		(fill yes
			(thermal_gap 0.5)
			(thermal_bridge_width 0.5)
			(island_removal_mode 0)
		)
		(polygon
			(pts
				(arc
					(start 440.250072 -290.816538)
					(mid 439.597292 -290.816538)
					(end 440.250072 -290.816538)
				)
			)
		)
	)
	(zone
		(layers "B.Cu" "In6.Cu" "In11.Cu" "In13.Cu" "In15.Cu")
		(hatch none 0.5)
		(connect_pads
			(clearance 0)
		)
		(min_thickness 0.25)
		(keepout
			(tracks not_allowed)
			(vias allowed)
			(pads allowed)
			(copperpour not_allowed)
			(footprints allowed)
		)
		(placement
			(enabled no)
			(sheetname "")
		)
		(fill yes
			(thermal_gap 0.5)
			(thermal_bridge_width 0.5)
			(island_removal_mode 0)
		)
		(polygon
			(pts
				(arc
					(start 295.230804 -288.266632)
					(mid 294.578024 -288.266632)
					(end 295.230804 -288.266632)
				)
			)
		)
	)
	(zone
		(layers "B.Cu" "In6.Cu" "In11.Cu" "In13.Cu" "In15.Cu")
		(hatch none 0.5)
		(connect_pads
			(clearance 0)
		)
		(min_thickness 0.25)
		(keepout
			(tracks not_allowed)
			(vias allowed)
			(pads allowed)
			(copperpour not_allowed)
			(footprints allowed)
		)
		(placement
			(enabled no)
			(sheetname "")
		)
		(fill yes
			(thermal_gap 0.5)
			(thermal_bridge_width 0.5)
			(island_removal_mode 0)
		)
		(polygon
			(pts
				(arc
					(start 130.292602 -246.364506)
					(mid 129.639822 -246.364506)
					(end 130.292602 -246.364506)
				)
			)
		)
	)
	(zone
		(layers "B.Cu" "In6.Cu" "In11.Cu" "In13.Cu" "In15.Cu")
		(hatch none 0.5)
		(connect_pads
			(clearance 0)
		)
		(min_thickness 0.25)
		(keepout
			(tracks not_allowed)
			(vias allowed)
			(pads allowed)
			(copperpour not_allowed)
			(footprints allowed)
		)
		(placement
			(enabled no)
			(sheetname "")
		)
		(fill yes
			(thermal_gap 0.5)
			(thermal_bridge_width 0.5)
			(island_removal_mode 0)
		)
		(polygon
			(pts
				(arc
					(start 340.281006 -262.058658)
					(mid 339.628226 -262.058658)
					(end 340.281006 -262.058658)
				)
			)
		)
	)
	(zone
		(layers "B.Cu" "In6.Cu" "In11.Cu" "In13.Cu" "In15.Cu")
		(hatch none 0.5)
		(connect_pads
			(clearance 0)
		)
		(min_thickness 0.25)
		(keepout
			(tracks not_allowed)
			(vias allowed)
			(pads allowed)
			(copperpour not_allowed)
			(footprints allowed)
		)
		(placement
			(enabled no)
			(sheetname "")
		)
		(fill yes
			(thermal_gap 0.5)
			(thermal_bridge_width 0.5)
			(island_removal_mode 0)
		)
		(polygon
			(pts
				(arc
					(start 380.222252 -261.244842)
					(mid 379.569472 -261.244842)
					(end 380.222252 -261.244842)
				)
			)
		)
	)
	(zone
		(layers "B.Cu" "In6.Cu" "In11.Cu" "In13.Cu" "In15.Cu")
		(hatch none 0.5)
		(connect_pads
			(clearance 0)
		)
		(min_thickness 0.25)
		(keepout
			(tracks not_allowed)
			(vias allowed)
			(pads allowed)
			(copperpour not_allowed)
			(footprints allowed)
		)
		(placement
			(enabled no)
			(sheetname "")
		)
		(fill yes
			(thermal_gap 0.5)
			(thermal_bridge_width 0.5)
			(island_removal_mode 0)
		)
		(polygon
			(pts
				(arc
					(start 51.390804 -195.616576)
					(mid 50.738024 -195.616576)
					(end 51.390804 -195.616576)
				)
			)
		)
	)
	(zone
		(layers "B.Cu" "In6.Cu" "In11.Cu" "In13.Cu" "In15.Cu")
		(hatch none 0.5)
		(connect_pads
			(clearance 0)
		)
		(min_thickness 0.25)
		(keepout
			(tracks not_allowed)
			(vias allowed)
			(pads allowed)
			(copperpour not_allowed)
			(footprints allowed)
		)
		(placement
			(enabled no)
			(sheetname "")
		)
		(fill yes
			(thermal_gap 0.5)
			(thermal_bridge_width 0.5)
			(island_removal_mode 0)
		)
		(polygon
			(pts
				(arc
					(start 382.462024 -217.878406)
					(mid 381.809244 -217.878406)
					(end 382.462024 -217.878406)
				)
			)
		)
	)
	(zone
		(layers "B.Cu" "In6.Cu" "In11.Cu" "In13.Cu" "In15.Cu")
		(hatch none 0.5)
		(connect_pads
			(clearance 0)
		)
		(min_thickness 0.25)
		(keepout
			(tracks not_allowed)
			(vias allowed)
			(pads allowed)
			(copperpour not_allowed)
			(footprints allowed)
		)
		(placement
			(enabled no)
			(sheetname "")
		)
		(fill yes
			(thermal_gap 0.5)
			(thermal_bridge_width 0.5)
			(island_removal_mode 0)
		)
		(polygon
			(pts
				(arc
					(start 374.003824 -217.878406)
					(mid 373.351044 -217.878406)
					(end 374.003824 -217.878406)
				)
			)
		)
	)
	(zone
		(layers "B.Cu" "In6.Cu" "In11.Cu" "In13.Cu" "In15.Cu")
		(hatch none 0.5)
		(connect_pads
			(clearance 0)
		)
		(min_thickness 0.25)
		(keepout
			(tracks not_allowed)
			(vias allowed)
			(pads allowed)
			(copperpour not_allowed)
			(footprints allowed)
		)
		(placement
			(enabled no)
			(sheetname "")
		)
		(fill yes
			(thermal_gap 0.5)
			(thermal_bridge_width 0.5)
			(island_removal_mode 0)
		)
		(polygon
			(pts
				(arc
					(start 93.750384 -266.128246)
					(mid 93.097604 -266.128246)
					(end 93.750384 -266.128246)
				)
			)
		)
	)
	(zone
		(layers "B.Cu" "In6.Cu" "In11.Cu" "In13.Cu" "In15.Cu")
		(hatch none 0.5)
		(connect_pads
			(clearance 0)
		)
		(min_thickness 0.25)
		(keepout
			(tracks not_allowed)
			(vias allowed)
			(pads allowed)
			(copperpour not_allowed)
			(footprints allowed)
		)
		(placement
			(enabled no)
			(sheetname "")
		)
		(fill yes
			(thermal_gap 0.5)
			(thermal_bridge_width 0.5)
			(island_removal_mode 0)
		)
		(polygon
			(pts
				(arc
					(start 51.416204 -301.866808)
					(mid 50.763424 -301.866808)
					(end 51.416204 -301.866808)
				)
			)
		)
	)
	(zone
		(layers "B.Cu" "In6.Cu" "In11.Cu" "In13.Cu" "In15.Cu")
		(hatch none 0.5)
		(connect_pads
			(clearance 0)
		)
		(min_thickness 0.25)
		(keepout
			(tracks not_allowed)
			(vias allowed)
			(pads allowed)
			(copperpour not_allowed)
			(footprints allowed)
		)
		(placement
			(enabled no)
			(sheetname "")
		)
		(fill yes
			(thermal_gap 0.5)
			(thermal_bridge_width 0.5)
			(island_removal_mode 0)
		)
		(polygon
			(pts
				(arc
					(start 134.521956 -217.878406)
					(mid 133.869176 -217.878406)
					(end 134.521956 -217.878406)
				)
			)
		)
	)
	(zone
		(layers "B.Cu" "In6.Cu" "In11.Cu" "In13.Cu" "In15.Cu")
		(hatch none 0.5)
		(connect_pads
			(clearance 0)
		)
		(min_thickness 0.25)
		(keepout
			(tracks not_allowed)
			(vias allowed)
			(pads allowed)
			(copperpour not_allowed)
			(footprints allowed)
		)
		(placement
			(enabled no)
			(sheetname "")
		)
		(fill yes
			(thermal_gap 0.5)
			(thermal_bridge_width 0.5)
			(island_removal_mode 0)
		)
		(polygon
			(pts
				(arc
					(start 131.812538 -262.058658)
					(mid 131.159758 -262.058658)
					(end 131.812538 -262.058658)
				)
			)
		)
	)
	(zone
		(layers "B.Cu" "In6.Cu" "In11.Cu" "In13.Cu" "In15.Cu")
		(hatch none 0.5)
		(connect_pads
			(clearance 0)
		)
		(min_thickness 0.25)
		(keepout
			(tracks not_allowed)
			(vias allowed)
			(pads allowed)
			(copperpour not_allowed)
			(footprints allowed)
		)
		(placement
			(enabled no)
			(sheetname "")
		)
		(fill yes
			(thermal_gap 0.5)
			(thermal_bridge_width 0.5)
			(island_removal_mode 0)
		)
		(polygon
			(pts
				(arc
					(start 379.642624 -240.667286)
					(mid 378.989844 -240.667286)
					(end 379.642624 -240.667286)
				)
			)
		)
	)
	(zone
		(layers "B.Cu" "In6.Cu" "In11.Cu" "In13.Cu" "In15.Cu")
		(hatch none 0.5)
		(connect_pads
			(clearance 0)
		)
		(min_thickness 0.25)
		(keepout
			(tracks not_allowed)
			(vias allowed)
			(pads allowed)
			(copperpour not_allowed)
			(footprints allowed)
		)
		(placement
			(enabled no)
			(sheetname "")
		)
		(fill yes
			(thermal_gap 0.5)
			(thermal_bridge_width 0.5)
			(island_removal_mode 0)
		)
		(polygon
			(pts
				(arc
					(start 47.290736 -305.266598)
					(mid 46.637956 -305.266598)
					(end 47.290736 -305.266598)
				)
			)
		)
	)
	(zone
		(layers "B.Cu" "In6.Cu" "In11.Cu" "In13.Cu" "In15.Cu")
		(hatch none 0.5)
		(connect_pads
			(clearance 0)
		)
		(min_thickness 0.25)
		(keepout
			(tracks not_allowed)
			(vias allowed)
			(pads allowed)
			(copperpour not_allowed)
			(footprints allowed)
		)
		(placement
			(enabled no)
			(sheetname "")
		)
		(fill yes
			(thermal_gap 0.5)
			(thermal_bridge_width 0.5)
			(island_removal_mode 0)
		)
		(polygon
			(pts
				(arc
					(start 359.071926 -43.610784)
					(mid 358.368346 -43.610784)
					(end 359.071926 -43.610784)
				)
			)
		)
	)
	(zone
		(layers "B.Cu" "In6.Cu" "In11.Cu" "In13.Cu" "In15.Cu")
		(hatch none 0.5)
		(connect_pads
			(clearance 0)
		)
		(min_thickness 0.25)
		(keepout
			(tracks not_allowed)
			(vias allowed)
			(pads allowed)
			(copperpour not_allowed)
			(footprints allowed)
		)
		(placement
			(enabled no)
			(sheetname "")
		)
		(fill yes
			(thermal_gap 0.5)
			(thermal_bridge_width 0.5)
			(island_removal_mode 0)
		)
		(polygon
			(pts
				(arc
					(start 102.098602 -217.064336)
					(mid 101.445822 -217.064336)
					(end 102.098602 -217.064336)
				)
			)
		)
	)
	(zone
		(layers "B.Cu" "In6.Cu" "In11.Cu" "In13.Cu" "In15.Cu")
		(hatch none 0.5)
		(connect_pads
			(clearance 0)
		)
		(min_thickness 0.25)
		(keepout
			(tracks not_allowed)
			(vias allowed)
			(pads allowed)
			(copperpour not_allowed)
			(footprints allowed)
		)
		(placement
			(enabled no)
			(sheetname "")
		)
		(fill yes
			(thermal_gap 0.5)
			(thermal_bridge_width 0.5)
			(island_removal_mode 0)
		)
		(polygon
			(pts
				(arc
					(start 127.583438 -288.917126)
					(mid 126.930658 -288.917126)
					(end 127.583438 -288.917126)
				)
			)
		)
	)
	(zone
		(layers "B.Cu" "In6.Cu" "In11.Cu" "In13.Cu" "In15.Cu")
		(hatch none 0.5)
		(connect_pads
			(clearance 0)
		)
		(min_thickness 0.25)
		(keepout
			(tracks not_allowed)
			(vias allowed)
			(pads allowed)
			(copperpour not_allowed)
			(footprints allowed)
		)
		(placement
			(enabled no)
			(sheetname "")
		)
		(fill yes
			(thermal_gap 0.5)
			(thermal_bridge_width 0.5)
			(island_removal_mode 0)
		)
		(polygon
			(pts
				(arc
					(start 295.230804 -282.316682)
					(mid 294.578024 -282.316682)
					(end 295.230804 -282.316682)
				)
			)
		)
	)
	(zone
		(layers "B.Cu" "In6.Cu" "In11.Cu" "In13.Cu" "In15.Cu")
		(hatch none 0.5)
		(connect_pads
			(clearance 0)
		)
		(min_thickness 0.25)
		(keepout
			(tracks not_allowed)
			(vias allowed)
			(pads allowed)
			(copperpour not_allowed)
			(footprints allowed)
		)
		(placement
			(enabled no)
			(sheetname "")
		)
		(fill yes
			(thermal_gap 0.5)
			(thermal_bridge_width 0.5)
			(island_removal_mode 0)
		)
		(polygon
			(pts
				(arc
					(start 380.692406 -288.103056)
					(mid 380.039626 -288.103056)
					(end 380.692406 -288.103056)
				)
			)
		)
	)
	(zone
		(layers "B.Cu" "In6.Cu" "In11.Cu" "In13.Cu" "In15.Cu")
		(hatch none 0.5)
		(connect_pads
			(clearance 0)
		)
		(min_thickness 0.25)
		(keepout
			(tracks not_allowed)
			(vias allowed)
			(pads allowed)
			(copperpour not_allowed)
			(footprints allowed)
		)
		(placement
			(enabled no)
			(sheetname "")
		)
		(fill yes
			(thermal_gap 0.5)
			(thermal_bridge_width 0.5)
			(island_removal_mode 0)
		)
		(polygon
			(pts
				(arc
					(start 280.143204 -295.916604)
					(mid 279.490424 -295.916604)
					(end 280.143204 -295.916604)
				)
			)
		)
	)
	(zone
		(layers "B.Cu" "In6.Cu" "In11.Cu" "In13.Cu" "In15.Cu")
		(hatch none 0.5)
		(connect_pads
			(clearance 0)
		)
		(min_thickness 0.25)
		(keepout
			(tracks not_allowed)
			(vias allowed)
			(pads allowed)
			(copperpour not_allowed)
			(footprints allowed)
		)
		(placement
			(enabled no)
			(sheetname "")
		)
		(fill yes
			(thermal_gap 0.5)
			(thermal_bridge_width 0.5)
			(island_removal_mode 0)
		)
		(polygon
			(pts
				(arc
					(start 95.160338 -255.547622)
					(mid 94.507558 -255.547622)
					(end 95.160338 -255.547622)
				)
			)
		)
	)
	(zone
		(layers "B.Cu" "In6.Cu" "In11.Cu" "In13.Cu" "In15.Cu")
		(hatch none 0.5)
		(connect_pads
			(clearance 0)
		)
		(min_thickness 0.25)
		(keepout
			(tracks not_allowed)
			(vias allowed)
			(pads allowed)
			(copperpour not_allowed)
			(footprints allowed)
		)
		(placement
			(enabled no)
			(sheetname "")
		)
		(fill yes
			(thermal_gap 0.5)
			(thermal_bridge_width 0.5)
			(island_removal_mode 0)
		)
		(polygon
			(pts
				(arc
					(start 133.691884 -289.807142)
					(mid 133.039104 -289.807142)
					(end 133.691884 -289.807142)
				)
			)
		)
	)
	(zone
		(layers "B.Cu" "In6.Cu" "In11.Cu" "In13.Cu" "In15.Cu")
		(hatch none 0.5)
		(connect_pads
			(clearance 0)
		)
		(min_thickness 0.25)
		(keepout
			(tracks not_allowed)
			(vias allowed)
			(pads allowed)
			(copperpour not_allowed)
			(footprints allowed)
		)
		(placement
			(enabled no)
			(sheetname "")
		)
		(fill yes
			(thermal_gap 0.5)
			(thermal_bridge_width 0.5)
			(island_removal_mode 0)
		)
		(polygon
			(pts
				(arc
					(start 335.00187 -226.831144)
					(mid 334.34909 -226.831144)
					(end 335.00187 -226.831144)
				)
			)
		)
	)
	(zone
		(layers "B.Cu" "In6.Cu" "In11.Cu" "In13.Cu" "In15.Cu")
		(hatch none 0.5)
		(connect_pads
			(clearance 0)
		)
		(min_thickness 0.25)
		(keepout
			(tracks not_allowed)
			(vias allowed)
			(pads allowed)
			(copperpour not_allowed)
			(footprints allowed)
		)
		(placement
			(enabled no)
			(sheetname "")
		)
		(fill yes
			(thermal_gap 0.5)
			(thermal_bridge_width 0.5)
			(island_removal_mode 0)
		)
		(polygon
			(pts
				(arc
					(start 425.162472 -227.066602)
					(mid 424.509692 -227.066602)
					(end 425.162472 -227.066602)
				)
			)
		)
	)
	(zone
		(layers "B.Cu" "In6.Cu" "In11.Cu" "In13.Cu" "In15.Cu")
		(hatch none 0.5)
		(connect_pads
			(clearance 0)
		)
		(min_thickness 0.25)
		(keepout
			(tracks not_allowed)
			(vias allowed)
			(pads allowed)
			(copperpour not_allowed)
			(footprints allowed)
		)
		(placement
			(enabled no)
			(sheetname "")
		)
		(fill yes
			(thermal_gap 0.5)
			(thermal_bridge_width 0.5)
			(island_removal_mode 0)
		)
		(polygon
			(pts
				(arc
					(start 440.250072 -204.96657)
					(mid 439.597292 -204.96657)
					(end 440.250072 -204.96657)
				)
			)
		)
	)
	(zone
		(layers "B.Cu" "In6.Cu" "In11.Cu" "In13.Cu" "In15.Cu")
		(hatch none 0.5)
		(connect_pads
			(clearance 0)
		)
		(min_thickness 0.25)
		(keepout
			(tracks not_allowed)
			(vias allowed)
			(pads allowed)
			(copperpour not_allowed)
			(footprints allowed)
		)
		(placement
			(enabled no)
			(sheetname "")
		)
		(fill yes
			(thermal_gap 0.5)
			(thermal_bridge_width 0.5)
			(island_removal_mode 0)
		)
		(polygon
			(pts
				(arc
					(start 23.465282 -385.809998)
					(mid 22.761702 -385.809998)
					(end 23.465282 -385.809998)
				)
			)
		)
	)
	(zone
		(layers "B.Cu" "In6.Cu" "In11.Cu" "In13.Cu" "In15.Cu")
		(hatch none 0.5)
		(connect_pads
			(clearance 0)
		)
		(min_thickness 0.25)
		(keepout
			(tracks not_allowed)
			(vias allowed)
			(pads allowed)
			(copperpour not_allowed)
			(footprints allowed)
		)
		(placement
			(enabled no)
			(sheetname "")
		)
		(fill yes
			(thermal_gap 0.5)
			(thermal_bridge_width 0.5)
			(island_removal_mode 0)
		)
		(polygon
			(pts
				(arc
					(start 436.150004 -295.916604)
					(mid 435.497224 -295.916604)
					(end 436.150004 -295.916604)
				)
			)
		)
	)
	(zone
		(layers "B.Cu" "In6.Cu" "In11.Cu" "In13.Cu" "In15.Cu")
		(hatch none 0.5)
		(connect_pads
			(clearance 0)
		)
		(min_thickness 0.25)
		(keepout
			(tracks not_allowed)
			(vias allowed)
			(pads allowed)
			(copperpour not_allowed)
			(footprints allowed)
		)
		(placement
			(enabled no)
			(sheetname "")
		)
		(fill yes
			(thermal_gap 0.5)
			(thermal_bridge_width 0.5)
			(island_removal_mode 0)
		)
		(polygon
			(pts
				(arc
					(start 36.303204 -234.716574)
					(mid 35.650424 -234.716574)
					(end 36.303204 -234.716574)
				)
			)
		)
	)
	(zone
		(layers "B.Cu" "In6.Cu" "In11.Cu" "In13.Cu" "In15.Cu")
		(hatch none 0.5)
		(connect_pads
			(clearance 0)
		)
		(min_thickness 0.25)
		(keepout
			(tracks not_allowed)
			(vias allowed)
			(pads allowed)
			(copperpour not_allowed)
			(footprints allowed)
		)
		(placement
			(enabled no)
			(sheetname "")
		)
		(fill yes
			(thermal_gap 0.5)
			(thermal_bridge_width 0.5)
			(island_removal_mode 0)
		)
		(polygon
			(pts
				(arc
					(start 359.436924 -217.064336)
					(mid 358.784144 -217.064336)
					(end 359.436924 -217.064336)
				)
			)
		)
	)
	(zone
		(layers "B.Cu" "In6.Cu" "In11.Cu" "In13.Cu" "In15.Cu")
		(hatch none 0.5)
		(connect_pads
			(clearance 0)
		)
		(min_thickness 0.25)
		(keepout
			(tracks not_allowed)
			(vias allowed)
			(pads allowed)
			(copperpour not_allowed)
			(footprints allowed)
		)
		(placement
			(enabled no)
			(sheetname "")
		)
		(fill yes
			(thermal_gap 0.5)
			(thermal_bridge_width 0.5)
			(island_removal_mode 0)
		)
		(polygon
			(pts
				(arc
					(start 380.11227 -241.481102)
					(mid 379.45949 -241.481102)
					(end 380.11227 -241.481102)
				)
			)
		)
	)
	(zone
		(layers "B.Cu" "In6.Cu" "In11.Cu" "In13.Cu" "In15.Cu")
		(hatch none 0.5)
		(connect_pads
			(clearance 0)
		)
		(min_thickness 0.25)
		(keepout
			(tracks not_allowed)
			(vias allowed)
			(pads allowed)
			(copperpour not_allowed)
			(footprints allowed)
		)
		(placement
			(enabled no)
			(sheetname "")
		)
		(fill yes
			(thermal_gap 0.5)
			(thermal_bridge_width 0.5)
			(island_removal_mode 0)
		)
		(polygon
			(pts
				(arc
					(start 47.290736 -306.96662)
					(mid 46.637956 -306.96662)
					(end 47.290736 -306.96662)
				)
			)
		)
	)
	(zone
		(layers "B.Cu" "In6.Cu" "In11.Cu" "In13.Cu" "In15.Cu")
		(hatch none 0.5)
		(connect_pads
			(clearance 0)
		)
		(min_thickness 0.25)
		(keepout
			(tracks not_allowed)
			(vias allowed)
			(pads allowed)
			(copperpour not_allowed)
			(footprints allowed)
		)
		(placement
			(enabled no)
			(sheetname "")
		)
		(fill yes
			(thermal_gap 0.5)
			(thermal_bridge_width 0.5)
			(island_removal_mode 0)
		)
		(polygon
			(pts
				(arc
					(start 345.809824 -217.878406)
					(mid 345.157044 -217.878406)
					(end 345.809824 -217.878406)
				)
			)
		)
	)
	(zone
		(layers "B.Cu" "In6.Cu" "In11.Cu" "In13.Cu" "In15.Cu")
		(hatch none 0.5)
		(connect_pads
			(clearance 0)
		)
		(min_thickness 0.25)
		(keepout
			(tracks not_allowed)
			(vias allowed)
			(pads allowed)
			(copperpour not_allowed)
			(footprints allowed)
		)
		(placement
			(enabled no)
			(sheetname "")
		)
		(fill yes
			(thermal_gap 0.5)
			(thermal_bridge_width 0.5)
			(island_removal_mode 0)
		)
		(polygon
			(pts
				(arc
					(start 342.160606 -266.941808)
					(mid 341.507826 -266.941808)
					(end 342.160606 -266.941808)
				)
			)
		)
	)
	(zone
		(layers "B.Cu" "In6.Cu" "In11.Cu" "In13.Cu" "In15.Cu")
		(hatch none 0.5)
		(connect_pads
			(clearance 0)
		)
		(min_thickness 0.25)
		(keepout
			(tracks not_allowed)
			(vias allowed)
			(pads allowed)
			(copperpour not_allowed)
			(footprints allowed)
		)
		(placement
			(enabled no)
			(sheetname "")
		)
		(fill yes
			(thermal_gap 0.5)
			(thermal_bridge_width 0.5)
			(island_removal_mode 0)
		)
		(polygon
			(pts
				(arc
					(start 341.220806 -288.103056)
					(mid 340.568026 -288.103056)
					(end 341.220806 -288.103056)
				)
			)
		)
	)
	(zone
		(layers "B.Cu" "In6.Cu" "In11.Cu" "In13.Cu" "In15.Cu")
		(hatch none 0.5)
		(connect_pads
			(clearance 0)
		)
		(min_thickness 0.25)
		(keepout
			(tracks not_allowed)
			(vias allowed)
			(pads allowed)
			(copperpour not_allowed)
			(footprints allowed)
		)
		(placement
			(enabled no)
			(sheetname "")
		)
		(fill yes
			(thermal_gap 0.5)
			(thermal_bridge_width 0.5)
			(island_removal_mode 0)
		)
		(polygon
			(pts
				(arc
					(start 378.812806 -265.314176)
					(mid 378.160026 -265.314176)
					(end 378.812806 -265.314176)
				)
			)
		)
	)
	(zone
		(layers "B.Cu" "In6.Cu" "In11.Cu" "In13.Cu" "In15.Cu")
		(hatch none 0.5)
		(connect_pads
			(clearance 0)
		)
		(min_thickness 0.25)
		(keepout
			(tracks not_allowed)
			(vias allowed)
			(pads allowed)
			(copperpour not_allowed)
			(footprints allowed)
		)
		(placement
			(enabled no)
			(sheetname "")
		)
		(fill yes
			(thermal_gap 0.5)
			(thermal_bridge_width 0.5)
			(island_removal_mode 0)
		)
		(polygon
			(pts
				(arc
					(start 173.122336 -202.416664)
					(mid 172.469556 -202.416664)
					(end 173.122336 -202.416664)
				)
			)
		)
	)
	(zone
		(layers "B.Cu" "In6.Cu" "In11.Cu" "In13.Cu" "In15.Cu")
		(hatch none 0.5)
		(connect_pads
			(clearance 0)
		)
		(min_thickness 0.25)
		(keepout
			(tracks not_allowed)
			(vias allowed)
			(pads allowed)
			(copperpour not_allowed)
			(footprints allowed)
		)
		(placement
			(enabled no)
			(sheetname "")
		)
		(fill yes
			(thermal_gap 0.5)
			(thermal_bridge_width 0.5)
			(island_removal_mode 0)
		)
		(polygon
			(pts
				(arc
					(start 299.356272 -281.466798)
					(mid 298.703492 -281.466798)
					(end 299.356272 -281.466798)
				)
			)
		)
	)
	(zone
		(layers "B.Cu" "In6.Cu" "In11.Cu" "In13.Cu" "In15.Cu")
		(hatch none 0.5)
		(connect_pads
			(clearance 0)
		)
		(min_thickness 0.25)
		(keepout
			(tracks not_allowed)
			(vias allowed)
			(pads allowed)
			(copperpour not_allowed)
			(footprints allowed)
		)
		(placement
			(enabled no)
			(sheetname "")
		)
		(fill yes
			(thermal_gap 0.5)
			(thermal_bridge_width 0.5)
			(island_removal_mode 0)
		)
		(polygon
			(pts
				(arc
					(start 85.652102 -226.017328)
					(mid 84.999322 -226.017328)
					(end 85.652102 -226.017328)
				)
			)
		)
	)
	(zone
		(layers "B.Cu" "In6.Cu" "In11.Cu" "In13.Cu" "In15.Cu")
		(hatch none 0.5)
		(connect_pads
			(clearance 0)
		)
		(min_thickness 0.25)
		(keepout
			(tracks not_allowed)
			(vias allowed)
			(pads allowed)
			(copperpour not_allowed)
			(footprints allowed)
		)
		(placement
			(enabled no)
			(sheetname "")
		)
		(fill yes
			(thermal_gap 0.5)
			(thermal_bridge_width 0.5)
			(island_removal_mode 0)
		)
		(polygon
			(pts
				(arc
					(start 425.162472 -283.166566)
					(mid 424.509692 -283.166566)
					(end 425.162472 -283.166566)
				)
			)
		)
	)
	(zone
		(layers "B.Cu" "In6.Cu" "In11.Cu" "In13.Cu" "In15.Cu")
		(hatch none 0.5)
		(connect_pads
			(clearance 0)
		)
		(min_thickness 0.25)
		(keepout
			(tracks not_allowed)
			(vias allowed)
			(pads allowed)
			(copperpour not_allowed)
			(footprints allowed)
		)
		(placement
			(enabled no)
			(sheetname "")
		)
		(fill yes
			(thermal_gap 0.5)
			(thermal_bridge_width 0.5)
			(island_removal_mode 0)
		)
		(polygon
			(pts
				(arc
					(start 93.640402 -246.364506)
					(mid 92.987622 -246.364506)
					(end 93.640402 -246.364506)
				)
			)
		)
	)
	(zone
		(layers "B.Cu" "In6.Cu" "In11.Cu" "In13.Cu" "In15.Cu")
		(hatch none 0.5)
		(connect_pads
			(clearance 0)
		)
		(min_thickness 0.25)
		(keepout
			(tracks not_allowed)
			(vias allowed)
			(pads allowed)
			(copperpour not_allowed)
			(footprints allowed)
		)
		(placement
			(enabled no)
			(sheetname "")
		)
		(fill yes
			(thermal_gap 0.5)
			(thermal_bridge_width 0.5)
			(island_removal_mode 0)
		)
		(polygon
			(pts
				(arc
					(start 280.143204 -314.616592)
					(mid 279.490424 -314.616592)
					(end 280.143204 -314.616592)
				)
			)
		)
	)
	(zone
		(layers "B.Cu" "In6.Cu" "In11.Cu" "In13.Cu" "In15.Cu")
		(hatch none 0.5)
		(connect_pads
			(clearance 0)
		)
		(min_thickness 0.25)
		(keepout
			(tracks not_allowed)
			(vias allowed)
			(pads allowed)
			(copperpour not_allowed)
			(footprints allowed)
		)
		(placement
			(enabled no)
			(sheetname "")
		)
		(fill yes
			(thermal_gap 0.5)
			(thermal_bridge_width 0.5)
			(island_removal_mode 0)
		)
		(polygon
			(pts
				(arc
					(start 192.284604 -246.616728)
					(mid 191.631824 -246.616728)
					(end 192.284604 -246.616728)
				)
			)
		)
	)
	(zone
		(layers "B.Cu" "In6.Cu" "In11.Cu" "In13.Cu" "In15.Cu")
		(hatch none 0.5)
		(connect_pads
			(clearance 0)
		)
		(min_thickness 0.25)
		(keepout
			(tracks not_allowed)
			(vias allowed)
			(pads allowed)
			(copperpour not_allowed)
			(footprints allowed)
		)
		(placement
			(enabled no)
			(sheetname "")
		)
		(fill yes
			(thermal_gap 0.5)
			(thermal_bridge_width 0.5)
			(island_removal_mode 0)
		)
		(polygon
			(pts
				(arc
					(start 377.872752 -289.807142)
					(mid 377.219972 -289.807142)
					(end 377.872752 -289.807142)
				)
			)
		)
	)
	(zone
		(layers "B.Cu" "In6.Cu" "In11.Cu" "In13.Cu" "In15.Cu")
		(hatch none 0.5)
		(connect_pads
			(clearance 0)
		)
		(min_thickness 0.25)
		(keepout
			(tracks not_allowed)
			(vias allowed)
			(pads allowed)
			(copperpour not_allowed)
			(footprints allowed)
		)
		(placement
			(enabled no)
			(sheetname "")
		)
		(fill yes
			(thermal_gap 0.5)
			(thermal_bridge_width 0.5)
			(island_removal_mode 0)
		)
		(polygon
			(pts
				(arc
					(start 94.220538 -278.336502)
					(mid 93.567758 -278.336502)
					(end 94.220538 -278.336502)
				)
			)
		)
	)
	(zone
		(layers "B.Cu" "In6.Cu" "In11.Cu" "In13.Cu" "In15.Cu")
		(hatch none 0.5)
		(connect_pads
			(clearance 0)
		)
		(min_thickness 0.25)
		(keepout
			(tracks not_allowed)
			(vias allowed)
			(pads allowed)
			(copperpour not_allowed)
			(footprints allowed)
		)
		(placement
			(enabled no)
			(sheetname "")
		)
		(fill yes
			(thermal_gap 0.5)
			(thermal_bridge_width 0.5)
			(island_removal_mode 0)
		)
		(polygon
			(pts
				(arc
					(start 93.750384 -259.616956)
					(mid 93.097604 -259.616956)
					(end 93.750384 -259.616956)
				)
			)
		)
	)
	(zone
		(layers "B.Cu" "In6.Cu" "In11.Cu" "In13.Cu" "In15.Cu")
		(hatch none 0.5)
		(connect_pads
			(clearance 0)
		)
		(min_thickness 0.25)
		(keepout
			(tracks not_allowed)
			(vias allowed)
			(pads allowed)
			(copperpour not_allowed)
			(footprints allowed)
		)
		(placement
			(enabled no)
			(sheetname "")
		)
		(fill yes
			(thermal_gap 0.5)
			(thermal_bridge_width 0.5)
			(island_removal_mode 0)
		)
		(polygon
			(pts
				(arc
					(start 436.150004 -294.216582)
					(mid 435.497224 -294.216582)
					(end 436.150004 -294.216582)
				)
			)
		)
	)
	(zone
		(layers "B.Cu" "In6.Cu" "In11.Cu" "In13.Cu" "In15.Cu")
		(hatch none 0.5)
		(connect_pads
			(clearance 0)
		)
		(min_thickness 0.25)
		(keepout
			(tracks not_allowed)
			(vias allowed)
			(pads allowed)
			(copperpour not_allowed)
			(footprints allowed)
		)
		(placement
			(enabled no)
			(sheetname "")
		)
		(fill yes
			(thermal_gap 0.5)
			(thermal_bridge_width 0.5)
			(island_removal_mode 0)
		)
		(polygon
			(pts
				(arc
					(start 440.250072 -238.966756)
					(mid 439.597292 -238.966756)
					(end 440.250072 -238.966756)
				)
			)
		)
	)
	(zone
		(layers "B.Cu" "In6.Cu" "In11.Cu" "In13.Cu" "In15.Cu")
		(hatch none 0.5)
		(connect_pads
			(clearance 0)
		)
		(min_thickness 0.25)
		(keepout
			(tracks not_allowed)
			(vias allowed)
			(pads allowed)
			(copperpour not_allowed)
			(footprints allowed)
		)
		(placement
			(enabled no)
			(sheetname "")
		)
		(fill yes
			(thermal_gap 0.5)
			(thermal_bridge_width 0.5)
			(island_removal_mode 0)
		)
		(polygon
			(pts
				(arc
					(start 90.931238 -288.917126)
					(mid 90.278458 -288.917126)
					(end 90.931238 -288.917126)
				)
			)
		)
	)
	(zone
		(layers "B.Cu" "In6.Cu" "In11.Cu" "In13.Cu" "In15.Cu")
		(hatch none 0.5)
		(connect_pads
			(clearance 0)
		)
		(min_thickness 0.25)
		(keepout
			(tracks not_allowed)
			(vias allowed)
			(pads allowed)
			(copperpour not_allowed)
			(footprints allowed)
		)
		(placement
			(enabled no)
			(sheetname "")
		)
		(fill yes
			(thermal_gap 0.5)
			(thermal_bridge_width 0.5)
			(island_removal_mode 0)
		)
		(polygon
			(pts
				(arc
					(start 130.292602 -233.34218)
					(mid 129.639822 -233.34218)
					(end 130.292602 -233.34218)
				)
			)
		)
	)
	(zone
		(layers "B.Cu" "In6.Cu" "In11.Cu" "In13.Cu" "In15.Cu")
		(hatch none 0.5)
		(connect_pads
			(clearance 0)
		)
		(min_thickness 0.25)
		(keepout
			(tracks not_allowed)
			(vias allowed)
			(pads allowed)
			(copperpour not_allowed)
			(footprints allowed)
		)
		(placement
			(enabled no)
			(sheetname "")
		)
		(fill yes
			(thermal_gap 0.5)
			(thermal_bridge_width 0.5)
			(island_removal_mode 0)
		)
		(polygon
			(pts
				(arc
					(start 173.122336 -306.96662)
					(mid 172.469556 -306.96662)
					(end 173.122336 -306.96662)
				)
			)
		)
	)
	(zone
		(layers "B.Cu" "In6.Cu" "In11.Cu" "In13.Cu" "In15.Cu")
		(hatch none 0.5)
		(connect_pads
			(clearance 0)
		)
		(min_thickness 0.25)
		(keepout
			(tracks not_allowed)
			(vias allowed)
			(pads allowed)
			(copperpour not_allowed)
			(footprints allowed)
		)
		(placement
			(enabled no)
			(sheetname "")
		)
		(fill yes
			(thermal_gap 0.5)
			(thermal_bridge_width 0.5)
			(island_removal_mode 0)
		)
		(polygon
			(pts
				(arc
					(start 130.762756 -248.806208)
					(mid 130.109976 -248.806208)
					(end 130.762756 -248.806208)
				)
			)
		)
	)
	(zone
		(layers "B.Cu" "In6.Cu" "In11.Cu" "In13.Cu" "In15.Cu")
		(hatch none 0.5)
		(connect_pads
			(clearance 0)
		)
		(min_thickness 0.25)
		(keepout
			(tracks not_allowed)
			(vias allowed)
			(pads allowed)
			(copperpour not_allowed)
			(footprints allowed)
		)
		(placement
			(enabled no)
			(sheetname "")
		)
		(fill yes
			(thermal_gap 0.5)
			(thermal_bridge_width 0.5)
			(island_removal_mode 0)
		)
		(polygon
			(pts
				(arc
					(start 378.23267 -217.064336)
					(mid 377.57989 -217.064336)
					(end 378.23267 -217.064336)
				)
			)
		)
	)
	(zone
		(layers "B.Cu" "In6.Cu" "In11.Cu" "In13.Cu" "In15.Cu")
		(hatch none 0.5)
		(connect_pads
			(clearance 0)
		)
		(min_thickness 0.25)
		(keepout
			(tracks not_allowed)
			(vias allowed)
			(pads allowed)
			(copperpour not_allowed)
			(footprints allowed)
		)
		(placement
			(enabled no)
			(sheetname "")
		)
		(fill yes
			(thermal_gap 0.5)
			(thermal_bridge_width 0.5)
			(island_removal_mode 0)
		)
		(polygon
			(pts
				(arc
					(start 92.700602 -230.086662)
					(mid 92.047822 -230.086662)
					(end 92.700602 -230.086662)
				)
			)
		)
	)
	(zone
		(layers "B.Cu" "In6.Cu" "In11.Cu" "In13.Cu" "In15.Cu")
		(hatch none 0.5)
		(connect_pads
			(clearance 0)
		)
		(min_thickness 0.25)
		(keepout
			(tracks not_allowed)
			(vias allowed)
			(pads allowed)
			(copperpour not_allowed)
			(footprints allowed)
		)
		(placement
			(enabled no)
			(sheetname "")
		)
		(fill yes
			(thermal_gap 0.5)
			(thermal_bridge_width 0.5)
			(island_removal_mode 0)
		)
		(polygon
			(pts
				(arc
					(start 280.143204 -213.46668)
					(mid 279.490424 -213.46668)
					(end 280.143204 -213.46668)
				)
			)
		)
	)
	(zone
		(layers "B.Cu" "In6.Cu" "In11.Cu" "In13.Cu" "In15.Cu")
		(hatch none 0.5)
		(connect_pads
			(clearance 0)
		)
		(min_thickness 0.25)
		(keepout
			(tracks not_allowed)
			(vias allowed)
			(pads allowed)
			(copperpour not_allowed)
			(footprints allowed)
		)
		(placement
			(enabled no)
			(sheetname "")
		)
		(fill yes
			(thermal_gap 0.5)
			(thermal_bridge_width 0.5)
			(island_removal_mode 0)
		)
		(polygon
			(pts
				(arc
					(start 378.702824 -235.783882)
					(mid 378.050044 -235.783882)
					(end 378.702824 -235.783882)
				)
			)
		)
	)
	(zone
		(layers "B.Cu" "In6.Cu" "In11.Cu" "In13.Cu" "In15.Cu")
		(hatch none 0.5)
		(connect_pads
			(clearance 0)
		)
		(min_thickness 0.25)
		(keepout
			(tracks not_allowed)
			(vias allowed)
			(pads allowed)
			(copperpour not_allowed)
			(footprints allowed)
		)
		(placement
			(enabled no)
			(sheetname "")
		)
		(fill yes
			(thermal_gap 0.5)
			(thermal_bridge_width 0.5)
			(island_removal_mode 0)
		)
		(polygon
			(pts
				(arc
					(start 380.582424 -232.528364)
					(mid 379.929644 -232.528364)
					(end 380.582424 -232.528364)
				)
			)
		)
	)
	(zone
		(layers "B.Cu" "In6.Cu" "In11.Cu" "In13.Cu" "In15.Cu")
		(hatch none 0.5)
		(connect_pads
			(clearance 0)
		)
		(min_thickness 0.25)
		(keepout
			(tracks not_allowed)
			(vias allowed)
			(pads allowed)
			(copperpour not_allowed)
			(footprints allowed)
		)
		(placement
			(enabled no)
			(sheetname "")
		)
		(fill yes
			(thermal_gap 0.5)
			(thermal_bridge_width 0.5)
			(island_removal_mode 0)
		)
		(polygon
			(pts
				(arc
					(start 358.027224 -217.878406)
					(mid 357.374444 -217.878406)
					(end 358.027224 -217.878406)
				)
			)
		)
	)
	(zone
		(layers "B.Cu" "In6.Cu" "In11.Cu" "In13.Cu" "In15.Cu")
		(hatch none 0.5)
		(connect_pads
			(clearance 0)
		)
		(min_thickness 0.25)
		(keepout
			(tracks not_allowed)
			(vias allowed)
			(pads allowed)
			(copperpour not_allowed)
			(footprints allowed)
		)
		(placement
			(enabled no)
			(sheetname "")
		)
		(fill yes
			(thermal_gap 0.5)
			(thermal_bridge_width 0.5)
			(island_removal_mode 0)
		)
		(polygon
			(pts
				(arc
					(start 366.01527 -218.692222)
					(mid 365.36249 -218.692222)
					(end 366.01527 -218.692222)
				)
			)
		)
	)
	(zone
		(layers "B.Cu" "In6.Cu" "In11.Cu" "In13.Cu" "In15.Cu")
		(hatch none 0.5)
		(connect_pads
			(clearance 0)
		)
		(min_thickness 0.25)
		(keepout
			(tracks not_allowed)
			(vias allowed)
			(pads allowed)
			(copperpour not_allowed)
			(footprints allowed)
		)
		(placement
			(enabled no)
			(sheetname "")
		)
		(fill yes
			(thermal_gap 0.5)
			(thermal_bridge_width 0.5)
			(island_removal_mode 0)
		)
		(polygon
			(pts
				(arc
					(start 188.209936 -239.81664)
					(mid 187.557156 -239.81664)
					(end 188.209936 -239.81664)
				)
			)
		)
	)
	(zone
		(layers "B.Cu" "In6.Cu" "In11.Cu" "In13.Cu" "In15.Cu")
		(hatch none 0.5)
		(connect_pads
			(clearance 0)
		)
		(min_thickness 0.25)
		(keepout
			(tracks not_allowed)
			(vias allowed)
			(pads allowed)
			(copperpour not_allowed)
			(footprints allowed)
		)
		(placement
			(enabled no)
			(sheetname "")
		)
		(fill yes
			(thermal_gap 0.5)
			(thermal_bridge_width 0.5)
			(island_removal_mode 0)
		)
		(polygon
			(pts
				(arc
					(start 102.568756 -217.878406)
					(mid 101.915976 -217.878406)
					(end 102.568756 -217.878406)
				)
			)
		)
	)
	(zone
		(layers "B.Cu" "In6.Cu" "In11.Cu" "In13.Cu" "In15.Cu")
		(hatch none 0.5)
		(connect_pads
			(clearance 0)
		)
		(min_thickness 0.25)
		(keepout
			(tracks not_allowed)
			(vias allowed)
			(pads allowed)
			(copperpour not_allowed)
			(footprints allowed)
		)
		(placement
			(enabled no)
			(sheetname "")
		)
		(fill yes
			(thermal_gap 0.5)
			(thermal_bridge_width 0.5)
			(island_removal_mode 0)
		)
		(polygon
			(pts
				(arc
					(start 85.182456 -225.203258)
					(mid 84.529676 -225.203258)
					(end 85.182456 -225.203258)
				)
			)
		)
	)
	(zone
		(layers "B.Cu" "In6.Cu" "In11.Cu" "In13.Cu" "In15.Cu")
		(hatch none 0.5)
		(connect_pads
			(clearance 0)
		)
		(min_thickness 0.25)
		(keepout
			(tracks not_allowed)
			(vias allowed)
			(pads allowed)
			(copperpour not_allowed)
			(footprints allowed)
		)
		(placement
			(enabled no)
			(sheetname "")
		)
		(fill yes
			(thermal_gap 0.5)
			(thermal_bridge_width 0.5)
			(island_removal_mode 0)
		)
		(polygon
			(pts
				(arc
					(start 132.282184 -275.8948)
					(mid 131.629404 -275.8948)
					(end 132.282184 -275.8948)
				)
			)
		)
	)
	(zone
		(layers "B.Cu" "In6.Cu" "In11.Cu" "In13.Cu" "In15.Cu")
		(hatch none 0.5)
		(connect_pads
			(clearance 0)
		)
		(min_thickness 0.25)
		(keepout
			(tracks not_allowed)
			(vias allowed)
			(pads allowed)
			(copperpour not_allowed)
			(footprints allowed)
		)
		(placement
			(enabled no)
			(sheetname "")
		)
		(fill yes
			(thermal_gap 0.5)
			(thermal_bridge_width 0.5)
			(island_removal_mode 0)
		)
		(polygon
			(pts
				(arc
					(start 114.786156 -217.878406)
					(mid 114.133376 -217.878406)
					(end 114.786156 -217.878406)
				)
			)
		)
	)
	(zone
		(layers "B.Cu" "In6.Cu" "In11.Cu" "In13.Cu" "In15.Cu")
		(hatch none 0.5)
		(connect_pads
			(clearance 0)
		)
		(min_thickness 0.25)
		(keepout
			(tracks not_allowed)
			(vias allowed)
			(pads allowed)
			(copperpour not_allowed)
			(footprints allowed)
		)
		(placement
			(enabled no)
			(sheetname "")
		)
		(fill yes
			(thermal_gap 0.5)
			(thermal_bridge_width 0.5)
			(island_removal_mode 0)
		)
		(polygon
			(pts
				(arc
					(start 425.162472 -195.616576)
					(mid 424.509692 -195.616576)
					(end 425.162472 -195.616576)
				)
			)
		)
	)
	(zone
		(layers "B.Cu" "In6.Cu" "In11.Cu" "In13.Cu" "In15.Cu")
		(hatch none 0.5)
		(connect_pads
			(clearance 0)
		)
		(min_thickness 0.25)
		(keepout
			(tracks not_allowed)
			(vias allowed)
			(pads allowed)
			(copperpour not_allowed)
			(footprints allowed)
		)
		(placement
			(enabled no)
			(sheetname "")
		)
		(fill yes
			(thermal_gap 0.5)
			(thermal_bridge_width 0.5)
			(island_removal_mode 0)
		)
		(polygon
			(pts
				(arc
					(start 36.303204 -315.46673)
					(mid 35.650424 -315.46673)
					(end 36.303204 -315.46673)
				)
			)
		)
	)
	(zone
		(layers "B.Cu" "In6.Cu" "In11.Cu" "In13.Cu" "In15.Cu")
		(hatch none 0.5)
		(connect_pads
			(clearance 0)
		)
		(min_thickness 0.25)
		(keepout
			(tracks not_allowed)
			(vias allowed)
			(pads allowed)
			(copperpour not_allowed)
			(footprints allowed)
		)
		(placement
			(enabled no)
			(sheetname "")
		)
		(fill yes
			(thermal_gap 0.5)
			(thermal_bridge_width 0.5)
			(island_removal_mode 0)
		)
		(polygon
			(pts
				(arc
					(start 379.752606 -275.08073)
					(mid 379.099826 -275.08073)
					(end 379.752606 -275.08073)
				)
			)
		)
	)
	(zone
		(layers "B.Cu" "In6.Cu" "In11.Cu" "In13.Cu" "In15.Cu")
		(hatch none 0.5)
		(connect_pads
			(clearance 0)
		)
		(min_thickness 0.25)
		(keepout
			(tracks not_allowed)
			(vias allowed)
			(pads allowed)
			(copperpour not_allowed)
			(footprints allowed)
		)
		(placement
			(enabled no)
			(sheetname "")
		)
		(fill yes
			(thermal_gap 0.5)
			(thermal_bridge_width 0.5)
			(island_removal_mode 0)
		)
		(polygon
			(pts
				(arc
					(start 192.310004 -259.366766)
					(mid 191.657224 -259.366766)
					(end 192.310004 -259.366766)
				)
			)
		)
	)
	(zone
		(layers "B.Cu" "In6.Cu" "In11.Cu" "In13.Cu" "In15.Cu")
		(hatch none 0.5)
		(connect_pads
			(clearance 0)
		)
		(min_thickness 0.25)
		(keepout
			(tracks not_allowed)
			(vias allowed)
			(pads allowed)
			(copperpour not_allowed)
			(footprints allowed)
		)
		(placement
			(enabled no)
			(sheetname "")
		)
		(fill yes
			(thermal_gap 0.5)
			(thermal_bridge_width 0.5)
			(island_removal_mode 0)
		)
		(polygon
			(pts
				(arc
					(start 436.150004 -252.566678)
					(mid 435.497224 -252.566678)
					(end 436.150004 -252.566678)
				)
			)
		)
	)
	(zone
		(layers "B.Cu" "In6.Cu" "In11.Cu" "In13.Cu" "In15.Cu")
		(hatch none 0.5)
		(connect_pads
			(clearance 0)
		)
		(min_thickness 0.25)
		(keepout
			(tracks not_allowed)
			(vias allowed)
			(pads allowed)
			(copperpour not_allowed)
			(footprints allowed)
		)
		(placement
			(enabled no)
			(sheetname "")
		)
		(fill yes
			(thermal_gap 0.5)
			(thermal_bridge_width 0.5)
			(island_removal_mode 0)
		)
		(polygon
			(pts
				(arc
					(start 340.64067 -238.225584)
					(mid 339.98789 -238.225584)
					(end 340.64067 -238.225584)
				)
			)
		)
	)
	(zone
		(layers "B.Cu" "In6.Cu" "In11.Cu" "In13.Cu" "In15.Cu")
		(hatch none 0.5)
		(connect_pads
			(clearance 0)
		)
		(min_thickness 0.25)
		(keepout
			(tracks not_allowed)
			(vias allowed)
			(pads allowed)
			(copperpour not_allowed)
			(footprints allowed)
		)
		(placement
			(enabled no)
			(sheetname "")
		)
		(fill yes
			(thermal_gap 0.5)
			(thermal_bridge_width 0.5)
			(island_removal_mode 0)
		)
		(polygon
			(pts
				(arc
					(start 280.143204 -238.116618)
					(mid 279.490424 -238.116618)
					(end 280.143204 -238.116618)
				)
			)
		)
	)
	(zone
		(layers "B.Cu" "In6.Cu" "In11.Cu" "In13.Cu" "In15.Cu")
		(hatch none 0.5)
		(connect_pads
			(clearance 0)
		)
		(min_thickness 0.25)
		(keepout
			(tracks not_allowed)
			(vias allowed)
			(pads allowed)
			(copperpour not_allowed)
			(footprints allowed)
		)
		(placement
			(enabled no)
			(sheetname "")
		)
		(fill yes
			(thermal_gap 0.5)
			(thermal_bridge_width 0.5)
			(island_removal_mode 0)
		)
		(polygon
			(pts
				(arc
					(start 36.303204 -206.666592)
					(mid 35.650424 -206.666592)
					(end 36.303204 -206.666592)
				)
			)
		)
	)
	(zone
		(layers "B.Cu" "In6.Cu" "In11.Cu" "In13.Cu" "In15.Cu")
		(hatch none 0.5)
		(connect_pads
			(clearance 0)
		)
		(min_thickness 0.25)
		(keepout
			(tracks not_allowed)
			(vias allowed)
			(pads allowed)
			(copperpour not_allowed)
			(footprints allowed)
		)
		(placement
			(enabled no)
			(sheetname "")
		)
		(fill yes
			(thermal_gap 0.5)
			(thermal_bridge_width 0.5)
			(island_removal_mode 0)
		)
		(polygon
			(pts
				(arc
					(start 32.203136 -205.816708)
					(mid 31.550356 -205.816708)
					(end 32.203136 -205.816708)
				)
			)
		)
	)
	(zone
		(layers "B.Cu" "In6.Cu" "In11.Cu" "In13.Cu" "In15.Cu")
		(hatch none 0.5)
		(connect_pads
			(clearance 0)
		)
		(min_thickness 0.25)
		(keepout
			(tracks not_allowed)
			(vias allowed)
			(pads allowed)
			(copperpour not_allowed)
			(footprints allowed)
		)
		(placement
			(enabled no)
			(sheetname "")
		)
		(fill yes
			(thermal_gap 0.5)
			(thermal_bridge_width 0.5)
			(island_removal_mode 0)
		)
		(polygon
			(pts
				(arc
					(start 342.630252 -257.98907)
					(mid 341.977472 -257.98907)
					(end 342.630252 -257.98907)
				)
			)
		)
	)
	(zone
		(layers "B.Cu" "In6.Cu" "In11.Cu" "In13.Cu" "In15.Cu")
		(hatch none 0.5)
		(connect_pads
			(clearance 0)
		)
		(min_thickness 0.25)
		(keepout
			(tracks not_allowed)
			(vias allowed)
			(pads allowed)
			(copperpour not_allowed)
			(footprints allowed)
		)
		(placement
			(enabled no)
			(sheetname "")
		)
		(fill yes
			(thermal_gap 0.5)
			(thermal_bridge_width 0.5)
			(island_removal_mode 0)
		)
		(polygon
			(pts
				(arc
					(start 114.316256 -218.692222)
					(mid 113.663476 -218.692222)
					(end 114.316256 -218.692222)
				)
			)
		)
	)
	(zone
		(layers "B.Cu" "In6.Cu" "In11.Cu" "In13.Cu" "In15.Cu")
		(hatch none 0.5)
		(connect_pads
			(clearance 0)
		)
		(min_thickness 0.25)
		(keepout
			(tracks not_allowed)
			(vias allowed)
			(pads allowed)
			(copperpour not_allowed)
			(footprints allowed)
		)
		(placement
			(enabled no)
			(sheetname "")
		)
		(fill yes
			(thermal_gap 0.5)
			(thermal_bridge_width 0.5)
			(island_removal_mode 0)
		)
		(polygon
			(pts
				(arc
					(start 92.810584 -267.755878)
					(mid 92.157804 -267.755878)
					(end 92.810584 -267.755878)
				)
			)
		)
	)
	(zone
		(layers "B.Cu" "In6.Cu" "In11.Cu" "In13.Cu" "In15.Cu")
		(hatch none 0.5)
		(connect_pads
			(clearance 0)
		)
		(min_thickness 0.25)
		(keepout
			(tracks not_allowed)
			(vias allowed)
			(pads allowed)
			(copperpour not_allowed)
			(footprints allowed)
		)
		(placement
			(enabled no)
			(sheetname "")
		)
		(fill yes
			(thermal_gap 0.5)
			(thermal_bridge_width 0.5)
			(island_removal_mode 0)
		)
		(polygon
			(pts
				(arc
					(start 359.935526 -43.610784)
					(mid 359.231946 -43.610784)
					(end 359.935526 -43.610784)
				)
			)
		)
	)
	(zone
		(layers "B.Cu" "In6.Cu" "In11.Cu" "In13.Cu" "In15.Cu")
		(hatch none 0.5)
		(connect_pads
			(clearance 0)
		)
		(min_thickness 0.25)
		(keepout
			(tracks not_allowed)
			(vias allowed)
			(pads allowed)
			(copperpour not_allowed)
			(footprints allowed)
		)
		(placement
			(enabled no)
			(sheetname "")
		)
		(fill yes
			(thermal_gap 0.5)
			(thermal_bridge_width 0.5)
			(island_removal_mode 0)
		)
		(polygon
			(pts
				(arc
					(start 421.062404 -202.416664)
					(mid 420.409624 -202.416664)
					(end 421.062404 -202.416664)
				)
			)
		)
	)
	(zone
		(layers "B.Cu" "In6.Cu" "In11.Cu" "In13.Cu" "In15.Cu")
		(hatch none 0.5)
		(connect_pads
			(clearance 0)
		)
		(min_thickness 0.25)
		(keepout
			(tracks not_allowed)
			(vias allowed)
			(pads allowed)
			(copperpour not_allowed)
			(footprints allowed)
		)
		(placement
			(enabled no)
			(sheetname "")
		)
		(fill yes
			(thermal_gap 0.5)
			(thermal_bridge_width 0.5)
			(island_removal_mode 0)
		)
		(polygon
			(pts
				(arc
					(start 130.402584 -261.244842)
					(mid 129.749804 -261.244842)
					(end 130.402584 -261.244842)
				)
			)
		)
	)
	(zone
		(layers "B.Cu" "In6.Cu" "In11.Cu" "In13.Cu" "In15.Cu")
		(hatch none 0.5)
		(connect_pads
			(clearance 0)
		)
		(min_thickness 0.25)
		(keepout
			(tracks not_allowed)
			(vias allowed)
			(pads allowed)
			(copperpour not_allowed)
			(footprints allowed)
		)
		(placement
			(enabled no)
			(sheetname "")
		)
		(fill yes
			(thermal_gap 0.5)
			(thermal_bridge_width 0.5)
			(island_removal_mode 0)
		)
		(polygon
			(pts
				(arc
					(start 295.230804 -280.61666)
					(mid 294.578024 -280.61666)
					(end 295.230804 -280.61666)
				)
			)
		)
	)
	(zone
		(layers "B.Cu" "In6.Cu" "In11.Cu" "In13.Cu" "In15.Cu")
		(hatch none 0.5)
		(connect_pads
			(clearance 0)
		)
		(min_thickness 0.25)
		(keepout
			(tracks not_allowed)
			(vias allowed)
			(pads allowed)
			(copperpour not_allowed)
			(footprints allowed)
		)
		(placement
			(enabled no)
			(sheetname "")
		)
		(fill yes
			(thermal_gap 0.5)
			(thermal_bridge_width 0.5)
			(island_removal_mode 0)
		)
		(polygon
			(pts
				(arc
					(start 105.388156 -217.878406)
					(mid 104.735376 -217.878406)
					(end 105.388156 -217.878406)
				)
			)
		)
	)
	(zone
		(layers "B.Cu" "In6.Cu" "In11.Cu" "In13.Cu" "In15.Cu")
		(hatch none 0.5)
		(connect_pads
			(clearance 0)
		)
		(min_thickness 0.25)
		(keepout
			(tracks not_allowed)
			(vias allowed)
			(pads allowed)
			(copperpour not_allowed)
			(footprints allowed)
		)
		(placement
			(enabled no)
			(sheetname "")
		)
		(fill yes
			(thermal_gap 0.5)
			(thermal_bridge_width 0.5)
			(island_removal_mode 0)
		)
		(polygon
			(pts
				(arc
					(start 378.23267 -247.992138)
					(mid 377.57989 -247.992138)
					(end 378.23267 -247.992138)
				)
			)
		)
	)
	(zone
		(layers "B.Cu" "In6.Cu" "In11.Cu" "In13.Cu" "In15.Cu")
		(hatch none 0.5)
		(connect_pads
			(clearance 0)
		)
		(min_thickness 0.25)
		(keepout
			(tracks not_allowed)
			(vias allowed)
			(pads allowed)
			(copperpour not_allowed)
			(footprints allowed)
		)
		(placement
			(enabled no)
			(sheetname "")
		)
		(fill yes
			(thermal_gap 0.5)
			(thermal_bridge_width 0.5)
			(island_removal_mode 0)
		)
		(polygon
			(pts
				(arc
					(start 121.004838 -288.917126)
					(mid 120.352058 -288.917126)
					(end 121.004838 -288.917126)
				)
			)
		)
	)
	(zone
		(layers "B.Cu" "In6.Cu" "In11.Cu" "In13.Cu" "In15.Cu")
		(hatch none 0.5)
		(connect_pads
			(clearance 0)
		)
		(min_thickness 0.25)
		(keepout
			(tracks not_allowed)
			(vias allowed)
			(pads allowed)
			(copperpour not_allowed)
			(footprints allowed)
		)
		(placement
			(enabled no)
			(sheetname "")
		)
		(fill yes
			(thermal_gap 0.5)
			(thermal_bridge_width 0.5)
			(island_removal_mode 0)
		)
		(polygon
			(pts
				(arc
					(start 436.150004 -264.466578)
					(mid 435.497224 -264.466578)
					(end 436.150004 -264.466578)
				)
			)
		)
	)
	(zone
		(layers "B.Cu" "In6.Cu" "In11.Cu" "In13.Cu" "In15.Cu")
		(hatch none 0.5)
		(connect_pads
			(clearance 0)
		)
		(min_thickness 0.25)
		(keepout
			(tracks not_allowed)
			(vias allowed)
			(pads allowed)
			(copperpour not_allowed)
			(footprints allowed)
		)
		(placement
			(enabled no)
			(sheetname "")
		)
		(fill yes
			(thermal_gap 0.5)
			(thermal_bridge_width 0.5)
			(island_removal_mode 0)
		)
		(polygon
			(pts
				(arc
					(start 353.328224 -217.878406)
					(mid 352.675444 -217.878406)
					(end 353.328224 -217.878406)
				)
			)
		)
	)
	(zone
		(layers "B.Cu" "In6.Cu" "In11.Cu" "In13.Cu" "In15.Cu")
		(hatch none 0.5)
		(connect_pads
			(clearance 0)
		)
		(min_thickness 0.25)
		(keepout
			(tracks not_allowed)
			(vias allowed)
			(pads allowed)
			(copperpour not_allowed)
			(footprints allowed)
		)
		(placement
			(enabled no)
			(sheetname "")
		)
		(fill yes
			(thermal_gap 0.5)
			(thermal_bridge_width 0.5)
			(island_removal_mode 0)
		)
		(polygon
			(pts
				(arc
					(start 90.821002 -217.064336)
					(mid 90.168222 -217.064336)
					(end 90.821002 -217.064336)
				)
			)
		)
	)
	(zone
		(layers "B.Cu" "In6.Cu" "In11.Cu" "In13.Cu" "In15.Cu")
		(hatch none 0.5)
		(connect_pads
			(clearance 0)
		)
		(min_thickness 0.25)
		(keepout
			(tracks not_allowed)
			(vias allowed)
			(pads allowed)
			(copperpour not_allowed)
			(footprints allowed)
		)
		(placement
			(enabled no)
			(sheetname "")
		)
		(fill yes
			(thermal_gap 0.5)
			(thermal_bridge_width 0.5)
			(island_removal_mode 0)
		)
		(polygon
			(pts
				(arc
					(start 47.290736 -286.56661)
					(mid 46.637956 -286.56661)
					(end 47.290736 -286.56661)
				)
			)
		)
	)
	(zone
		(layers "B.Cu" "In6.Cu" "In11.Cu" "In13.Cu" "In15.Cu")
		(hatch none 0.5)
		(connect_pads
			(clearance 0)
		)
		(min_thickness 0.25)
		(keepout
			(tracks not_allowed)
			(vias allowed)
			(pads allowed)
			(copperpour not_allowed)
			(footprints allowed)
		)
		(placement
			(enabled no)
			(sheetname "")
		)
		(fill yes
			(thermal_gap 0.5)
			(thermal_bridge_width 0.5)
			(island_removal_mode 0)
		)
		(polygon
			(pts
				(arc
					(start 436.150004 -235.566712)
					(mid 435.497224 -235.566712)
					(end 436.150004 -235.566712)
				)
			)
		)
	)
	(zone
		(layers "B.Cu" "In6.Cu" "In11.Cu" "In13.Cu" "In15.Cu")
		(hatch none 0.5)
		(connect_pads
			(clearance 0)
		)
		(min_thickness 0.25)
		(keepout
			(tracks not_allowed)
			(vias allowed)
			(pads allowed)
			(copperpour not_allowed)
			(footprints allowed)
		)
		(placement
			(enabled no)
			(sheetname "")
		)
		(fill yes
			(thermal_gap 0.5)
			(thermal_bridge_width 0.5)
			(island_removal_mode 0)
		)
		(polygon
			(pts
				(arc
					(start 372.124224 -217.878406)
					(mid 371.471444 -217.878406)
					(end 372.124224 -217.878406)
				)
			)
		)
	)
	(zone
		(layers "B.Cu" "In6.Cu" "In11.Cu" "In13.Cu" "In15.Cu")
		(hatch none 0.5)
		(connect_pads
			(clearance 0)
		)
		(min_thickness 0.25)
		(keepout
			(tracks not_allowed)
			(vias allowed)
			(pads allowed)
			(copperpour not_allowed)
			(footprints allowed)
		)
		(placement
			(enabled no)
			(sheetname "")
		)
		(fill yes
			(thermal_gap 0.5)
			(thermal_bridge_width 0.5)
			(island_removal_mode 0)
		)
		(polygon
			(pts
				(arc
					(start 280.143204 -207.51673)
					(mid 279.490424 -207.51673)
					(end 280.143204 -207.51673)
				)
			)
		)
	)
	(zone
		(layers "B.Cu" "In6.Cu" "In11.Cu" "In13.Cu" "In15.Cu")
		(hatch none 0.5)
		(connect_pads
			(clearance 0)
		)
		(min_thickness 0.25)
		(keepout
			(tracks not_allowed)
			(vias allowed)
			(pads allowed)
			(copperpour not_allowed)
			(footprints allowed)
		)
		(placement
			(enabled no)
			(sheetname "")
		)
		(fill yes
			(thermal_gap 0.5)
			(thermal_bridge_width 0.5)
			(island_removal_mode 0)
		)
		(polygon
			(pts
				(arc
					(start 376.823224 -217.878406)
					(mid 376.170444 -217.878406)
					(end 376.823224 -217.878406)
				)
			)
		)
	)
	(zone
		(layers "B.Cu" "In6.Cu" "In11.Cu" "In13.Cu" "In15.Cu")
		(hatch none 0.5)
		(connect_pads
			(clearance 0)
		)
		(min_thickness 0.25)
		(keepout
			(tracks not_allowed)
			(vias allowed)
			(pads allowed)
			(copperpour not_allowed)
			(footprints allowed)
		)
		(placement
			(enabled no)
			(sheetname "")
		)
		(fill yes
			(thermal_gap 0.5)
			(thermal_bridge_width 0.5)
			(island_removal_mode 0)
		)
		(polygon
			(pts
				(arc
					(start 380.222252 -269.38351)
					(mid 379.569472 -269.38351)
					(end 380.222252 -269.38351)
				)
			)
		)
	)
	(zone
		(layers "B.Cu" "In6.Cu" "In11.Cu" "In13.Cu" "In15.Cu")
		(hatch none 0.5)
		(connect_pads
			(clearance 0)
		)
		(min_thickness 0.25)
		(keepout
			(tracks not_allowed)
			(vias allowed)
			(pads allowed)
			(copperpour not_allowed)
			(footprints allowed)
		)
		(placement
			(enabled no)
			(sheetname "")
		)
		(fill yes
			(thermal_gap 0.5)
			(thermal_bridge_width 0.5)
			(island_removal_mode 0)
		)
		(polygon
			(pts
				(arc
					(start 188.209936 -241.516662)
					(mid 187.557156 -241.516662)
					(end 188.209936 -241.516662)
				)
			)
		)
	)
	(zone
		(layers "B.Cu" "In6.Cu" "In11.Cu" "In13.Cu" "In15.Cu")
		(hatch none 0.5)
		(connect_pads
			(clearance 0)
		)
		(min_thickness 0.25)
		(keepout
			(tracks not_allowed)
			(vias allowed)
			(pads allowed)
			(copperpour not_allowed)
			(footprints allowed)
		)
		(placement
			(enabled no)
			(sheetname "")
		)
		(fill yes
			(thermal_gap 0.5)
			(thermal_bridge_width 0.5)
			(island_removal_mode 0)
		)
		(polygon
			(pts
				(arc
					(start 272.599404 -245.76659)
					(mid 271.946624 -245.76659)
					(end 272.599404 -245.76659)
				)
			)
		)
	)
	(zone
		(layers "B.Cu" "In6.Cu" "In11.Cu" "In13.Cu" "In15.Cu")
		(hatch none 0.5)
		(connect_pads
			(clearance 0)
		)
		(min_thickness 0.25)
		(keepout
			(tracks not_allowed)
			(vias allowed)
			(pads allowed)
			(copperpour not_allowed)
			(footprints allowed)
		)
		(placement
			(enabled no)
			(sheetname "")
		)
		(fill yes
			(thermal_gap 0.5)
			(thermal_bridge_width 0.5)
			(island_removal_mode 0)
		)
		(polygon
			(pts
				(arc
					(start 378.702824 -232.528364)
					(mid 378.050044 -232.528364)
					(end 378.702824 -232.528364)
				)
			)
		)
	)
	(zone
		(layers "B.Cu" "In6.Cu" "In11.Cu" "In13.Cu" "In15.Cu")
		(hatch none 0.5)
		(connect_pads
			(clearance 0)
		)
		(min_thickness 0.25)
		(keepout
			(tracks not_allowed)
			(vias allowed)
			(pads allowed)
			(copperpour not_allowed)
			(footprints allowed)
		)
		(placement
			(enabled no)
			(sheetname "")
		)
		(fill yes
			(thermal_gap 0.5)
			(thermal_bridge_width 0.5)
			(island_removal_mode 0)
		)
		(polygon
			(pts
				(arc
					(start 344.039952 -289.807142)
					(mid 343.387172 -289.807142)
					(end 344.039952 -289.807142)
				)
			)
		)
	)
	(zone
		(layers "B.Cu" "In6.Cu" "In11.Cu" "In13.Cu" "In15.Cu")
		(hatch none 0.5)
		(connect_pads
			(clearance 0)
		)
		(min_thickness 0.25)
		(keepout
			(tracks not_allowed)
			(vias allowed)
			(pads allowed)
			(copperpour not_allowed)
			(footprints allowed)
		)
		(placement
			(enabled no)
			(sheetname "")
		)
		(fill yes
			(thermal_gap 0.5)
			(thermal_bridge_width 0.5)
			(island_removal_mode 0)
		)
		(polygon
			(pts
				(arc
					(start 340.280752 -289.807142)
					(mid 339.627972 -289.807142)
					(end 340.280752 -289.807142)
				)
			)
		)
	)
	(zone
		(layers "B.Cu" "In6.Cu" "In11.Cu" "In13.Cu" "In15.Cu")
		(hatch none 0.5)
		(connect_pads
			(clearance 0)
		)
		(min_thickness 0.25)
		(keepout
			(tracks not_allowed)
			(vias allowed)
			(pads allowed)
			(copperpour not_allowed)
			(footprints allowed)
		)
		(placement
			(enabled no)
			(sheetname "")
		)
		(fill yes
			(thermal_gap 0.5)
			(thermal_bridge_width 0.5)
			(island_removal_mode 0)
		)
		(polygon
			(pts
				(arc
					(start 177.222404 -227.91674)
					(mid 176.569624 -227.91674)
					(end 177.222404 -227.91674)
				)
			)
		)
	)
	(zone
		(layers "B.Cu" "In6.Cu" "In11.Cu" "In13.Cu" "In15.Cu")
		(hatch none 0.5)
		(connect_pads
			(clearance 0)
		)
		(min_thickness 0.25)
		(keepout
			(tracks not_allowed)
			(vias allowed)
			(pads allowed)
			(copperpour not_allowed)
			(footprints allowed)
		)
		(placement
			(enabled no)
			(sheetname "")
		)
		(fill yes
			(thermal_gap 0.5)
			(thermal_bridge_width 0.5)
			(island_removal_mode 0)
		)
		(polygon
			(pts
				(arc
					(start 88.001856 -225.203258)
					(mid 87.349076 -225.203258)
					(end 88.001856 -225.203258)
				)
			)
		)
	)
	(zone
		(layers "B.Cu" "In6.Cu" "In11.Cu" "In13.Cu" "In15.Cu")
		(hatch none 0.5)
		(connect_pads
			(clearance 0)
		)
		(min_thickness 0.25)
		(keepout
			(tracks not_allowed)
			(vias allowed)
			(pads allowed)
			(copperpour not_allowed)
			(footprints allowed)
		)
		(placement
			(enabled no)
			(sheetname "")
		)
		(fill yes
			(thermal_gap 0.5)
			(thermal_bridge_width 0.5)
			(island_removal_mode 0)
		)
		(polygon
			(pts
				(arc
					(start 421.062404 -288.266632)
					(mid 420.409624 -288.266632)
					(end 421.062404 -288.266632)
				)
			)
		)
	)
	(zone
		(layers "B.Cu" "In6.Cu" "In11.Cu" "In13.Cu" "In15.Cu")
		(hatch none 0.5)
		(connect_pads
			(clearance 0)
		)
		(min_thickness 0.25)
		(keepout
			(tracks not_allowed)
			(vias allowed)
			(pads allowed)
			(copperpour not_allowed)
			(footprints allowed)
		)
		(placement
			(enabled no)
			(sheetname "")
		)
		(fill yes
			(thermal_gap 0.5)
			(thermal_bridge_width 0.5)
			(island_removal_mode 0)
		)
		(polygon
			(pts
				(arc
					(start 280.143204 -267.866622)
					(mid 279.490424 -267.866622)
					(end 280.143204 -267.866622)
				)
			)
		)
	)
	(zone
		(layers "B.Cu" "In6.Cu" "In11.Cu" "In13.Cu" "In15.Cu")
		(hatch none 0.5)
		(connect_pads
			(clearance 0)
		)
		(min_thickness 0.25)
		(keepout
			(tracks not_allowed)
			(vias allowed)
			(pads allowed)
			(copperpour not_allowed)
			(footprints allowed)
		)
		(placement
			(enabled no)
			(sheetname "")
		)
		(fill yes
			(thermal_gap 0.5)
			(thermal_bridge_width 0.5)
			(island_removal_mode 0)
		)
		(polygon
			(pts
				(arc
					(start 129.822956 -242.294918)
					(mid 129.170176 -242.294918)
					(end 129.822956 -242.294918)
				)
			)
		)
	)
	(zone
		(layers "B.Cu" "In6.Cu" "In11.Cu" "In13.Cu" "In15.Cu")
		(hatch none 0.5)
		(connect_pads
			(clearance 0)
		)
		(min_thickness 0.25)
		(keepout
			(tracks not_allowed)
			(vias allowed)
			(pads allowed)
			(copperpour not_allowed)
			(footprints allowed)
		)
		(placement
			(enabled no)
			(sheetname "")
		)
		(fill yes
			(thermal_gap 0.5)
			(thermal_bridge_width 0.5)
			(island_removal_mode 0)
		)
		(polygon
			(pts
				(arc
					(start 177.222404 -306.116736)
					(mid 176.569624 -306.116736)
					(end 177.222404 -306.116736)
				)
			)
		)
	)
	(zone
		(layers "B.Cu" "In6.Cu" "In11.Cu" "In13.Cu" "In15.Cu")
		(hatch none 0.5)
		(connect_pads
			(clearance 0)
		)
		(min_thickness 0.25)
		(keepout
			(tracks not_allowed)
			(vias allowed)
			(pads allowed)
			(copperpour not_allowed)
			(footprints allowed)
		)
		(placement
			(enabled no)
			(sheetname "")
		)
		(fill yes
			(thermal_gap 0.5)
			(thermal_bridge_width 0.5)
			(island_removal_mode 0)
		)
		(polygon
			(pts
				(arc
					(start 295.230804 -230.466646)
					(mid 294.578024 -230.466646)
					(end 295.230804 -230.466646)
				)
			)
		)
	)
	(zone
		(layers "B.Cu" "In6.Cu" "In11.Cu" "In13.Cu" "In15.Cu")
		(hatch none 0.5)
		(connect_pads
			(clearance 0)
		)
		(min_thickness 0.25)
		(keepout
			(tracks not_allowed)
			(vias allowed)
			(pads allowed)
			(copperpour not_allowed)
			(footprints allowed)
		)
		(placement
			(enabled no)
			(sheetname "")
		)
		(fill yes
			(thermal_gap 0.5)
			(thermal_bridge_width 0.5)
			(island_removal_mode 0)
		)
		(polygon
			(pts
				(arc
					(start 340.171024 -240.667286)
					(mid 339.518244 -240.667286)
					(end 340.171024 -240.667286)
				)
			)
		)
	)
	(zone
		(layers "B.Cu" "In6.Cu" "In11.Cu" "In13.Cu" "In15.Cu")
		(hatch none 0.5)
		(connect_pads
			(clearance 0)
		)
		(min_thickness 0.25)
		(keepout
			(tracks not_allowed)
			(vias allowed)
			(pads allowed)
			(copperpour not_allowed)
			(footprints allowed)
		)
		(placement
			(enabled no)
			(sheetname "")
		)
		(fill yes
			(thermal_gap 0.5)
			(thermal_bridge_width 0.5)
			(island_removal_mode 0)
		)
		(polygon
			(pts
				(arc
					(start 340.171024 -235.783882)
					(mid 339.518244 -235.783882)
					(end 340.171024 -235.783882)
				)
			)
		)
	)
	(zone
		(layers "B.Cu" "In6.Cu" "In11.Cu" "In13.Cu" "In15.Cu")
		(hatch none 0.5)
		(connect_pads
			(clearance 0)
		)
		(min_thickness 0.25)
		(keepout
			(tracks not_allowed)
			(vias allowed)
			(pads allowed)
			(copperpour not_allowed)
			(footprints allowed)
		)
		(placement
			(enabled no)
			(sheetname "")
		)
		(fill yes
			(thermal_gap 0.5)
			(thermal_bridge_width 0.5)
			(island_removal_mode 0)
		)
		(polygon
			(pts
				(arc
					(start 188.209936 -291.666676)
					(mid 187.557156 -291.666676)
					(end 188.209936 -291.666676)
				)
			)
		)
	)
	(zone
		(layers "B.Cu" "In6.Cu" "In11.Cu" "In13.Cu" "In15.Cu")
		(hatch none 0.5)
		(connect_pads
			(clearance 0)
		)
		(min_thickness 0.25)
		(keepout
			(tracks not_allowed)
			(vias allowed)
			(pads allowed)
			(copperpour not_allowed)
			(footprints allowed)
		)
		(placement
			(enabled no)
			(sheetname "")
		)
		(fill yes
			(thermal_gap 0.5)
			(thermal_bridge_width 0.5)
			(island_removal_mode 0)
		)
		(polygon
			(pts
				(arc
					(start 177.222404 -304.416714)
					(mid 176.569624 -304.416714)
					(end 177.222404 -304.416714)
				)
			)
		)
	)
	(zone
		(layers "B.Cu" "In6.Cu" "In11.Cu" "In13.Cu" "In15.Cu")
		(hatch none 0.5)
		(connect_pads
			(clearance 0)
		)
		(min_thickness 0.25)
		(keepout
			(tracks not_allowed)
			(vias allowed)
			(pads allowed)
			(copperpour not_allowed)
			(footprints allowed)
		)
		(placement
			(enabled no)
			(sheetname "")
		)
		(fill yes
			(thermal_gap 0.5)
			(thermal_bridge_width 0.5)
			(island_removal_mode 0)
		)
		(polygon
			(pts
				(arc
					(start 92.230956 -245.55069)
					(mid 91.578176 -245.55069)
					(end 92.230956 -245.55069)
				)
			)
		)
	)
	(zone
		(layers "B.Cu" "In6.Cu" "In11.Cu" "In13.Cu" "In15.Cu")
		(hatch none 0.5)
		(connect_pads
			(clearance 0)
		)
		(min_thickness 0.25)
		(keepout
			(tracks not_allowed)
			(vias allowed)
			(pads allowed)
			(copperpour not_allowed)
			(footprints allowed)
		)
		(placement
			(enabled no)
			(sheetname "")
		)
		(fill yes
			(thermal_gap 0.5)
			(thermal_bridge_width 0.5)
			(island_removal_mode 0)
		)
		(polygon
			(pts
				(arc
					(start 280.143204 -250.866656)
					(mid 279.490424 -250.866656)
					(end 280.143204 -250.866656)
				)
			)
		)
	)
	(zone
		(layers "B.Cu" "In6.Cu" "In11.Cu" "In13.Cu" "In15.Cu")
		(hatch none 0.5)
		(connect_pads
			(clearance 0)
		)
		(min_thickness 0.25)
		(keepout
			(tracks not_allowed)
			(vias allowed)
			(pads allowed)
			(copperpour not_allowed)
			(footprints allowed)
		)
		(placement
			(enabled no)
			(sheetname "")
		)
		(fill yes
			(thermal_gap 0.5)
			(thermal_bridge_width 0.5)
			(island_removal_mode 0)
		)
		(polygon
			(pts
				(arc
					(start 132.282184 -269.38351)
					(mid 131.629404 -269.38351)
					(end 132.282184 -269.38351)
				)
			)
		)
	)
	(zone
		(layers "B.Cu" "In6.Cu" "In11.Cu" "In13.Cu" "In15.Cu")
		(hatch none 0.5)
		(connect_pads
			(clearance 0)
		)
		(min_thickness 0.25)
		(keepout
			(tracks not_allowed)
			(vias allowed)
			(pads allowed)
			(copperpour not_allowed)
			(footprints allowed)
		)
		(placement
			(enabled no)
			(sheetname "")
		)
		(fill yes
			(thermal_gap 0.5)
			(thermal_bridge_width 0.5)
			(island_removal_mode 0)
		)
		(polygon
			(pts
				(arc
					(start 340.750652 -267.755878)
					(mid 340.097872 -267.755878)
					(end 340.750652 -267.755878)
				)
			)
		)
	)
	(zone
		(layers "B.Cu" "In6.Cu" "In11.Cu" "In13.Cu" "In15.Cu")
		(hatch none 0.5)
		(connect_pads
			(clearance 0)
		)
		(min_thickness 0.25)
		(keepout
			(tracks not_allowed)
			(vias allowed)
			(pads allowed)
			(copperpour not_allowed)
			(footprints allowed)
		)
		(placement
			(enabled no)
			(sheetname "")
		)
		(fill yes
			(thermal_gap 0.5)
			(thermal_bridge_width 0.5)
			(island_removal_mode 0)
		)
		(polygon
			(pts
				(arc
					(start 92.340684 -289.807142)
					(mid 91.687904 -289.807142)
					(end 92.340684 -289.807142)
				)
			)
		)
	)
	(zone
		(layers "B.Cu" "In6.Cu" "In11.Cu" "In13.Cu" "In15.Cu")
		(hatch none 0.5)
		(connect_pads
			(clearance 0)
		)
		(min_thickness 0.25)
		(keepout
			(tracks not_allowed)
			(vias allowed)
			(pads allowed)
			(copperpour not_allowed)
			(footprints allowed)
		)
		(placement
			(enabled no)
			(sheetname "")
		)
		(fill yes
			(thermal_gap 0.5)
			(thermal_bridge_width 0.5)
			(island_removal_mode 0)
		)
		(polygon
			(pts
				(arc
					(start 340.750652 -279.150318)
					(mid 340.097872 -279.150318)
					(end 340.750652 -279.150318)
				)
			)
		)
	)
	(zone
		(layers "B.Cu" "In6.Cu" "In11.Cu" "In13.Cu" "In15.Cu")
		(hatch none 0.5)
		(connect_pads
			(clearance 0)
		)
		(min_thickness 0.25)
		(keepout
			(tracks not_allowed)
			(vias allowed)
			(pads allowed)
			(copperpour not_allowed)
			(footprints allowed)
		)
		(placement
			(enabled no)
			(sheetname "")
		)
		(fill yes
			(thermal_gap 0.5)
			(thermal_bridge_width 0.5)
			(island_removal_mode 0)
		)
		(polygon
			(pts
				(arc
					(start 342.630506 -288.917126)
					(mid 341.977726 -288.917126)
					(end 342.630506 -288.917126)
				)
			)
		)
	)
	(zone
		(layers "B.Cu" "In6.Cu" "In11.Cu" "In13.Cu" "In15.Cu")
		(hatch none 0.5)
		(connect_pads
			(clearance 0)
		)
		(min_thickness 0.25)
		(keepout
			(tracks not_allowed)
			(vias allowed)
			(pads allowed)
			(copperpour not_allowed)
			(footprints allowed)
		)
		(placement
			(enabled no)
			(sheetname "")
		)
		(fill yes
			(thermal_gap 0.5)
			(thermal_bridge_width 0.5)
			(island_removal_mode 0)
		)
		(polygon
			(pts
				(arc
					(start 195.753736 -245.76659)
					(mid 195.100956 -245.76659)
					(end 195.753736 -245.76659)
				)
			)
		)
	)
	(zone
		(layers "B.Cu" "In6.Cu" "In11.Cu" "In13.Cu" "In15.Cu")
		(hatch none 0.5)
		(connect_pads
			(clearance 0)
		)
		(min_thickness 0.25)
		(keepout
			(tracks not_allowed)
			(vias allowed)
			(pads allowed)
			(copperpour not_allowed)
			(footprints allowed)
		)
		(placement
			(enabled no)
			(sheetname "")
		)
		(fill yes
			(thermal_gap 0.5)
			(thermal_bridge_width 0.5)
			(island_removal_mode 0)
		)
		(polygon
			(pts
				(arc
					(start 276.699472 -260.21665)
					(mid 276.046692 -260.21665)
					(end 276.699472 -260.21665)
				)
			)
		)
	)
	(zone
		(layers "B.Cu" "In6.Cu" "In11.Cu" "In13.Cu" "In15.Cu")
		(hatch none 0.5)
		(connect_pads
			(clearance 0)
		)
		(min_thickness 0.25)
		(keepout
			(tracks not_allowed)
			(vias allowed)
			(pads allowed)
			(copperpour not_allowed)
			(footprints allowed)
		)
		(placement
			(enabled no)
			(sheetname "")
		)
		(fill yes
			(thermal_gap 0.5)
			(thermal_bridge_width 0.5)
			(island_removal_mode 0)
		)
		(polygon
			(pts
				(arc
					(start 32.203136 -259.366766)
					(mid 31.550356 -259.366766)
					(end 32.203136 -259.366766)
				)
			)
		)
	)
	(zone
		(layers "B.Cu" "In6.Cu" "In11.Cu" "In13.Cu" "In15.Cu")
		(hatch none 0.5)
		(connect_pads
			(clearance 0)
		)
		(min_thickness 0.25)
		(keepout
			(tracks not_allowed)
			(vias allowed)
			(pads allowed)
			(copperpour not_allowed)
			(footprints allowed)
		)
		(placement
			(enabled no)
			(sheetname "")
		)
		(fill yes
			(thermal_gap 0.5)
			(thermal_bridge_width 0.5)
			(island_removal_mode 0)
		)
		(polygon
			(pts
				(arc
					(start 299.330872 -203.266802)
					(mid 298.678092 -203.266802)
					(end 299.330872 -203.266802)
				)
			)
		)
	)
	(zone
		(layers "B.Cu" "In6.Cu" "In11.Cu" "In13.Cu" "In15.Cu")
		(hatch none 0.5)
		(connect_pads
			(clearance 0)
		)
		(min_thickness 0.25)
		(keepout
			(tracks not_allowed)
			(vias allowed)
			(pads allowed)
			(copperpour not_allowed)
			(footprints allowed)
		)
		(placement
			(enabled no)
			(sheetname "")
		)
		(fill yes
			(thermal_gap 0.5)
			(thermal_bridge_width 0.5)
			(island_removal_mode 0)
		)
		(polygon
			(pts
				(arc
					(start 280.143204 -262.76681)
					(mid 279.490424 -262.76681)
					(end 280.143204 -262.76681)
				)
			)
		)
	)
	(zone
		(layers "B.Cu" "In6.Cu" "In11.Cu" "In13.Cu" "In15.Cu")
		(hatch none 0.5)
		(connect_pads
			(clearance 0)
		)
		(min_thickness 0.25)
		(keepout
			(tracks not_allowed)
			(vias allowed)
			(pads allowed)
			(copperpour not_allowed)
			(footprints allowed)
		)
		(placement
			(enabled no)
			(sheetname "")
		)
		(fill yes
			(thermal_gap 0.5)
			(thermal_bridge_width 0.5)
			(island_removal_mode 0)
		)
		(polygon
			(pts
				(arc
					(start 112.436402 -218.692222)
					(mid 111.783622 -218.692222)
					(end 112.436402 -218.692222)
				)
			)
		)
	)
	(zone
		(layers "B.Cu" "In6.Cu" "In11.Cu" "In13.Cu" "In15.Cu")
		(hatch none 0.5)
		(connect_pads
			(clearance 0)
		)
		(min_thickness 0.25)
		(keepout
			(tracks not_allowed)
			(vias allowed)
			(pads allowed)
			(copperpour not_allowed)
			(footprints allowed)
		)
		(placement
			(enabled no)
			(sheetname "")
		)
		(fill yes
			(thermal_gap 0.5)
			(thermal_bridge_width 0.5)
			(island_removal_mode 0)
		)
		(polygon
			(pts
				(arc
					(start 380.11227 -233.34218)
					(mid 379.45949 -233.34218)
					(end 380.11227 -233.34218)
				)
			)
		)
	)
	(zone
		(layers "B.Cu" "In6.Cu" "In11.Cu" "In13.Cu" "In15.Cu")
		(hatch none 0.5)
		(connect_pads
			(clearance 0)
		)
		(min_thickness 0.25)
		(keepout
			(tracks not_allowed)
			(vias allowed)
			(pads allowed)
			(copperpour not_allowed)
			(footprints allowed)
		)
		(placement
			(enabled no)
			(sheetname "")
		)
		(fill yes
			(thermal_gap 0.5)
			(thermal_bridge_width 0.5)
			(island_removal_mode 0)
		)
		(polygon
			(pts
				(arc
					(start 89.411556 -217.878406)
					(mid 88.758776 -217.878406)
					(end 89.411556 -217.878406)
				)
			)
		)
	)
	(zone
		(layers "B.Cu" "In6.Cu" "In11.Cu" "In13.Cu" "In15.Cu")
		(hatch none 0.5)
		(connect_pads
			(clearance 0)
		)
		(min_thickness 0.25)
		(keepout
			(tracks not_allowed)
			(vias allowed)
			(pads allowed)
			(copperpour not_allowed)
			(footprints allowed)
		)
		(placement
			(enabled no)
			(sheetname "")
		)
		(fill yes
			(thermal_gap 0.5)
			(thermal_bridge_width 0.5)
			(island_removal_mode 0)
		)
		(polygon
			(pts
				(arc
					(start 378.702824 -240.667286)
					(mid 378.050044 -240.667286)
					(end 378.702824 -240.667286)
				)
			)
		)
	)
	(zone
		(layers "B.Cu" "In6.Cu" "In11.Cu" "In13.Cu" "In15.Cu")
		(hatch none 0.5)
		(connect_pads
			(clearance 0)
		)
		(min_thickness 0.25)
		(keepout
			(tracks not_allowed)
			(vias allowed)
			(pads allowed)
			(copperpour not_allowed)
			(footprints allowed)
		)
		(placement
			(enabled no)
			(sheetname "")
		)
		(fill yes
			(thermal_gap 0.5)
			(thermal_bridge_width 0.5)
			(island_removal_mode 0)
		)
		(polygon
			(pts
				(arc
					(start 338.291424 -217.878406)
					(mid 337.638644 -217.878406)
					(end 338.291424 -217.878406)
				)
			)
		)
	)
	(zone
		(layers "B.Cu" "In6.Cu" "In11.Cu" "In13.Cu" "In15.Cu")
		(hatch none 0.5)
		(connect_pads
			(clearance 0)
		)
		(min_thickness 0.25)
		(keepout
			(tracks not_allowed)
			(vias allowed)
			(pads allowed)
			(copperpour not_allowed)
			(footprints allowed)
		)
		(placement
			(enabled no)
			(sheetname "")
		)
		(fill yes
			(thermal_gap 0.5)
			(thermal_bridge_width 0.5)
			(island_removal_mode 0)
		)
		(polygon
			(pts
				(arc
					(start 92.230956 -217.878406)
					(mid 91.578176 -217.878406)
					(end 92.230956 -217.878406)
				)
			)
		)
	)
	(zone
		(layers "B.Cu" "In6.Cu" "In11.Cu" "In13.Cu" "In15.Cu")
		(hatch none 0.5)
		(connect_pads
			(clearance 0)
		)
		(min_thickness 0.25)
		(keepout
			(tracks not_allowed)
			(vias allowed)
			(pads allowed)
			(copperpour not_allowed)
			(footprints allowed)
		)
		(placement
			(enabled no)
			(sheetname "")
		)
		(fill yes
			(thermal_gap 0.5)
			(thermal_bridge_width 0.5)
			(island_removal_mode 0)
		)
		(polygon
			(pts
				(arc
					(start 86.122256 -226.831144)
					(mid 85.469476 -226.831144)
					(end 86.122256 -226.831144)
				)
			)
		)
	)
	(zone
		(layers "B.Cu" "In6.Cu" "In11.Cu" "In13.Cu" "In15.Cu")
		(hatch none 0.5)
		(connect_pads
			(clearance 0)
		)
		(min_thickness 0.25)
		(keepout
			(tracks not_allowed)
			(vias allowed)
			(pads allowed)
			(copperpour not_allowed)
			(footprints allowed)
		)
		(placement
			(enabled no)
			(sheetname "")
		)
		(fill yes
			(thermal_gap 0.5)
			(thermal_bridge_width 0.5)
			(island_removal_mode 0)
		)
		(polygon
			(pts
				(arc
					(start 436.150004 -266.1666)
					(mid 435.497224 -266.1666)
					(end 436.150004 -266.1666)
				)
			)
		)
	)
	(zone
		(layers "B.Cu" "In6.Cu" "In11.Cu" "In13.Cu" "In15.Cu")
		(hatch none 0.5)
		(connect_pads
			(clearance 0)
		)
		(min_thickness 0.25)
		(keepout
			(tracks not_allowed)
			(vias allowed)
			(pads allowed)
			(copperpour not_allowed)
			(footprints allowed)
		)
		(placement
			(enabled no)
			(sheetname "")
		)
		(fill yes
			(thermal_gap 0.5)
			(thermal_bridge_width 0.5)
			(island_removal_mode 0)
		)
		(polygon
			(pts
				(arc
					(start 334.062324 -223.575626)
					(mid 333.409544 -223.575626)
					(end 334.062324 -223.575626)
				)
			)
		)
	)
	(zone
		(layers "B.Cu" "In6.Cu" "In11.Cu" "In13.Cu" "In15.Cu")
		(hatch none 0.5)
		(connect_pads
			(clearance 0)
		)
		(min_thickness 0.25)
		(keepout
			(tracks not_allowed)
			(vias allowed)
			(pads allowed)
			(copperpour not_allowed)
			(footprints allowed)
		)
		(placement
			(enabled no)
			(sheetname "")
		)
		(fill yes
			(thermal_gap 0.5)
			(thermal_bridge_width 0.5)
			(island_removal_mode 0)
		)
		(polygon
			(pts
				(arc
					(start 364.605824 -217.878406)
					(mid 363.953044 -217.878406)
					(end 364.605824 -217.878406)
				)
			)
		)
	)
	(zone
		(layers "B.Cu" "In6.Cu" "In11.Cu" "In13.Cu" "In15.Cu")
		(hatch none 0.5)
		(connect_pads
			(clearance 0)
		)
		(min_thickness 0.25)
		(keepout
			(tracks not_allowed)
			(vias allowed)
			(pads allowed)
			(copperpour not_allowed)
			(footprints allowed)
		)
		(placement
			(enabled no)
			(sheetname "")
		)
		(fill yes
			(thermal_gap 0.5)
			(thermal_bridge_width 0.5)
			(island_removal_mode 0)
		)
		(polygon
			(pts
				(arc
					(start 341.690452 -275.8948)
					(mid 341.037672 -275.8948)
					(end 341.690452 -275.8948)
				)
			)
		)
	)
	(zone
		(layers "B.Cu" "In6.Cu" "In11.Cu" "In13.Cu" "In15.Cu")
		(hatch none 0.5)
		(connect_pads
			(clearance 0)
		)
		(min_thickness 0.25)
		(keepout
			(tracks not_allowed)
			(vias allowed)
			(pads allowed)
			(copperpour not_allowed)
			(footprints allowed)
		)
		(placement
			(enabled no)
			(sheetname "")
		)
		(fill yes
			(thermal_gap 0.5)
			(thermal_bridge_width 0.5)
			(island_removal_mode 0)
		)
		(polygon
			(pts
				(arc
					(start 129.462784 -257.98907)
					(mid 128.810004 -257.98907)
					(end 129.462784 -257.98907)
				)
			)
		)
	)
	(zone
		(layers "B.Cu" "In6.Cu" "In11.Cu" "In13.Cu" "In15.Cu")
		(hatch none 0.5)
		(connect_pads
			(clearance 0)
		)
		(min_thickness 0.25)
		(keepout
			(tracks not_allowed)
			(vias allowed)
			(pads allowed)
			(copperpour not_allowed)
			(footprints allowed)
		)
		(placement
			(enabled no)
			(sheetname "")
		)
		(fill yes
			(thermal_gap 0.5)
			(thermal_bridge_width 0.5)
			(island_removal_mode 0)
		)
		(polygon
			(pts
				(arc
					(start 92.700602 -243.108988)
					(mid 92.047822 -243.108988)
					(end 92.700602 -243.108988)
				)
			)
		)
	)
	(zone
		(layers "B.Cu" "In6.Cu" "In11.Cu" "In13.Cu" "In15.Cu")
		(hatch none 0.5)
		(connect_pads
			(clearance 0)
		)
		(min_thickness 0.25)
		(keepout
			(tracks not_allowed)
			(vias allowed)
			(pads allowed)
			(copperpour not_allowed)
			(footprints allowed)
		)
		(placement
			(enabled no)
			(sheetname "")
		)
		(fill yes
			(thermal_gap 0.5)
			(thermal_bridge_width 0.5)
			(island_removal_mode 0)
		)
		(polygon
			(pts
				(arc
					(start 380.222252 -275.8948)
					(mid 379.569472 -275.8948)
					(end 380.222252 -275.8948)
				)
			)
		)
	)
	(zone
		(layers "B.Cu" "In6.Cu" "In11.Cu" "In13.Cu" "In15.Cu")
		(hatch none 0.5)
		(connect_pads
			(clearance 0)
		)
		(min_thickness 0.25)
		(keepout
			(tracks not_allowed)
			(vias allowed)
			(pads allowed)
			(copperpour not_allowed)
			(footprints allowed)
		)
		(placement
			(enabled no)
			(sheetname "")
		)
		(fill yes
			(thermal_gap 0.5)
			(thermal_bridge_width 0.5)
			(island_removal_mode 0)
		)
		(polygon
			(pts
				(arc
					(start 123.824238 -288.917126)
					(mid 123.171458 -288.917126)
					(end 123.824238 -288.917126)
				)
			)
		)
	)
	(zone
		(layers "B.Cu" "In6.Cu" "In11.Cu" "In13.Cu" "In15.Cu")
		(hatch none 0.5)
		(connect_pads
			(clearance 0)
		)
		(min_thickness 0.25)
		(keepout
			(tracks not_allowed)
			(vias allowed)
			(pads allowed)
			(copperpour not_allowed)
			(footprints allowed)
		)
		(placement
			(enabled no)
			(sheetname "")
		)
		(fill yes
			(thermal_gap 0.5)
			(thermal_bridge_width 0.5)
			(island_removal_mode 0)
		)
		(polygon
			(pts
				(arc
					(start 173.122336 -228.766624)
					(mid 172.469556 -228.766624)
					(end 173.122336 -228.766624)
				)
			)
		)
	)
	(zone
		(layers "B.Cu" "In6.Cu" "In11.Cu" "In13.Cu" "In15.Cu")
		(hatch none 0.5)
		(connect_pads
			(clearance 0)
		)
		(min_thickness 0.25)
		(keepout
			(tracks not_allowed)
			(vias allowed)
			(pads allowed)
			(copperpour not_allowed)
			(footprints allowed)
		)
		(placement
			(enabled no)
			(sheetname "")
		)
		(fill yes
			(thermal_gap 0.5)
			(thermal_bridge_width 0.5)
			(island_removal_mode 0)
		)
		(polygon
			(pts
				(arc
					(start 341.58047 -228.45903)
					(mid 340.92769 -228.45903)
					(end 341.58047 -228.45903)
				)
			)
		)
	)
	(zone
		(layers "B.Cu" "In6.Cu" "In11.Cu" "In13.Cu" "In15.Cu")
		(hatch none 0.5)
		(connect_pads
			(clearance 0)
		)
		(min_thickness 0.25)
		(keepout
			(tracks not_allowed)
			(vias allowed)
			(pads allowed)
			(copperpour not_allowed)
			(footprints allowed)
		)
		(placement
			(enabled no)
			(sheetname "")
		)
		(fill yes
			(thermal_gap 0.5)
			(thermal_bridge_width 0.5)
			(island_removal_mode 0)
		)
		(polygon
			(pts
				(arc
					(start 340.64067 -236.597952)
					(mid 339.98789 -236.597952)
					(end 340.64067 -236.597952)
				)
			)
		)
	)
	(zone
		(layers "B.Cu" "In6.Cu" "In11.Cu" "In13.Cu" "In15.Cu")
		(hatch none 0.5)
		(connect_pads
			(clearance 0)
		)
		(min_thickness 0.25)
		(keepout
			(tracks not_allowed)
			(vias allowed)
			(pads allowed)
			(copperpour not_allowed)
			(footprints allowed)
		)
		(placement
			(enabled no)
			(sheetname "")
		)
		(fill yes
			(thermal_gap 0.5)
			(thermal_bridge_width 0.5)
			(island_removal_mode 0)
		)
		(polygon
			(pts
				(arc
					(start 340.750652 -264.50036)
					(mid 340.097872 -264.50036)
					(end 340.750652 -264.50036)
				)
			)
		)
	)
	(zone
		(layers "B.Cu" "In6.Cu" "In11.Cu" "In13.Cu" "In15.Cu")
		(hatch none 0.5)
		(connect_pads
			(clearance 0)
		)
		(min_thickness 0.25)
		(keepout
			(tracks not_allowed)
			(vias allowed)
			(pads allowed)
			(copperpour not_allowed)
			(footprints allowed)
		)
		(placement
			(enabled no)
			(sheetname "")
		)
		(fill yes
			(thermal_gap 0.5)
			(thermal_bridge_width 0.5)
			(island_removal_mode 0)
		)
		(polygon
			(pts
				(arc
					(start 47.290736 -232.166668)
					(mid 46.637956 -232.166668)
					(end 47.290736 -232.166668)
				)
			)
		)
	)
	(zone
		(layers "B.Cu" "In6.Cu" "In11.Cu" "In13.Cu" "In15.Cu")
		(hatch none 0.5)
		(connect_pads
			(clearance 0)
		)
		(min_thickness 0.25)
		(keepout
			(tracks not_allowed)
			(vias allowed)
			(pads allowed)
			(copperpour not_allowed)
			(footprints allowed)
		)
		(placement
			(enabled no)
			(sheetname "")
		)
		(fill yes
			(thermal_gap 0.5)
			(thermal_bridge_width 0.5)
			(island_removal_mode 0)
		)
		(polygon
			(pts
				(arc
					(start 192.310004 -251.716794)
					(mid 191.657224 -251.716794)
					(end 192.310004 -251.716794)
				)
			)
		)
	)
	(zone
		(layers "B.Cu" "In6.Cu" "In11.Cu" "In13.Cu" "In15.Cu")
		(hatch none 0.5)
		(connect_pads
			(clearance 0)
		)
		(min_thickness 0.25)
		(keepout
			(tracks not_allowed)
			(vias allowed)
			(pads allowed)
			(copperpour not_allowed)
			(footprints allowed)
		)
		(placement
			(enabled no)
			(sheetname "")
		)
		(fill yes
			(thermal_gap 0.5)
			(thermal_bridge_width 0.5)
			(island_removal_mode 0)
		)
		(polygon
			(pts
				(arc
					(start 340.750652 -271.011396)
					(mid 340.097872 -271.011396)
					(end 340.750652 -271.011396)
				)
			)
		)
	)
	(zone
		(layers "B.Cu" "In6.Cu" "In11.Cu" "In13.Cu" "In15.Cu")
		(hatch none 0.5)
		(connect_pads
			(clearance 0)
		)
		(min_thickness 0.25)
		(keepout
			(tracks not_allowed)
			(vias allowed)
			(pads allowed)
			(copperpour not_allowed)
			(footprints allowed)
		)
		(placement
			(enabled no)
			(sheetname "")
		)
		(fill yes
			(thermal_gap 0.5)
			(thermal_bridge_width 0.5)
			(island_removal_mode 0)
		)
		(polygon
			(pts
				(arc
					(start 173.122336 -224.516696)
					(mid 172.469556 -224.516696)
					(end 173.122336 -224.516696)
				)
			)
		)
	)
	(zone
		(layers "B.Cu" "In6.Cu" "In11.Cu" "In13.Cu" "In15.Cu")
		(hatch none 0.5)
		(connect_pads
			(clearance 0)
		)
		(min_thickness 0.25)
		(keepout
			(tracks not_allowed)
			(vias allowed)
			(pads allowed)
			(copperpour not_allowed)
			(footprints allowed)
		)
		(placement
			(enabled no)
			(sheetname "")
		)
		(fill yes
			(thermal_gap 0.5)
			(thermal_bridge_width 0.5)
			(island_removal_mode 0)
		)
		(polygon
			(pts
				(arc
					(start 51.390804 -225.36658)
					(mid 50.738024 -225.36658)
					(end 51.390804 -225.36658)
				)
			)
		)
	)
	(zone
		(layers "B.Cu" "In6.Cu" "In11.Cu" "In13.Cu" "In15.Cu")
		(hatch none 0.5)
		(connect_pads
			(clearance 0)
		)
		(min_thickness 0.25)
		(keepout
			(tracks not_allowed)
			(vias allowed)
			(pads allowed)
			(copperpour not_allowed)
			(footprints allowed)
		)
		(placement
			(enabled no)
			(sheetname "")
		)
		(fill yes
			(thermal_gap 0.5)
			(thermal_bridge_width 0.5)
			(island_removal_mode 0)
		)
		(polygon
			(pts
				(arc
					(start 379.642624 -227.64496)
					(mid 378.989844 -227.64496)
					(end 379.642624 -227.64496)
				)
			)
		)
	)
	(zone
		(layers "B.Cu" "In6.Cu" "In11.Cu" "In13.Cu" "In15.Cu")
		(hatch none 0.5)
		(connect_pads
			(clearance 0)
		)
		(min_thickness 0.25)
		(keepout
			(tracks not_allowed)
			(vias allowed)
			(pads allowed)
			(copperpour not_allowed)
			(footprints allowed)
		)
		(placement
			(enabled no)
			(sheetname "")
		)
		(fill yes
			(thermal_gap 0.5)
			(thermal_bridge_width 0.5)
			(island_removal_mode 0)
		)
		(polygon
			(pts
				(arc
					(start 295.230804 -202.416664)
					(mid 294.578024 -202.416664)
					(end 295.230804 -202.416664)
				)
			)
		)
	)
	(zone
		(layers "B.Cu" "In6.Cu" "In11.Cu" "In13.Cu" "In15.Cu")
		(hatch none 0.5)
		(connect_pads
			(clearance 0)
		)
		(min_thickness 0.25)
		(keepout
			(tracks not_allowed)
			(vias allowed)
			(pads allowed)
			(copperpour not_allowed)
			(footprints allowed)
		)
		(placement
			(enabled no)
			(sheetname "")
		)
		(fill yes
			(thermal_gap 0.5)
			(thermal_bridge_width 0.5)
			(island_removal_mode 0)
		)
		(polygon
			(pts
				(arc
					(start 94.110556 -230.900478)
					(mid 93.457776 -230.900478)
					(end 94.110556 -230.900478)
				)
			)
		)
	)
	(zone
		(layers "B.Cu" "In6.Cu" "In11.Cu" "In13.Cu" "In15.Cu")
		(hatch none 0.5)
		(connect_pads
			(clearance 0)
		)
		(min_thickness 0.25)
		(keepout
			(tracks not_allowed)
			(vias allowed)
			(pads allowed)
			(copperpour not_allowed)
			(footprints allowed)
		)
		(placement
			(enabled no)
			(sheetname "")
		)
		(fill yes
			(thermal_gap 0.5)
			(thermal_bridge_width 0.5)
			(island_removal_mode 0)
		)
		(polygon
			(pts
				(arc
					(start 335.472024 -224.389442)
					(mid 334.819244 -224.389442)
					(end 335.472024 -224.389442)
				)
			)
		)
	)
	(zone
		(layers "B.Cu" "In6.Cu" "In11.Cu" "In13.Cu" "In15.Cu")
		(hatch none 0.5)
		(connect_pads
			(clearance 0)
		)
		(min_thickness 0.25)
		(keepout
			(tracks not_allowed)
			(vias allowed)
			(pads allowed)
			(copperpour not_allowed)
			(footprints allowed)
		)
		(placement
			(enabled no)
			(sheetname "")
		)
		(fill yes
			(thermal_gap 0.5)
			(thermal_bridge_width 0.5)
			(island_removal_mode 0)
		)
		(polygon
			(pts
				(arc
					(start 343.100406 -255.547622)
					(mid 342.447626 -255.547622)
					(end 343.100406 -255.547622)
				)
			)
		)
	)
	(zone
		(layers "B.Cu" "In6.Cu" "In11.Cu" "In13.Cu" "In15.Cu")
		(hatch none 0.5)
		(connect_pads
			(clearance 0)
		)
		(min_thickness 0.25)
		(keepout
			(tracks not_allowed)
			(vias allowed)
			(pads allowed)
			(copperpour not_allowed)
			(footprints allowed)
		)
		(placement
			(enabled no)
			(sheetname "")
		)
		(fill yes
			(thermal_gap 0.5)
			(thermal_bridge_width 0.5)
			(island_removal_mode 0)
		)
		(polygon
			(pts
				(arc
					(start 378.342652 -271.011396)
					(mid 377.689872 -271.011396)
					(end 378.342652 -271.011396)
				)
			)
		)
	)
	(zone
		(layers "B.Cu" "In6.Cu" "In11.Cu" "In13.Cu" "In15.Cu")
		(hatch none 0.5)
		(connect_pads
			(clearance 0)
		)
		(min_thickness 0.25)
		(keepout
			(tracks not_allowed)
			(vias allowed)
			(pads allowed)
			(copperpour not_allowed)
			(footprints allowed)
		)
		(placement
			(enabled no)
			(sheetname "")
		)
		(fill yes
			(thermal_gap 0.5)
			(thermal_bridge_width 0.5)
			(island_removal_mode 0)
		)
		(polygon
			(pts
				(arc
					(start 337.82127 -218.692222)
					(mid 337.16849 -218.692222)
					(end 337.82127 -218.692222)
				)
			)
		)
	)
	(zone
		(layers "B.Cu" "In6.Cu" "In11.Cu" "In13.Cu" "In15.Cu")
		(hatch none 0.5)
		(connect_pads
			(clearance 0)
		)
		(min_thickness 0.25)
		(keepout
			(tracks not_allowed)
			(vias allowed)
			(pads allowed)
			(copperpour not_allowed)
			(footprints allowed)
		)
		(placement
			(enabled no)
			(sheetname "")
		)
		(fill yes
			(thermal_gap 0.5)
			(thermal_bridge_width 0.5)
			(island_removal_mode 0)
		)
		(polygon
			(pts
				(arc
					(start 133.222238 -288.917126)
					(mid 132.569458 -288.917126)
					(end 133.222238 -288.917126)
				)
			)
		)
	)
	(zone
		(layers "B.Cu" "In6.Cu" "In11.Cu" "In13.Cu" "In15.Cu")
		(hatch none 0.5)
		(connect_pads
			(clearance 0)
		)
		(min_thickness 0.25)
		(keepout
			(tracks not_allowed)
			(vias allowed)
			(pads allowed)
			(copperpour not_allowed)
			(footprints allowed)
		)
		(placement
			(enabled no)
			(sheetname "")
		)
		(fill yes
			(thermal_gap 0.5)
			(thermal_bridge_width 0.5)
			(island_removal_mode 0)
		)
		(polygon
			(pts
				(arc
					(start 342.52027 -234.970066)
					(mid 341.86749 -234.970066)
					(end 342.52027 -234.970066)
				)
			)
		)
	)
	(zone
		(layers "B.Cu" "In6.Cu" "In11.Cu" "In13.Cu" "In15.Cu")
		(hatch none 0.5)
		(connect_pads
			(clearance 0)
		)
		(min_thickness 0.25)
		(keepout
			(tracks not_allowed)
			(vias allowed)
			(pads allowed)
			(copperpour not_allowed)
			(footprints allowed)
		)
		(placement
			(enabled no)
			(sheetname "")
		)
		(fill yes
			(thermal_gap 0.5)
			(thermal_bridge_width 0.5)
			(island_removal_mode 0)
		)
		(polygon
			(pts
				(arc
					(start 339.810852 -257.98907)
					(mid 339.158072 -257.98907)
					(end 339.810852 -257.98907)
				)
			)
		)
	)
	(zone
		(layers "B.Cu" "In6.Cu" "In11.Cu" "In13.Cu" "In15.Cu")
		(hatch none 0.5)
		(connect_pads
			(clearance 0)
		)
		(min_thickness 0.25)
		(keepout
			(tracks not_allowed)
			(vias allowed)
			(pads allowed)
			(copperpour not_allowed)
			(footprints allowed)
		)
		(placement
			(enabled no)
			(sheetname "")
		)
		(fill yes
			(thermal_gap 0.5)
			(thermal_bridge_width 0.5)
			(island_removal_mode 0)
		)
		(polygon
			(pts
				(arc
					(start 91.870784 -277.522432)
					(mid 91.218004 -277.522432)
					(end 91.870784 -277.522432)
				)
			)
		)
	)
	(zone
		(layers "B.Cu" "In6.Cu" "In11.Cu" "In13.Cu" "In15.Cu")
		(hatch none 0.5)
		(connect_pads
			(clearance 0)
		)
		(min_thickness 0.25)
		(keepout
			(tracks not_allowed)
			(vias allowed)
			(pads allowed)
			(copperpour not_allowed)
			(footprints allowed)
		)
		(placement
			(enabled no)
			(sheetname "")
		)
		(fill yes
			(thermal_gap 0.5)
			(thermal_bridge_width 0.5)
			(island_removal_mode 0)
		)
		(polygon
			(pts
				(arc
					(start 342.160606 -276.708616)
					(mid 341.507826 -276.708616)
					(end 342.160606 -276.708616)
				)
			)
		)
	)
	(zone
		(layers "B.Cu" "In6.Cu" "In11.Cu" "In13.Cu" "In15.Cu")
		(hatch none 0.5)
		(connect_pads
			(clearance 0)
		)
		(min_thickness 0.25)
		(keepout
			(tracks not_allowed)
			(vias allowed)
			(pads allowed)
			(copperpour not_allowed)
			(footprints allowed)
		)
		(placement
			(enabled no)
			(sheetname "")
		)
		(fill yes
			(thermal_gap 0.5)
			(thermal_bridge_width 0.5)
			(island_removal_mode 0)
		)
		(polygon
			(pts
				(arc
					(start 377.763024 -227.64496)
					(mid 377.110244 -227.64496)
					(end 377.763024 -227.64496)
				)
			)
		)
	)
	(zone
		(layers "B.Cu" "In6.Cu" "In11.Cu" "In13.Cu" "In15.Cu")
		(hatch none 0.5)
		(connect_pads
			(clearance 0)
		)
		(min_thickness 0.25)
		(keepout
			(tracks not_allowed)
			(vias allowed)
			(pads allowed)
			(copperpour not_allowed)
			(footprints allowed)
		)
		(placement
			(enabled no)
			(sheetname "")
		)
		(fill yes
			(thermal_gap 0.5)
			(thermal_bridge_width 0.5)
			(island_removal_mode 0)
		)
		(polygon
			(pts
				(arc
					(start 132.282184 -261.244842)
					(mid 131.629404 -261.244842)
					(end 132.282184 -261.244842)
				)
			)
		)
	)
	(zone
		(layers "B.Cu" "In6.Cu" "In11.Cu" "In13.Cu" "In15.Cu")
		(hatch none 0.5)
		(connect_pads
			(clearance 0)
		)
		(min_thickness 0.25)
		(keepout
			(tracks not_allowed)
			(vias allowed)
			(pads allowed)
			(copperpour not_allowed)
			(footprints allowed)
		)
		(placement
			(enabled no)
			(sheetname "")
		)
		(fill yes
			(thermal_gap 0.5)
			(thermal_bridge_width 0.5)
			(island_removal_mode 0)
		)
		(polygon
			(pts
				(arc
					(start 241.015774 -53.847238)
					(mid 240.312194 -53.847238)
					(end 241.015774 -53.847238)
				)
			)
		)
	)
	(zone
		(layers "B.Cu" "In6.Cu" "In11.Cu" "In13.Cu" "In15.Cu")
		(hatch none 0.5)
		(connect_pads
			(clearance 0)
		)
		(min_thickness 0.25)
		(keepout
			(tracks not_allowed)
			(vias allowed)
			(pads allowed)
			(copperpour not_allowed)
			(footprints allowed)
		)
		(placement
			(enabled no)
			(sheetname "")
		)
		(fill yes
			(thermal_gap 0.5)
			(thermal_bridge_width 0.5)
			(island_removal_mode 0)
		)
		(polygon
			(pts
				(arc
					(start 192.310004 -237.266734)
					(mid 191.657224 -237.266734)
					(end 192.310004 -237.266734)
				)
			)
		)
	)
	(zone
		(layers "B.Cu" "In6.Cu" "In11.Cu" "In13.Cu" "In15.Cu")
		(hatch none 0.5)
		(connect_pads
			(clearance 0)
		)
		(min_thickness 0.25)
		(keepout
			(tracks not_allowed)
			(vias allowed)
			(pads allowed)
			(copperpour not_allowed)
			(footprints allowed)
		)
		(placement
			(enabled no)
			(sheetname "")
		)
		(fill yes
			(thermal_gap 0.5)
			(thermal_bridge_width 0.5)
			(island_removal_mode 0)
		)
		(polygon
			(pts
				(arc
					(start 280.143204 -316.316614)
					(mid 279.490424 -316.316614)
					(end 280.143204 -316.316614)
				)
			)
		)
	)
	(zone
		(layers "B.Cu" "In6.Cu" "In11.Cu" "In13.Cu" "In15.Cu")
		(hatch none 0.5)
		(connect_pads
			(clearance 0)
		)
		(min_thickness 0.25)
		(keepout
			(tracks not_allowed)
			(vias allowed)
			(pads allowed)
			(copperpour not_allowed)
			(footprints allowed)
		)
		(placement
			(enabled no)
			(sheetname "")
		)
		(fill yes
			(thermal_gap 0.5)
			(thermal_bridge_width 0.5)
			(island_removal_mode 0)
		)
		(polygon
			(pts
				(arc
					(start 192.310004 -312.066686)
					(mid 191.657224 -312.066686)
					(end 192.310004 -312.066686)
				)
			)
		)
	)
	(zone
		(layers "B.Cu" "In6.Cu" "In11.Cu" "In13.Cu" "In15.Cu")
		(hatch none 0.5)
		(connect_pads
			(clearance 0)
		)
		(min_thickness 0.25)
		(keepout
			(tracks not_allowed)
			(vias allowed)
			(pads allowed)
			(copperpour not_allowed)
			(footprints allowed)
		)
		(placement
			(enabled no)
			(sheetname "")
		)
		(fill yes
			(thermal_gap 0.5)
			(thermal_bridge_width 0.5)
			(island_removal_mode 0)
		)
		(polygon
			(pts
				(arc
					(start 284.243272 -260.21665)
					(mid 283.590492 -260.21665)
					(end 284.243272 -260.21665)
				)
			)
		)
	)
	(zone
		(layers "B.Cu" "In6.Cu" "In11.Cu" "In13.Cu" "In15.Cu")
		(hatch none 0.5)
		(connect_pads
			(clearance 0)
		)
		(min_thickness 0.25)
		(keepout
			(tracks not_allowed)
			(vias allowed)
			(pads allowed)
			(copperpour not_allowed)
			(footprints allowed)
		)
		(placement
			(enabled no)
			(sheetname "")
		)
		(fill yes
			(thermal_gap 0.5)
			(thermal_bridge_width 0.5)
			(island_removal_mode 0)
		)
		(polygon
			(pts
				(arc
					(start 94.220284 -289.807142)
					(mid 93.567504 -289.807142)
					(end 94.220284 -289.807142)
				)
			)
		)
	)
	(zone
		(layers "B.Cu" "In6.Cu" "In11.Cu" "In13.Cu" "In15.Cu")
		(hatch none 0.5)
		(connect_pads
			(clearance 0)
		)
		(min_thickness 0.25)
		(keepout
			(tracks not_allowed)
			(vias allowed)
			(pads allowed)
			(copperpour not_allowed)
			(footprints allowed)
		)
		(placement
			(enabled no)
			(sheetname "")
		)
		(fill yes
			(thermal_gap 0.5)
			(thermal_bridge_width 0.5)
			(island_removal_mode 0)
		)
		(polygon
			(pts
				(arc
					(start 47.290736 -204.116686)
					(mid 46.637956 -204.116686)
					(end 47.290736 -204.116686)
				)
			)
		)
	)
	(zone
		(layers "B.Cu" "In6.Cu" "In11.Cu" "In13.Cu" "In15.Cu")
		(hatch none 0.5)
		(connect_pads
			(clearance 0)
		)
		(min_thickness 0.25)
		(keepout
			(tracks not_allowed)
			(vias allowed)
			(pads allowed)
			(copperpour not_allowed)
			(footprints allowed)
		)
		(placement
			(enabled no)
			(sheetname "")
		)
		(fill yes
			(thermal_gap 0.5)
			(thermal_bridge_width 0.5)
			(island_removal_mode 0)
		)
		(polygon
			(pts
				(arc
					(start 36.303204 -248.31675)
					(mid 35.650424 -248.31675)
					(end 36.303204 -248.31675)
				)
			)
		)
	)
	(zone
		(layers "B.Cu" "In6.Cu" "In11.Cu" "In13.Cu" "In15.Cu")
		(hatch none 0.5)
		(connect_pads
			(clearance 0)
		)
		(min_thickness 0.25)
		(keepout
			(tracks not_allowed)
			(vias allowed)
			(pads allowed)
			(copperpour not_allowed)
			(footprints allowed)
		)
		(placement
			(enabled no)
			(sheetname "")
		)
		(fill yes
			(thermal_gap 0.5)
			(thermal_bridge_width 0.5)
			(island_removal_mode 0)
		)
		(polygon
			(pts
				(arc
					(start 284.243272 -234.716574)
					(mid 283.590492 -234.716574)
					(end 284.243272 -234.716574)
				)
			)
		)
	)
	(zone
		(layers "B.Cu" "In6.Cu" "In11.Cu" "In13.Cu" "In15.Cu")
		(hatch none 0.5)
		(connect_pads
			(clearance 0)
		)
		(min_thickness 0.25)
		(keepout
			(tracks not_allowed)
			(vias allowed)
			(pads allowed)
			(copperpour not_allowed)
			(footprints allowed)
		)
		(placement
			(enabled no)
			(sheetname "")
		)
		(fill yes
			(thermal_gap 0.5)
			(thermal_bridge_width 0.5)
			(island_removal_mode 0)
		)
		(polygon
			(pts
				(arc
					(start 295.230804 -204.116686)
					(mid 294.578024 -204.116686)
					(end 295.230804 -204.116686)
				)
			)
		)
	)
	(zone
		(layers "B.Cu" "In6.Cu" "In11.Cu" "In13.Cu" "In15.Cu")
		(hatch none 0.5)
		(connect_pads
			(clearance 0)
		)
		(min_thickness 0.25)
		(keepout
			(tracks not_allowed)
			(vias allowed)
			(pads allowed)
			(copperpour not_allowed)
			(footprints allowed)
		)
		(placement
			(enabled no)
			(sheetname "")
		)
		(fill yes
			(thermal_gap 0.5)
			(thermal_bridge_width 0.5)
			(island_removal_mode 0)
		)
		(polygon
			(pts
				(arc
					(start 129.822956 -247.178322)
					(mid 129.170176 -247.178322)
					(end 129.822956 -247.178322)
				)
			)
		)
	)
	(zone
		(layers "B.Cu" "In6.Cu" "In11.Cu" "In13.Cu" "In15.Cu")
		(hatch none 0.5)
		(connect_pads
			(clearance 0)
		)
		(min_thickness 0.25)
		(keepout
			(tracks not_allowed)
			(vias allowed)
			(pads allowed)
			(copperpour not_allowed)
			(footprints allowed)
		)
		(placement
			(enabled no)
			(sheetname "")
		)
		(fill yes
			(thermal_gap 0.5)
			(thermal_bridge_width 0.5)
			(island_removal_mode 0)
		)
		(polygon
			(pts
				(arc
					(start 440.250072 -292.51656)
					(mid 439.597292 -292.51656)
					(end 440.250072 -292.51656)
				)
			)
		)
	)
	(zone
		(layers "B.Cu" "In6.Cu" "In11.Cu" "In13.Cu" "In15.Cu")
		(hatch none 0.5)
		(connect_pads
			(clearance 0)
		)
		(min_thickness 0.25)
		(keepout
			(tracks not_allowed)
			(vias allowed)
			(pads allowed)
			(copperpour not_allowed)
			(footprints allowed)
		)
		(placement
			(enabled no)
			(sheetname "")
		)
		(fill yes
			(thermal_gap 0.5)
			(thermal_bridge_width 0.5)
			(island_removal_mode 0)
		)
		(polygon
			(pts
				(arc
					(start 436.150004 -291.666676)
					(mid 435.497224 -291.666676)
					(end 436.150004 -291.666676)
				)
			)
		)
	)
	(zone
		(layers "B.Cu" "In6.Cu" "In11.Cu" "In13.Cu" "In15.Cu")
		(hatch none 0.5)
		(connect_pads
			(clearance 0)
		)
		(min_thickness 0.25)
		(keepout
			(tracks not_allowed)
			(vias allowed)
			(pads allowed)
			(copperpour not_allowed)
			(footprints allowed)
		)
		(placement
			(enabled no)
			(sheetname "")
		)
		(fill yes
			(thermal_gap 0.5)
			(thermal_bridge_width 0.5)
			(island_removal_mode 0)
		)
		(polygon
			(pts
				(arc
					(start 342.52027 -217.064336)
					(mid 341.86749 -217.064336)
					(end 342.52027 -217.064336)
				)
			)
		)
	)
	(zone
		(layers "B.Cu" "In6.Cu" "In11.Cu" "In13.Cu" "In15.Cu")
		(hatch none 0.5)
		(connect_pads
			(clearance 0)
		)
		(min_thickness 0.25)
		(keepout
			(tracks not_allowed)
			(vias allowed)
			(pads allowed)
			(copperpour not_allowed)
			(footprints allowed)
		)
		(placement
			(enabled no)
			(sheetname "")
		)
		(fill yes
			(thermal_gap 0.5)
			(thermal_bridge_width 0.5)
			(island_removal_mode 0)
		)
		(polygon
			(pts
				(arc
					(start 188.209936 -295.916604)
					(mid 187.557156 -295.916604)
					(end 188.209936 -295.916604)
				)
			)
		)
	)
	(zone
		(layers "B.Cu" "In6.Cu" "In11.Cu" "In13.Cu" "In15.Cu")
		(hatch none 0.5)
		(connect_pads
			(clearance 0)
		)
		(min_thickness 0.25)
		(keepout
			(tracks not_allowed)
			(vias allowed)
			(pads allowed)
			(copperpour not_allowed)
			(footprints allowed)
		)
		(placement
			(enabled no)
			(sheetname "")
		)
		(fill yes
			(thermal_gap 0.5)
			(thermal_bridge_width 0.5)
			(island_removal_mode 0)
		)
		(polygon
			(pts
				(arc
					(start 188.209936 -247.466612)
					(mid 187.557156 -247.466612)
					(end 188.209936 -247.466612)
				)
			)
		)
	)
	(zone
		(layers "B.Cu" "In6.Cu" "In11.Cu" "In13.Cu" "In15.Cu")
		(hatch none 0.5)
		(connect_pads
			(clearance 0)
		)
		(min_thickness 0.25)
		(keepout
			(tracks not_allowed)
			(vias allowed)
			(pads allowed)
			(copperpour not_allowed)
			(footprints allowed)
		)
		(placement
			(enabled no)
			(sheetname "")
		)
		(fill yes
			(thermal_gap 0.5)
			(thermal_bridge_width 0.5)
			(island_removal_mode 0)
		)
		(polygon
			(pts
				(arc
					(start 87.061802 -226.831144)
					(mid 86.409022 -226.831144)
					(end 87.061802 -226.831144)
				)
			)
		)
	)
	(zone
		(layers "B.Cu" "In6.Cu" "In11.Cu" "In13.Cu" "In15.Cu")
		(hatch none 0.5)
		(connect_pads
			(clearance 0)
		)
		(min_thickness 0.25)
		(keepout
			(tracks not_allowed)
			(vias allowed)
			(pads allowed)
			(copperpour not_allowed)
			(footprints allowed)
		)
		(placement
			(enabled no)
			(sheetname "")
		)
		(fill yes
			(thermal_gap 0.5)
			(thermal_bridge_width 0.5)
			(island_removal_mode 0)
		)
		(polygon
			(pts
				(arc
					(start 131.232402 -218.692222)
					(mid 130.579622 -218.692222)
					(end 131.232402 -218.692222)
				)
			)
		)
	)
	(zone
		(layers "B.Cu" "In6.Cu" "In11.Cu" "In13.Cu" "In15.Cu")
		(hatch none 0.5)
		(connect_pads
			(clearance 0)
		)
		(min_thickness 0.25)
		(keepout
			(tracks not_allowed)
			(vias allowed)
			(pads allowed)
			(copperpour not_allowed)
			(footprints allowed)
		)
		(placement
			(enabled no)
			(sheetname "")
		)
		(fill yes
			(thermal_gap 0.5)
			(thermal_bridge_width 0.5)
			(island_removal_mode 0)
		)
		(polygon
			(pts
				(arc
					(start 379.642624 -245.55069)
					(mid 378.989844 -245.55069)
					(end 379.642624 -245.55069)
				)
			)
		)
	)
	(zone
		(layers "B.Cu" "In6.Cu" "In11.Cu" "In13.Cu" "In15.Cu")
		(hatch none 0.5)
		(connect_pads
			(clearance 0)
		)
		(min_thickness 0.25)
		(keepout
			(tracks not_allowed)
			(vias allowed)
			(pads allowed)
			(copperpour not_allowed)
			(footprints allowed)
		)
		(placement
			(enabled no)
			(sheetname "")
		)
		(fill yes
			(thermal_gap 0.5)
			(thermal_bridge_width 0.5)
			(island_removal_mode 0)
		)
		(polygon
			(pts
				(arc
					(start 421.062404 -303.566576)
					(mid 420.409624 -303.566576)
					(end 421.062404 -303.566576)
				)
			)
		)
	)
	(zone
		(layers "B.Cu" "In6.Cu" "In11.Cu" "In13.Cu" "In15.Cu")
		(hatch none 0.5)
		(connect_pads
			(clearance 0)
		)
		(min_thickness 0.25)
		(keepout
			(tracks not_allowed)
			(vias allowed)
			(pads allowed)
			(copperpour not_allowed)
			(footprints allowed)
		)
		(placement
			(enabled no)
			(sheetname "")
		)
		(fill yes
			(thermal_gap 0.5)
			(thermal_bridge_width 0.5)
			(island_removal_mode 0)
		)
		(polygon
			(pts
				(arc
					(start 97.869756 -217.878406)
					(mid 97.216976 -217.878406)
					(end 97.869756 -217.878406)
				)
			)
		)
	)
	(zone
		(layers "B.Cu" "In6.Cu" "In11.Cu" "In13.Cu" "In15.Cu")
		(hatch none 0.5)
		(connect_pads
			(clearance 0)
		)
		(min_thickness 0.25)
		(keepout
			(tracks not_allowed)
			(vias allowed)
			(pads allowed)
			(copperpour not_allowed)
			(footprints allowed)
		)
		(placement
			(enabled no)
			(sheetname "")
		)
		(fill yes
			(thermal_gap 0.5)
			(thermal_bridge_width 0.5)
			(island_removal_mode 0)
		)
		(polygon
			(pts
				(arc
					(start 340.750652 -259.616956)
					(mid 340.097872 -259.616956)
					(end 340.750652 -259.616956)
				)
			)
		)
	)
	(zone
		(layers "B.Cu" "In6.Cu" "In11.Cu" "In13.Cu" "In15.Cu")
		(hatch none 0.5)
		(connect_pads
			(clearance 0)
		)
		(min_thickness 0.25)
		(keepout
			(tracks not_allowed)
			(vias allowed)
			(pads allowed)
			(copperpour not_allowed)
			(footprints allowed)
		)
		(placement
			(enabled no)
			(sheetname "")
		)
		(fill yes
			(thermal_gap 0.5)
			(thermal_bridge_width 0.5)
			(island_removal_mode 0)
		)
		(polygon
			(pts
				(arc
					(start 436.150004 -308.666642)
					(mid 435.497224 -308.666642)
					(end 436.150004 -308.666642)
				)
			)
		)
	)
	(zone
		(layers "B.Cu" "In6.Cu" "In11.Cu" "In13.Cu" "In15.Cu")
		(hatch none 0.5)
		(connect_pads
			(clearance 0)
		)
		(min_thickness 0.25)
		(keepout
			(tracks not_allowed)
			(vias allowed)
			(pads allowed)
			(copperpour not_allowed)
			(footprints allowed)
		)
		(placement
			(enabled no)
			(sheetname "")
		)
		(fill yes
			(thermal_gap 0.5)
			(thermal_bridge_width 0.5)
			(island_removal_mode 0)
		)
		(polygon
			(pts
				(arc
					(start 440.250072 -309.516526)
					(mid 439.597292 -309.516526)
					(end 440.250072 -309.516526)
				)
			)
		)
	)
	(zone
		(layers "B.Cu" "In6.Cu" "In11.Cu" "In13.Cu" "In15.Cu")
		(hatch none 0.5)
		(connect_pads
			(clearance 0)
		)
		(min_thickness 0.25)
		(keepout
			(tracks not_allowed)
			(vias allowed)
			(pads allowed)
			(copperpour not_allowed)
			(footprints allowed)
		)
		(placement
			(enabled no)
			(sheetname "")
		)
		(fill yes
			(thermal_gap 0.5)
			(thermal_bridge_width 0.5)
			(island_removal_mode 0)
		)
		(polygon
			(pts
				(arc
					(start 36.303204 -260.21665)
					(mid 35.650424 -260.21665)
					(end 36.303204 -260.21665)
				)
			)
		)
	)
	(zone
		(layers "B.Cu" "In6.Cu" "In11.Cu" "In13.Cu" "In15.Cu")
		(hatch none 0.5)
		(connect_pads
			(clearance 0)
		)
		(min_thickness 0.25)
		(keepout
			(tracks not_allowed)
			(vias allowed)
			(pads allowed)
			(copperpour not_allowed)
			(footprints allowed)
		)
		(placement
			(enabled no)
			(sheetname "")
		)
		(fill yes
			(thermal_gap 0.5)
			(thermal_bridge_width 0.5)
			(island_removal_mode 0)
		)
		(polygon
			(pts
				(arc
					(start 284.243272 -290.816792)
					(mid 283.590492 -290.816792)
					(end 284.243272 -290.816792)
				)
			)
		)
	)
	(zone
		(layers "B.Cu" "In6.Cu" "In11.Cu" "In13.Cu" "In15.Cu")
		(hatch none 0.5)
		(connect_pads
			(clearance 0)
		)
		(min_thickness 0.25)
		(keepout
			(tracks not_allowed)
			(vias allowed)
			(pads allowed)
			(copperpour not_allowed)
			(footprints allowed)
		)
		(placement
			(enabled no)
			(sheetname "")
		)
		(fill yes
			(thermal_gap 0.5)
			(thermal_bridge_width 0.5)
			(island_removal_mode 0)
		)
		(polygon
			(pts
				(arc
					(start 343.930224 -217.878406)
					(mid 343.277444 -217.878406)
					(end 343.930224 -217.878406)
				)
			)
		)
	)
	(zone
		(layers "B.Cu" "In6.Cu" "In11.Cu" "In13.Cu" "In15.Cu")
		(hatch none 0.5)
		(connect_pads
			(clearance 0)
		)
		(min_thickness 0.25)
		(keepout
			(tracks not_allowed)
			(vias allowed)
			(pads allowed)
			(copperpour not_allowed)
			(footprints allowed)
		)
		(placement
			(enabled no)
			(sheetname "")
		)
		(fill yes
			(thermal_gap 0.5)
			(thermal_bridge_width 0.5)
			(island_removal_mode 0)
		)
		(polygon
			(pts
				(arc
					(start 120.424956 -217.878406)
					(mid 119.772176 -217.878406)
					(end 120.424956 -217.878406)
				)
			)
		)
	)
	(zone
		(layers "B.Cu" "In6.Cu" "In11.Cu" "In13.Cu" "In15.Cu")
		(hatch none 0.5)
		(connect_pads
			(clearance 0)
		)
		(min_thickness 0.25)
		(keepout
			(tracks not_allowed)
			(vias allowed)
			(pads allowed)
			(copperpour not_allowed)
			(footprints allowed)
		)
		(placement
			(enabled no)
			(sheetname "")
		)
		(fill yes
			(thermal_gap 0.5)
			(thermal_bridge_width 0.5)
			(island_removal_mode 0)
		)
		(polygon
			(pts
				(arc
					(start 32.203136 -262.76681)
					(mid 31.550356 -262.76681)
					(end 32.203136 -262.76681)
				)
			)
		)
	)
	(zone
		(layers "B.Cu" "In6.Cu" "In11.Cu" "In13.Cu" "In15.Cu")
		(hatch none 0.5)
		(connect_pads
			(clearance 0)
		)
		(min_thickness 0.25)
		(keepout
			(tracks not_allowed)
			(vias allowed)
			(pads allowed)
			(copperpour not_allowed)
			(footprints allowed)
		)
		(placement
			(enabled no)
			(sheetname "")
		)
		(fill yes
			(thermal_gap 0.5)
			(thermal_bridge_width 0.5)
			(island_removal_mode 0)
		)
		(polygon
			(pts
				(arc
					(start 440.250072 -311.216548)
					(mid 439.597292 -311.216548)
					(end 440.250072 -311.216548)
				)
			)
		)
	)
	(zone
		(layers "B.Cu" "In6.Cu" "In11.Cu" "In13.Cu" "In15.Cu")
		(hatch none 0.5)
		(connect_pads
			(clearance 0)
		)
		(min_thickness 0.25)
		(keepout
			(tracks not_allowed)
			(vias allowed)
			(pads allowed)
			(copperpour not_allowed)
			(footprints allowed)
		)
		(placement
			(enabled no)
			(sheetname "")
		)
		(fill yes
			(thermal_gap 0.5)
			(thermal_bridge_width 0.5)
			(island_removal_mode 0)
		)
		(polygon
			(pts
				(arc
					(start 295.230804 -302.716692)
					(mid 294.578024 -302.716692)
					(end 295.230804 -302.716692)
				)
			)
		)
	)
	(zone
		(layers "B.Cu" "In6.Cu" "In11.Cu" "In13.Cu" "In15.Cu")
		(hatch none 0.5)
		(connect_pads
			(clearance 0)
		)
		(min_thickness 0.25)
		(keepout
			(tracks not_allowed)
			(vias allowed)
			(pads allowed)
			(copperpour not_allowed)
			(footprints allowed)
		)
		(placement
			(enabled no)
			(sheetname "")
		)
		(fill yes
			(thermal_gap 0.5)
			(thermal_bridge_width 0.5)
			(island_removal_mode 0)
		)
		(polygon
			(pts
				(arc
					(start 379.642624 -230.900478)
					(mid 378.989844 -230.900478)
					(end 379.642624 -230.900478)
				)
			)
		)
	)
	(zone
		(layers "B.Cu" "In6.Cu" "In11.Cu" "In13.Cu" "In15.Cu")
		(hatch none 0.5)
		(connect_pads
			(clearance 0)
		)
		(min_thickness 0.25)
		(keepout
			(tracks not_allowed)
			(vias allowed)
			(pads allowed)
			(copperpour not_allowed)
			(footprints allowed)
		)
		(placement
			(enabled no)
			(sheetname "")
		)
		(fill yes
			(thermal_gap 0.5)
			(thermal_bridge_width 0.5)
			(island_removal_mode 0)
		)
		(polygon
			(pts
				(arc
					(start 32.203136 -207.51673)
					(mid 31.550356 -207.51673)
					(end 32.203136 -207.51673)
				)
			)
		)
	)
	(zone
		(layers "B.Cu" "In6.Cu" "In11.Cu" "In13.Cu" "In15.Cu")
		(hatch none 0.5)
		(connect_pads
			(clearance 0)
		)
		(min_thickness 0.25)
		(keepout
			(tracks not_allowed)
			(vias allowed)
			(pads allowed)
			(copperpour not_allowed)
			(footprints allowed)
		)
		(placement
			(enabled no)
			(sheetname "")
		)
		(fill yes
			(thermal_gap 0.5)
			(thermal_bridge_width 0.5)
			(island_removal_mode 0)
		)
		(polygon
			(pts
				(arc
					(start 192.310004 -313.766708)
					(mid 191.657224 -313.766708)
					(end 192.310004 -313.766708)
				)
			)
		)
	)
	(zone
		(layers "B.Cu" "In6.Cu" "In11.Cu" "In13.Cu" "In15.Cu")
		(hatch none 0.5)
		(connect_pads
			(clearance 0)
		)
		(min_thickness 0.25)
		(keepout
			(tracks not_allowed)
			(vias allowed)
			(pads allowed)
			(copperpour not_allowed)
			(footprints allowed)
		)
		(placement
			(enabled no)
			(sheetname "")
		)
		(fill yes
			(thermal_gap 0.5)
			(thermal_bridge_width 0.5)
			(island_removal_mode 0)
		)
		(polygon
			(pts
				(arc
					(start 132.172202 -233.34218)
					(mid 131.519422 -233.34218)
					(end 132.172202 -233.34218)
				)
			)
		)
	)
	(zone
		(layers "B.Cu" "In6.Cu" "In11.Cu" "In13.Cu" "In15.Cu")
		(hatch none 0.5)
		(connect_pads
			(clearance 0)
		)
		(min_thickness 0.25)
		(keepout
			(tracks not_allowed)
			(vias allowed)
			(pads allowed)
			(copperpour not_allowed)
			(footprints allowed)
		)
		(placement
			(enabled no)
			(sheetname "")
		)
		(fill yes
			(thermal_gap 0.5)
			(thermal_bridge_width 0.5)
			(island_removal_mode 0)
		)
		(polygon
			(pts
				(arc
					(start 130.402838 -288.917126)
					(mid 129.750058 -288.917126)
					(end 130.402838 -288.917126)
				)
			)
		)
	)
	(zone
		(layers "B.Cu" "In6.Cu" "In11.Cu" "In13.Cu" "In15.Cu")
		(hatch none 0.5)
		(connect_pads
			(clearance 0)
		)
		(min_thickness 0.25)
		(keepout
			(tracks not_allowed)
			(vias allowed)
			(pads allowed)
			(copperpour not_allowed)
			(footprints allowed)
		)
		(placement
			(enabled no)
			(sheetname "")
		)
		(fill yes
			(thermal_gap 0.5)
			(thermal_bridge_width 0.5)
			(island_removal_mode 0)
		)
		(polygon
			(pts
				(arc
					(start 32.203136 -297.616626)
					(mid 31.550356 -297.616626)
					(end 32.203136 -297.616626)
				)
			)
		)
	)
	(zone
		(layers "B.Cu" "In6.Cu" "In11.Cu" "In13.Cu" "In15.Cu")
		(hatch none 0.5)
		(connect_pads
			(clearance 0)
		)
		(min_thickness 0.25)
		(keepout
			(tracks not_allowed)
			(vias allowed)
			(pads allowed)
			(copperpour not_allowed)
			(footprints allowed)
		)
		(placement
			(enabled no)
			(sheetname "")
		)
		(fill yes
			(thermal_gap 0.5)
			(thermal_bridge_width 0.5)
			(island_removal_mode 0)
		)
		(polygon
			(pts
				(arc
					(start 92.340938 -276.708616)
					(mid 91.688158 -276.708616)
					(end 92.340938 -276.708616)
				)
			)
		)
	)
	(zone
		(layers "B.Cu" "In6.Cu" "In11.Cu" "In13.Cu" "In15.Cu")
		(hatch none 0.5)
		(connect_pads
			(clearance 0)
		)
		(min_thickness 0.25)
		(keepout
			(tracks not_allowed)
			(vias allowed)
			(pads allowed)
			(copperpour not_allowed)
			(footprints allowed)
		)
		(placement
			(enabled no)
			(sheetname "")
		)
		(fill yes
			(thermal_gap 0.5)
			(thermal_bridge_width 0.5)
			(island_removal_mode 0)
		)
		(polygon
			(pts
				(arc
					(start 132.282184 -259.616956)
					(mid 131.629404 -259.616956)
					(end 132.282184 -259.616956)
				)
			)
		)
	)
	(zone
		(layers "B.Cu" "In6.Cu" "In11.Cu" "In13.Cu" "In15.Cu")
		(hatch none 0.5)
		(connect_pads
			(clearance 0)
		)
		(min_thickness 0.25)
		(keepout
			(tracks not_allowed)
			(vias allowed)
			(pads allowed)
			(copperpour not_allowed)
			(footprints allowed)
		)
		(placement
			(enabled no)
			(sheetname "")
		)
		(fill yes
			(thermal_gap 0.5)
			(thermal_bridge_width 0.5)
			(island_removal_mode 0)
		)
		(polygon
			(pts
				(arc
					(start 350.03867 -217.064336)
					(mid 349.38589 -217.064336)
					(end 350.03867 -217.064336)
				)
			)
		)
	)
	(zone
		(layers "B.Cu" "In6.Cu" "In11.Cu" "In13.Cu" "In15.Cu")
		(hatch none 0.5)
		(connect_pads
			(clearance 0)
		)
		(min_thickness 0.25)
		(keepout
			(tracks not_allowed)
			(vias allowed)
			(pads allowed)
			(copperpour not_allowed)
			(footprints allowed)
		)
		(placement
			(enabled no)
			(sheetname "")
		)
		(fill yes
			(thermal_gap 0.5)
			(thermal_bridge_width 0.5)
			(island_removal_mode 0)
		)
		(polygon
			(pts
				(arc
					(start 344.689684 -44.220892)
					(mid 344.036904 -44.220892)
					(end 344.689684 -44.220892)
				)
			)
		)
	)
	(zone
		(layers "B.Cu" "In6.Cu" "In11.Cu" "In13.Cu" "In15.Cu")
		(hatch none 0.5)
		(connect_pads
			(clearance 0)
		)
		(min_thickness 0.25)
		(keepout
			(tracks not_allowed)
			(vias allowed)
			(pads allowed)
			(copperpour not_allowed)
			(footprints allowed)
		)
		(placement
			(enabled no)
			(sheetname "")
		)
		(fill yes
			(thermal_gap 0.5)
			(thermal_bridge_width 0.5)
			(island_removal_mode 0)
		)
		(polygon
			(pts
				(arc
					(start 295.230804 -299.316648)
					(mid 294.578024 -299.316648)
					(end 295.230804 -299.316648)
				)
			)
		)
	)
	(zone
		(layers "B.Cu" "In6.Cu" "In11.Cu" "In13.Cu" "In15.Cu")
		(hatch none 0.5)
		(connect_pads
			(clearance 0)
		)
		(min_thickness 0.25)
		(keepout
			(tracks not_allowed)
			(vias allowed)
			(pads allowed)
			(copperpour not_allowed)
			(footprints allowed)
		)
		(placement
			(enabled no)
			(sheetname "")
		)
		(fill yes
			(thermal_gap 0.5)
			(thermal_bridge_width 0.5)
			(island_removal_mode 0)
		)
		(polygon
			(pts
				(arc
					(start 47.290736 -228.766624)
					(mid 46.637956 -228.766624)
					(end 47.290736 -228.766624)
				)
			)
		)
	)
	(zone
		(layers "B.Cu" "In6.Cu" "In11.Cu" "In13.Cu" "In15.Cu")
		(hatch none 0.5)
		(connect_pads
			(clearance 0)
		)
		(min_thickness 0.25)
		(keepout
			(tracks not_allowed)
			(vias allowed)
			(pads allowed)
			(copperpour not_allowed)
			(footprints allowed)
		)
		(placement
			(enabled no)
			(sheetname "")
		)
		(fill yes
			(thermal_gap 0.5)
			(thermal_bridge_width 0.5)
			(island_removal_mode 0)
		)
		(polygon
			(pts
				(arc
					(start 421.062404 -232.166668)
					(mid 420.409624 -232.166668)
					(end 421.062404 -232.166668)
				)
			)
		)
	)
	(zone
		(layers "B.Cu" "In6.Cu" "In11.Cu" "In13.Cu" "In15.Cu")
		(hatch none 0.5)
		(connect_pads
			(clearance 0)
		)
		(min_thickness 0.25)
		(keepout
			(tracks not_allowed)
			(vias allowed)
			(pads allowed)
			(copperpour not_allowed)
			(footprints allowed)
		)
		(placement
			(enabled no)
			(sheetname "")
		)
		(fill yes
			(thermal_gap 0.5)
			(thermal_bridge_width 0.5)
			(island_removal_mode 0)
		)
		(polygon
			(pts
				(arc
					(start 110.087156 -217.878406)
					(mid 109.434376 -217.878406)
					(end 110.087156 -217.878406)
				)
			)
		)
	)
	(zone
		(layers "B.Cu" "In6.Cu" "In11.Cu" "In13.Cu" "In15.Cu")
		(hatch none 0.5)
		(connect_pads
			(clearance 0)
		)
		(min_thickness 0.25)
		(keepout
			(tracks not_allowed)
			(vias allowed)
			(pads allowed)
			(copperpour not_allowed)
			(footprints allowed)
		)
		(placement
			(enabled no)
			(sheetname "")
		)
		(fill yes
			(thermal_gap 0.5)
			(thermal_bridge_width 0.5)
			(island_removal_mode 0)
		)
		(polygon
			(pts
				(arc
					(start 173.122336 -204.116686)
					(mid 172.469556 -204.116686)
					(end 173.122336 -204.116686)
				)
			)
		)
	)
	(zone
		(layers "B.Cu" "In6.Cu" "In11.Cu" "In13.Cu" "In15.Cu")
		(hatch none 0.5)
		(connect_pads
			(clearance 0)
		)
		(min_thickness 0.25)
		(keepout
			(tracks not_allowed)
			(vias allowed)
			(pads allowed)
			(copperpour not_allowed)
			(footprints allowed)
		)
		(placement
			(enabled no)
			(sheetname "")
		)
		(fill yes
			(thermal_gap 0.5)
			(thermal_bridge_width 0.5)
			(island_removal_mode 0)
		)
		(polygon
			(pts
				(arc
					(start 378.812806 -258.80314)
					(mid 378.160026 -258.80314)
					(end 378.812806 -258.80314)
				)
			)
		)
	)
	(zone
		(layers "B.Cu" "In6.Cu" "In11.Cu" "In13.Cu" "In15.Cu")
		(hatch none 0.5)
		(connect_pads
			(clearance 0)
		)
		(min_thickness 0.25)
		(keepout
			(tracks not_allowed)
			(vias allowed)
			(pads allowed)
			(copperpour not_allowed)
			(footprints allowed)
		)
		(placement
			(enabled no)
			(sheetname "")
		)
		(fill yes
			(thermal_gap 0.5)
			(thermal_bridge_width 0.5)
			(island_removal_mode 0)
		)
		(polygon
			(pts
				(arc
					(start 339.70087 -218.692222)
					(mid 339.04809 -218.692222)
					(end 339.70087 -218.692222)
				)
			)
		)
	)
	(zone
		(layers "B.Cu" "In6.Cu" "In11.Cu" "In13.Cu" "In15.Cu")
		(hatch none 0.5)
		(connect_pads
			(clearance 0)
		)
		(min_thickness 0.25)
		(keepout
			(tracks not_allowed)
			(vias allowed)
			(pads allowed)
			(copperpour not_allowed)
			(footprints allowed)
		)
		(placement
			(enabled no)
			(sheetname "")
		)
		(fill yes
			(thermal_gap 0.5)
			(thermal_bridge_width 0.5)
			(island_removal_mode 0)
		)
		(polygon
			(pts
				(arc
					(start 192.310004 -261.916672)
					(mid 191.657224 -261.916672)
					(end 192.310004 -261.916672)
				)
			)
		)
	)
	(zone
		(layers "B.Cu" "In6.Cu" "In11.Cu" "In13.Cu" "In15.Cu")
		(hatch none 0.5)
		(connect_pads
			(clearance 0)
		)
		(min_thickness 0.25)
		(keepout
			(tracks not_allowed)
			(vias allowed)
			(pads allowed)
			(copperpour not_allowed)
			(footprints allowed)
		)
		(placement
			(enabled no)
			(sheetname "")
		)
		(fill yes
			(thermal_gap 0.5)
			(thermal_bridge_width 0.5)
			(island_removal_mode 0)
		)
		(polygon
			(pts
				(arc
					(start 333.59217 -224.389442)
					(mid 332.93939 -224.389442)
					(end 333.59217 -224.389442)
				)
			)
		)
	)
	(zone
		(layers "B.Cu" "In6.Cu" "In11.Cu" "In13.Cu" "In15.Cu")
		(hatch none 0.5)
		(connect_pads
			(clearance 0)
		)
		(min_thickness 0.25)
		(keepout
			(tracks not_allowed)
			(vias allowed)
			(pads allowed)
			(copperpour not_allowed)
			(footprints allowed)
		)
		(placement
			(enabled no)
			(sheetname "")
		)
		(fill yes
			(thermal_gap 0.5)
			(thermal_bridge_width 0.5)
			(island_removal_mode 0)
		)
		(polygon
			(pts
				(arc
					(start 338.871306 -288.917126)
					(mid 338.218526 -288.917126)
					(end 338.871306 -288.917126)
				)
			)
		)
	)
	(zone
		(layers "B.Cu" "In6.Cu" "In11.Cu" "In13.Cu" "In15.Cu")
		(hatch none 0.5)
		(connect_pads
			(clearance 0)
		)
		(min_thickness 0.25)
		(keepout
			(tracks not_allowed)
			(vias allowed)
			(pads allowed)
			(copperpour not_allowed)
			(footprints allowed)
		)
		(placement
			(enabled no)
			(sheetname "")
		)
		(fill yes
			(thermal_gap 0.5)
			(thermal_bridge_width 0.5)
			(island_removal_mode 0)
		)
		(polygon
			(pts
				(arc
					(start 93.640402 -239.853216)
					(mid 92.987622 -239.853216)
					(end 93.640402 -239.853216)
				)
			)
		)
	)
	(zone
		(layers "B.Cu" "In6.Cu" "In11.Cu" "In13.Cu" "In15.Cu")
		(hatch none 0.5)
		(connect_pads
			(clearance 0)
		)
		(min_thickness 0.25)
		(keepout
			(tracks not_allowed)
			(vias allowed)
			(pads allowed)
			(copperpour not_allowed)
			(footprints allowed)
		)
		(placement
			(enabled no)
			(sheetname "")
		)
		(fill yes
			(thermal_gap 0.5)
			(thermal_bridge_width 0.5)
			(island_removal_mode 0)
		)
		(polygon
			(pts
				(arc
					(start 347.21927 -218.692222)
					(mid 346.56649 -218.692222)
					(end 347.21927 -218.692222)
				)
			)
		)
	)
	(zone
		(layers "B.Cu" "In6.Cu" "In11.Cu" "In13.Cu" "In15.Cu")
		(hatch none 0.5)
		(connect_pads
			(clearance 0)
		)
		(min_thickness 0.25)
		(keepout
			(tracks not_allowed)
			(vias allowed)
			(pads allowed)
			(copperpour not_allowed)
			(footprints allowed)
		)
		(placement
			(enabled no)
			(sheetname "")
		)
		(fill yes
			(thermal_gap 0.5)
			(thermal_bridge_width 0.5)
			(island_removal_mode 0)
		)
		(polygon
			(pts
				(arc
					(start 92.810584 -264.50036)
					(mid 92.157804 -264.50036)
					(end 92.810584 -264.50036)
				)
			)
		)
	)
	(zone
		(layers "B.Cu" "In6.Cu" "In11.Cu" "In13.Cu" "In15.Cu")
		(hatch none 0.5)
		(connect_pads
			(clearance 0)
		)
		(min_thickness 0.25)
		(keepout
			(tracks not_allowed)
			(vias allowed)
			(pads allowed)
			(copperpour not_allowed)
			(footprints allowed)
		)
		(placement
			(enabled no)
			(sheetname "")
		)
		(fill yes
			(thermal_gap 0.5)
			(thermal_bridge_width 0.5)
			(island_removal_mode 0)
		)
		(polygon
			(pts
				(arc
					(start 199.853804 -244.916706)
					(mid 199.201024 -244.916706)
					(end 199.853804 -244.916706)
				)
			)
		)
	)
	(zone
		(layers "B.Cu" "In6.Cu" "In11.Cu" "In13.Cu" "In15.Cu")
		(hatch none 0.5)
		(connect_pads
			(clearance 0)
		)
		(min_thickness 0.25)
		(keepout
			(tracks not_allowed)
			(vias allowed)
			(pads allowed)
			(copperpour not_allowed)
			(footprints allowed)
		)
		(placement
			(enabled no)
			(sheetname "")
		)
		(fill yes
			(thermal_gap 0.5)
			(thermal_bridge_width 0.5)
			(island_removal_mode 0)
		)
		(polygon
			(pts
				(arc
					(start 377.763024 -247.178322)
					(mid 377.110244 -247.178322)
					(end 377.763024 -247.178322)
				)
			)
		)
	)
	(zone
		(layers "B.Cu" "In6.Cu" "In11.Cu" "In13.Cu" "In15.Cu")
		(hatch none 0.5)
		(connect_pads
			(clearance 0)
		)
		(min_thickness 0.25)
		(keepout
			(tracks not_allowed)
			(vias allowed)
			(pads allowed)
			(copperpour not_allowed)
			(footprints allowed)
		)
		(placement
			(enabled no)
			(sheetname "")
		)
		(fill yes
			(thermal_gap 0.5)
			(thermal_bridge_width 0.5)
			(island_removal_mode 0)
		)
		(polygon
			(pts
				(arc
					(start 177.222404 -203.266802)
					(mid 176.569624 -203.266802)
					(end 177.222404 -203.266802)
				)
			)
		)
	)
	(zone
		(layers "B.Cu" "In6.Cu" "In11.Cu" "In13.Cu" "In15.Cu")
		(hatch none 0.5)
		(connect_pads
			(clearance 0)
		)
		(min_thickness 0.25)
		(keepout
			(tracks not_allowed)
			(vias allowed)
			(pads allowed)
			(copperpour not_allowed)
			(footprints allowed)
		)
		(placement
			(enabled no)
			(sheetname "")
		)
		(fill yes
			(thermal_gap 0.5)
			(thermal_bridge_width 0.5)
			(island_removal_mode 0)
		)
		(polygon
			(pts
				(arc
					(start 127.003556 -248.806208)
					(mid 126.350776 -248.806208)
					(end 127.003556 -248.806208)
				)
			)
		)
	)
	(zone
		(layers "B.Cu" "In6.Cu" "In11.Cu" "In13.Cu" "In15.Cu")
		(hatch none 0.5)
		(connect_pads
			(clearance 0)
		)
		(min_thickness 0.25)
		(keepout
			(tracks not_allowed)
			(vias allowed)
			(pads allowed)
			(copperpour not_allowed)
			(footprints allowed)
		)
		(placement
			(enabled no)
			(sheetname "")
		)
		(fill yes
			(thermal_gap 0.5)
			(thermal_bridge_width 0.5)
			(island_removal_mode 0)
		)
		(polygon
			(pts
				(arc
					(start 378.23267 -228.45903)
					(mid 377.57989 -228.45903)
					(end 378.23267 -228.45903)
				)
			)
		)
	)
	(zone
		(layers "B.Cu" "In6.Cu" "In11.Cu" "In13.Cu" "In15.Cu")
		(hatch none 0.5)
		(connect_pads
			(clearance 0)
		)
		(min_thickness 0.25)
		(keepout
			(tracks not_allowed)
			(vias allowed)
			(pads allowed)
			(copperpour not_allowed)
			(footprints allowed)
		)
		(placement
			(enabled no)
			(sheetname "")
		)
		(fill yes
			(thermal_gap 0.5)
			(thermal_bridge_width 0.5)
			(island_removal_mode 0)
		)
		(polygon
			(pts
				(arc
					(start 382.102106 -288.917126)
					(mid 381.449326 -288.917126)
					(end 382.102106 -288.917126)
				)
			)
		)
	)
	(zone
		(layers "B.Cu" "In6.Cu" "In11.Cu" "In13.Cu" "In15.Cu")
		(hatch none 0.5)
		(connect_pads
			(clearance 0)
		)
		(min_thickness 0.25)
		(keepout
			(tracks not_allowed)
			(vias allowed)
			(pads allowed)
			(copperpour not_allowed)
			(footprints allowed)
		)
		(placement
			(enabled no)
			(sheetname "")
		)
		(fill yes
			(thermal_gap 0.5)
			(thermal_bridge_width 0.5)
			(island_removal_mode 0)
		)
		(polygon
			(pts
				(arc
					(start 188.209936 -293.366698)
					(mid 187.557156 -293.366698)
					(end 188.209936 -293.366698)
				)
			)
		)
	)
	(zone
		(layers "B.Cu" "In6.Cu" "In11.Cu" "In13.Cu" "In15.Cu")
		(hatch none 0.5)
		(connect_pads
			(clearance 0)
		)
		(min_thickness 0.25)
		(keepout
			(tracks not_allowed)
			(vias allowed)
			(pads allowed)
			(copperpour not_allowed)
			(footprints allowed)
		)
		(placement
			(enabled no)
			(sheetname "")
		)
		(fill yes
			(thermal_gap 0.5)
			(thermal_bridge_width 0.5)
			(island_removal_mode 0)
		)
		(polygon
			(pts
				(arc
					(start 101.738684 -289.807142)
					(mid 101.085904 -289.807142)
					(end 101.738684 -289.807142)
				)
			)
		)
	)
	(zone
		(layers "B.Cu" "In6.Cu" "In11.Cu" "In13.Cu" "In15.Cu")
		(hatch none 0.5)
		(connect_pads
			(clearance 0)
		)
		(min_thickness 0.25)
		(keepout
			(tracks not_allowed)
			(vias allowed)
			(pads allowed)
			(copperpour not_allowed)
			(footprints allowed)
		)
		(placement
			(enabled no)
			(sheetname "")
		)
		(fill yes
			(thermal_gap 0.5)
			(thermal_bridge_width 0.5)
			(island_removal_mode 0)
		)
		(polygon
			(pts
				(arc
					(start 440.250072 -212.616796)
					(mid 439.597292 -212.616796)
					(end 440.250072 -212.616796)
				)
			)
		)
	)
	(zone
		(layers "B.Cu" "In6.Cu" "In11.Cu" "In13.Cu" "In15.Cu")
		(hatch none 0.5)
		(connect_pads
			(clearance 0)
		)
		(min_thickness 0.25)
		(keepout
			(tracks not_allowed)
			(vias allowed)
			(pads allowed)
			(copperpour not_allowed)
			(footprints allowed)
		)
		(placement
			(enabled no)
			(sheetname "")
		)
		(fill yes
			(thermal_gap 0.5)
			(thermal_bridge_width 0.5)
			(island_removal_mode 0)
		)
		(polygon
			(pts
				(arc
					(start 119.485156 -217.878406)
					(mid 118.832376 -217.878406)
					(end 119.485156 -217.878406)
				)
			)
		)
	)
	(zone
		(layers "B.Cu" "In6.Cu" "In11.Cu" "In13.Cu" "In15.Cu")
		(hatch none 0.5)
		(connect_pads
			(clearance 0)
		)
		(min_thickness 0.25)
		(keepout
			(tracks not_allowed)
			(vias allowed)
			(pads allowed)
			(copperpour not_allowed)
			(footprints allowed)
		)
		(placement
			(enabled no)
			(sheetname "")
		)
		(fill yes
			(thermal_gap 0.5)
			(thermal_bridge_width 0.5)
			(island_removal_mode 0)
		)
		(polygon
			(pts
				(arc
					(start 107.267756 -217.878406)
					(mid 106.614976 -217.878406)
					(end 107.267756 -217.878406)
				)
			)
		)
	)
	(zone
		(layers "B.Cu" "In6.Cu" "In11.Cu" "In13.Cu" "In15.Cu")
		(hatch none 0.5)
		(connect_pads
			(clearance 0)
		)
		(min_thickness 0.25)
		(keepout
			(tracks not_allowed)
			(vias allowed)
			(pads allowed)
			(copperpour not_allowed)
			(footprints allowed)
		)
		(placement
			(enabled no)
			(sheetname "")
		)
		(fill yes
			(thermal_gap 0.5)
			(thermal_bridge_width 0.5)
			(island_removal_mode 0)
		)
		(polygon
			(pts
				(arc
					(start 421.062404 -198.166736)
					(mid 420.409624 -198.166736)
					(end 421.062404 -198.166736)
				)
			)
		)
	)
	(zone
		(layers "B.Cu" "In6.Cu" "In11.Cu" "In13.Cu" "In15.Cu")
		(hatch none 0.5)
		(connect_pads
			(clearance 0)
		)
		(min_thickness 0.25)
		(keepout
			(tracks not_allowed)
			(vias allowed)
			(pads allowed)
			(copperpour not_allowed)
			(footprints allowed)
		)
		(placement
			(enabled no)
			(sheetname "")
		)
		(fill yes
			(thermal_gap 0.5)
			(thermal_bridge_width 0.5)
			(island_removal_mode 0)
		)
		(polygon
			(pts
				(arc
					(start 124.293884 -289.807142)
					(mid 123.641104 -289.807142)
					(end 124.293884 -289.807142)
				)
			)
		)
	)
	(zone
		(layers "B.Cu" "In6.Cu" "In11.Cu" "In13.Cu" "In15.Cu")
		(hatch none 0.5)
		(connect_pads
			(clearance 0)
		)
		(min_thickness 0.25)
		(keepout
			(tracks not_allowed)
			(vias allowed)
			(pads allowed)
			(copperpour not_allowed)
			(footprints allowed)
		)
		(placement
			(enabled no)
			(sheetname "")
		)
		(fill yes
			(thermal_gap 0.5)
			(thermal_bridge_width 0.5)
			(island_removal_mode 0)
		)
		(polygon
			(pts
				(arc
					(start 380.222252 -264.50036)
					(mid 379.569472 -264.50036)
					(end 380.222252 -264.50036)
				)
			)
		)
	)
	(zone
		(layers "B.Cu" "In6.Cu" "In11.Cu" "In13.Cu" "In15.Cu")
		(hatch none 0.5)
		(connect_pads
			(clearance 0)
		)
		(min_thickness 0.25)
		(keepout
			(tracks not_allowed)
			(vias allowed)
			(pads allowed)
			(copperpour not_allowed)
			(footprints allowed)
		)
		(placement
			(enabled no)
			(sheetname "")
		)
		(fill yes
			(thermal_gap 0.5)
			(thermal_bridge_width 0.5)
			(island_removal_mode 0)
		)
		(polygon
			(pts
				(arc
					(start 128.413002 -217.064336)
					(mid 127.760222 -217.064336)
					(end 128.413002 -217.064336)
				)
			)
		)
	)
	(zone
		(layers "B.Cu" "In6.Cu" "In11.Cu" "In13.Cu" "In15.Cu")
		(hatch none 0.5)
		(connect_pads
			(clearance 0)
		)
		(min_thickness 0.25)
		(keepout
			(tracks not_allowed)
			(vias allowed)
			(pads allowed)
			(copperpour not_allowed)
			(footprints allowed)
		)
		(placement
			(enabled no)
			(sheetname "")
		)
		(fill yes
			(thermal_gap 0.5)
			(thermal_bridge_width 0.5)
			(island_removal_mode 0)
		)
		(polygon
			(pts
				(arc
					(start 342.630252 -262.872474)
					(mid 341.977472 -262.872474)
					(end 342.630252 -262.872474)
				)
			)
		)
	)
	(zone
		(layers "B.Cu" "In6.Cu" "In11.Cu" "In13.Cu" "In15.Cu")
		(hatch none 0.5)
		(connect_pads
			(clearance 0)
		)
		(min_thickness 0.25)
		(keepout
			(tracks not_allowed)
			(vias allowed)
			(pads allowed)
			(copperpour not_allowed)
			(footprints allowed)
		)
		(placement
			(enabled no)
			(sheetname "")
		)
		(fill yes
			(thermal_gap 0.5)
			(thermal_bridge_width 0.5)
			(island_removal_mode 0)
		)
		(polygon
			(pts
				(arc
					(start 36.303204 -246.616728)
					(mid 35.650424 -246.616728)
					(end 36.303204 -246.616728)
				)
			)
		)
	)
	(zone
		(layers "B.Cu" "In6.Cu" "In11.Cu" "In13.Cu" "In15.Cu")
		(hatch none 0.5)
		(connect_pads
			(clearance 0)
		)
		(min_thickness 0.25)
		(keepout
			(tracks not_allowed)
			(vias allowed)
			(pads allowed)
			(copperpour not_allowed)
			(footprints allowed)
		)
		(placement
			(enabled no)
			(sheetname "")
		)
		(fill yes
			(thermal_gap 0.5)
			(thermal_bridge_width 0.5)
			(island_removal_mode 0)
		)
		(polygon
			(pts
				(arc
					(start 380.11227 -247.992138)
					(mid 379.45949 -247.992138)
					(end 380.11227 -247.992138)
				)
			)
		)
	)
	(zone
		(layers "B.Cu" "In6.Cu" "In11.Cu" "In13.Cu" "In15.Cu")
		(hatch none 0.5)
		(connect_pads
			(clearance 0)
		)
		(min_thickness 0.25)
		(keepout
			(tracks not_allowed)
			(vias allowed)
			(pads allowed)
			(copperpour not_allowed)
			(footprints allowed)
		)
		(placement
			(enabled no)
			(sheetname "")
		)
		(fill yes
			(thermal_gap 0.5)
			(thermal_bridge_width 0.5)
			(island_removal_mode 0)
		)
		(polygon
			(pts
				(arc
					(start 363.19587 -217.064336)
					(mid 362.54309 -217.064336)
					(end 363.19587 -217.064336)
				)
			)
		)
	)
	(zone
		(layers "B.Cu" "In6.Cu" "In11.Cu" "In13.Cu" "In15.Cu")
		(hatch none 0.5)
		(connect_pads
			(clearance 0)
		)
		(min_thickness 0.25)
		(keepout
			(tracks not_allowed)
			(vias allowed)
			(pads allowed)
			(copperpour not_allowed)
			(footprints allowed)
		)
		(placement
			(enabled no)
			(sheetname "")
		)
		(fill yes
			(thermal_gap 0.5)
			(thermal_bridge_width 0.5)
			(island_removal_mode 0)
		)
		(polygon
			(pts
				(arc
					(start 93.170756 -217.878406)
					(mid 92.517976 -217.878406)
					(end 93.170756 -217.878406)
				)
			)
		)
	)
	(zone
		(layers "B.Cu" "In6.Cu" "In11.Cu" "In13.Cu" "In15.Cu")
		(hatch none 0.5)
		(connect_pads
			(clearance 0)
		)
		(min_thickness 0.25)
		(keepout
			(tracks not_allowed)
			(vias allowed)
			(pads allowed)
			(copperpour not_allowed)
			(footprints allowed)
		)
		(placement
			(enabled no)
			(sheetname "")
		)
		(fill yes
			(thermal_gap 0.5)
			(thermal_bridge_width 0.5)
			(island_removal_mode 0)
		)
		(polygon
			(pts
				(arc
					(start 436.150004 -237.266734)
					(mid 435.497224 -237.266734)
					(end 436.150004 -237.266734)
				)
			)
		)
	)
	(zone
		(layers "B.Cu" "In6.Cu" "In11.Cu" "In13.Cu" "In15.Cu")
		(hatch none 0.5)
		(connect_pads
			(clearance 0)
		)
		(min_thickness 0.25)
		(keepout
			(tracks not_allowed)
			(vias allowed)
			(pads allowed)
			(copperpour not_allowed)
			(footprints allowed)
		)
		(placement
			(enabled no)
			(sheetname "")
		)
		(fill yes
			(thermal_gap 0.5)
			(thermal_bridge_width 0.5)
			(island_removal_mode 0)
		)
		(polygon
			(pts
				(arc
					(start 97.399602 -218.692222)
					(mid 96.746822 -218.692222)
					(end 97.399602 -218.692222)
				)
			)
		)
	)
	(zone
		(layers "B.Cu" "In6.Cu" "In11.Cu" "In13.Cu" "In15.Cu")
		(hatch none 0.5)
		(connect_pads
			(clearance 0)
		)
		(min_thickness 0.25)
		(keepout
			(tracks not_allowed)
			(vias allowed)
			(pads allowed)
			(copperpour not_allowed)
			(footprints allowed)
		)
		(placement
			(enabled no)
			(sheetname "")
		)
		(fill yes
			(thermal_gap 0.5)
			(thermal_bridge_width 0.5)
			(island_removal_mode 0)
		)
		(polygon
			(pts
				(arc
					(start 188.209936 -210.066636)
					(mid 187.557156 -210.066636)
					(end 188.209936 -210.066636)
				)
			)
		)
	)
	(zone
		(layers "B.Cu" "In6.Cu" "In11.Cu" "In13.Cu" "In15.Cu")
		(hatch none 0.5)
		(connect_pads
			(clearance 0)
		)
		(min_thickness 0.25)
		(keepout
			(tracks not_allowed)
			(vias allowed)
			(pads allowed)
			(copperpour not_allowed)
			(footprints allowed)
		)
		(placement
			(enabled no)
			(sheetname "")
		)
		(fill yes
			(thermal_gap 0.5)
			(thermal_bridge_width 0.5)
			(island_removal_mode 0)
		)
		(polygon
			(pts
				(arc
					(start 295.230804 -196.466714)
					(mid 294.578024 -196.466714)
					(end 295.230804 -196.466714)
				)
			)
		)
	)
	(zone
		(layers "B.Cu" "In6.Cu" "In11.Cu" "In13.Cu" "In15.Cu")
		(hatch none 0.5)
		(connect_pads
			(clearance 0)
		)
		(min_thickness 0.25)
		(keepout
			(tracks not_allowed)
			(vias allowed)
			(pads allowed)
			(copperpour not_allowed)
			(footprints allowed)
		)
		(placement
			(enabled no)
			(sheetname "")
		)
		(fill yes
			(thermal_gap 0.5)
			(thermal_bridge_width 0.5)
			(island_removal_mode 0)
		)
		(polygon
			(pts
				(arc
					(start 284.243272 -251.716794)
					(mid 283.590492 -251.716794)
					(end 284.243272 -251.716794)
				)
			)
		)
	)
	(zone
		(layers "B.Cu" "In6.Cu" "In11.Cu" "In13.Cu" "In15.Cu")
		(hatch none 0.5)
		(connect_pads
			(clearance 0)
		)
		(min_thickness 0.25)
		(keepout
			(tracks not_allowed)
			(vias allowed)
			(pads allowed)
			(copperpour not_allowed)
			(footprints allowed)
		)
		(placement
			(enabled no)
			(sheetname "")
		)
		(fill yes
			(thermal_gap 0.5)
			(thermal_bridge_width 0.5)
			(island_removal_mode 0)
		)
		(polygon
			(pts
				(arc
					(start 262.589772 5.895594)
					(mid 261.886192 5.895594)
					(end 262.589772 5.895594)
				)
			)
		)
	)
	(zone
		(layers "B.Cu" "In6.Cu" "In11.Cu" "In13.Cu" "In15.Cu")
		(hatch none 0.5)
		(connect_pads
			(clearance 0)
		)
		(min_thickness 0.25)
		(keepout
			(tracks not_allowed)
			(vias allowed)
			(pads allowed)
			(copperpour not_allowed)
			(footprints allowed)
		)
		(placement
			(enabled no)
			(sheetname "")
		)
		(fill yes
			(thermal_gap 0.5)
			(thermal_bridge_width 0.5)
			(island_removal_mode 0)
		)
		(polygon
			(pts
				(arc
					(start 421.062404 -284.866588)
					(mid 420.409624 -284.866588)
					(end 421.062404 -284.866588)
				)
			)
		)
	)
	(zone
		(layers "B.Cu" "In6.Cu" "In11.Cu" "In13.Cu" "In15.Cu")
		(hatch none 0.5)
		(connect_pads
			(clearance 0)
		)
		(min_thickness 0.25)
		(keepout
			(tracks not_allowed)
			(vias allowed)
			(pads allowed)
			(copperpour not_allowed)
			(footprints allowed)
		)
		(placement
			(enabled no)
			(sheetname "")
		)
		(fill yes
			(thermal_gap 0.5)
			(thermal_bridge_width 0.5)
			(island_removal_mode 0)
		)
		(polygon
			(pts
				(arc
					(start 341.690452 -267.755878)
					(mid 341.037672 -267.755878)
					(end 341.690452 -267.755878)
				)
			)
		)
	)
	(zone
		(layers "B.Cu" "In6.Cu" "In11.Cu" "In13.Cu" "In15.Cu")
		(hatch none 0.5)
		(connect_pads
			(clearance 0)
		)
		(min_thickness 0.25)
		(keepout
			(tracks not_allowed)
			(vias allowed)
			(pads allowed)
			(copperpour not_allowed)
			(footprints allowed)
		)
		(placement
			(enabled no)
			(sheetname "")
		)
		(fill yes
			(thermal_gap 0.5)
			(thermal_bridge_width 0.5)
			(island_removal_mode 0)
		)
		(polygon
			(pts
				(arc
					(start 284.243272 -263.616694)
					(mid 283.590492 -263.616694)
					(end 284.243272 -263.616694)
				)
			)
		)
	)
	(zone
		(layers "B.Cu" "In6.Cu" "In11.Cu" "In13.Cu" "In15.Cu")
		(hatch none 0.5)
		(connect_pads
			(clearance 0)
		)
		(min_thickness 0.25)
		(keepout
			(tracks not_allowed)
			(vias allowed)
			(pads allowed)
			(copperpour not_allowed)
			(footprints allowed)
		)
		(placement
			(enabled no)
			(sheetname "")
		)
		(fill yes
			(thermal_gap 0.5)
			(thermal_bridge_width 0.5)
			(island_removal_mode 0)
		)
		(polygon
			(pts
				(arc
					(start 369.77447 -218.692222)
					(mid 369.12169 -218.692222)
					(end 369.77447 -218.692222)
				)
			)
		)
	)
	(zone
		(layers "B.Cu" "In6.Cu" "In11.Cu" "In13.Cu" "In15.Cu")
		(hatch none 0.5)
		(connect_pads
			(clearance 0)
		)
		(min_thickness 0.25)
		(keepout
			(tracks not_allowed)
			(vias allowed)
			(pads allowed)
			(copperpour not_allowed)
			(footprints allowed)
		)
		(placement
			(enabled no)
			(sheetname "")
		)
		(fill yes
			(thermal_gap 0.5)
			(thermal_bridge_width 0.5)
			(island_removal_mode 0)
		)
		(polygon
			(pts
				(arc
					(start 342.160606 -278.336502)
					(mid 341.507826 -278.336502)
					(end 342.160606 -278.336502)
				)
			)
		)
	)
	(zone
		(layers "B.Cu" "In6.Cu" "In11.Cu" "In13.Cu" "In15.Cu")
		(hatch none 0.5)
		(connect_pads
			(clearance 0)
		)
		(min_thickness 0.25)
		(keepout
			(tracks not_allowed)
			(vias allowed)
			(pads allowed)
			(copperpour not_allowed)
			(footprints allowed)
		)
		(placement
			(enabled no)
			(sheetname "")
		)
		(fill yes
			(thermal_gap 0.5)
			(thermal_bridge_width 0.5)
			(island_removal_mode 0)
		)
		(polygon
			(pts
				(arc
					(start 377.873006 -275.08073)
					(mid 377.220226 -275.08073)
					(end 377.873006 -275.08073)
				)
			)
		)
	)
	(zone
		(layers "B.Cu" "In6.Cu" "In11.Cu" "In13.Cu" "In15.Cu")
		(hatch none 0.5)
		(connect_pads
			(clearance 0)
		)
		(min_thickness 0.25)
		(keepout
			(tracks not_allowed)
			(vias allowed)
			(pads allowed)
			(copperpour not_allowed)
			(footprints allowed)
		)
		(placement
			(enabled no)
			(sheetname "")
		)
		(fill yes
			(thermal_gap 0.5)
			(thermal_bridge_width 0.5)
			(island_removal_mode 0)
		)
		(polygon
			(pts
				(arc
					(start 126.533402 -249.620024)
					(mid 125.880622 -249.620024)
					(end 126.533402 -249.620024)
				)
			)
		)
	)
	(zone
		(layers "B.Cu" "In6.Cu" "In11.Cu" "In13.Cu" "In15.Cu")
		(hatch none 0.5)
		(connect_pads
			(clearance 0)
		)
		(min_thickness 0.25)
		(keepout
			(tracks not_allowed)
			(vias allowed)
			(pads allowed)
			(copperpour not_allowed)
			(footprints allowed)
		)
		(placement
			(enabled no)
			(sheetname "")
		)
		(fill yes
			(thermal_gap 0.5)
			(thermal_bridge_width 0.5)
			(island_removal_mode 0)
		)
		(polygon
			(pts
				(arc
					(start 192.310004 -296.766742)
					(mid 191.657224 -296.766742)
					(end 192.310004 -296.766742)
				)
			)
		)
	)
	(zone
		(layers "B.Cu" "In6.Cu" "In11.Cu" "In13.Cu" "In15.Cu")
		(hatch none 0.5)
		(connect_pads
			(clearance 0)
		)
		(min_thickness 0.25)
		(keepout
			(tracks not_allowed)
			(vias allowed)
			(pads allowed)
			(copperpour not_allowed)
			(footprints allowed)
		)
		(placement
			(enabled no)
			(sheetname "")
		)
		(fill yes
			(thermal_gap 0.5)
			(thermal_bridge_width 0.5)
			(island_removal_mode 0)
		)
		(polygon
			(pts
				(arc
					(start 376.933206 -257.175254)
					(mid 376.280426 -257.175254)
					(end 376.933206 -257.175254)
				)
			)
		)
	)
	(zone
		(layers "B.Cu" "In6.Cu" "In11.Cu" "In13.Cu" "In15.Cu")
		(hatch none 0.5)
		(connect_pads
			(clearance 0)
		)
		(min_thickness 0.25)
		(keepout
			(tracks not_allowed)
			(vias allowed)
			(pads allowed)
			(copperpour not_allowed)
			(footprints allowed)
		)
		(placement
			(enabled no)
			(sheetname "")
		)
		(fill yes
			(thermal_gap 0.5)
			(thermal_bridge_width 0.5)
			(island_removal_mode 0)
		)
		(polygon
			(pts
				(arc
					(start 188.209936 -207.51673)
					(mid 187.557156 -207.51673)
					(end 188.209936 -207.51673)
				)
			)
		)
	)
	(zone
		(layers "B.Cu" "In6.Cu" "In11.Cu" "In13.Cu" "In15.Cu")
		(hatch none 0.5)
		(connect_pads
			(clearance 0)
		)
		(min_thickness 0.25)
		(keepout
			(tracks not_allowed)
			(vias allowed)
			(pads allowed)
			(copperpour not_allowed)
			(footprints allowed)
		)
		(placement
			(enabled no)
			(sheetname "")
		)
		(fill yes
			(thermal_gap 0.5)
			(thermal_bridge_width 0.5)
			(island_removal_mode 0)
		)
		(polygon
			(pts
				(arc
					(start 128.522984 -259.616956)
					(mid 127.870204 -259.616956)
					(end 128.522984 -259.616956)
				)
			)
		)
	)
	(zone
		(layers "B.Cu" "In6.Cu" "In11.Cu" "In13.Cu" "In15.Cu")
		(hatch none 0.5)
		(connect_pads
			(clearance 0)
		)
		(min_thickness 0.25)
		(keepout
			(tracks not_allowed)
			(vias allowed)
			(pads allowed)
			(copperpour not_allowed)
			(footprints allowed)
		)
		(placement
			(enabled no)
			(sheetname "")
		)
		(fill yes
			(thermal_gap 0.5)
			(thermal_bridge_width 0.5)
			(island_removal_mode 0)
		)
		(polygon
			(pts
				(arc
					(start 36.303204 -244.916706)
					(mid 35.650424 -244.916706)
					(end 36.303204 -244.916706)
				)
			)
		)
	)
	(zone
		(layers "B.Cu" "In6.Cu" "In11.Cu" "In13.Cu" "In15.Cu")
		(hatch none 0.5)
		(connect_pads
			(clearance 0)
		)
		(min_thickness 0.25)
		(keepout
			(tracks not_allowed)
			(vias allowed)
			(pads allowed)
			(copperpour not_allowed)
			(footprints allowed)
		)
		(placement
			(enabled no)
			(sheetname "")
		)
		(fill yes
			(thermal_gap 0.5)
			(thermal_bridge_width 0.5)
			(island_removal_mode 0)
		)
		(polygon
			(pts
				(arc
					(start 340.750652 -272.639282)
					(mid 340.097872 -272.639282)
					(end 340.750652 -272.639282)
				)
			)
		)
	)
	(zone
		(layers "B.Cu" "In6.Cu" "In11.Cu" "In13.Cu" "In15.Cu")
		(hatch none 0.5)
		(connect_pads
			(clearance 0)
		)
		(min_thickness 0.25)
		(keepout
			(tracks not_allowed)
			(vias allowed)
			(pads allowed)
			(copperpour not_allowed)
			(footprints allowed)
		)
		(placement
			(enabled no)
			(sheetname "")
		)
		(fill yes
			(thermal_gap 0.5)
			(thermal_bridge_width 0.5)
			(island_removal_mode 0)
		)
		(polygon
			(pts
				(arc
					(start 284.243272 -240.666778)
					(mid 283.590492 -240.666778)
					(end 284.243272 -240.666778)
				)
			)
		)
	)
	(zone
		(layers "B.Cu" "In6.Cu" "In11.Cu" "In13.Cu" "In15.Cu")
		(hatch none 0.5)
		(connect_pads
			(clearance 0)
		)
		(min_thickness 0.25)
		(keepout
			(tracks not_allowed)
			(vias allowed)
			(pads allowed)
			(copperpour not_allowed)
			(footprints allowed)
		)
		(placement
			(enabled no)
			(sheetname "")
		)
		(fill yes
			(thermal_gap 0.5)
			(thermal_bridge_width 0.5)
			(island_removal_mode 0)
		)
		(polygon
			(pts
				(arc
					(start 436.150004 -249.166634)
					(mid 435.497224 -249.166634)
					(end 436.150004 -249.166634)
				)
			)
		)
	)
	(zone
		(layers "B.Cu" "In6.Cu" "In11.Cu" "In13.Cu" "In15.Cu")
		(hatch none 0.5)
		(connect_pads
			(clearance 0)
		)
		(min_thickness 0.25)
		(keepout
			(tracks not_allowed)
			(vias allowed)
			(pads allowed)
			(copperpour not_allowed)
			(footprints allowed)
		)
		(placement
			(enabled no)
			(sheetname "")
		)
		(fill yes
			(thermal_gap 0.5)
			(thermal_bridge_width 0.5)
			(island_removal_mode 0)
		)
		(polygon
			(pts
				(arc
					(start 344.689684 -47.040292)
					(mid 344.036904 -47.040292)
					(end 344.689684 -47.040292)
				)
			)
		)
	)
	(zone
		(layers "B.Cu" "In6.Cu" "In11.Cu" "In13.Cu" "In15.Cu")
		(hatch none 0.5)
		(connect_pads
			(clearance 0)
		)
		(min_thickness 0.25)
		(keepout
			(tracks not_allowed)
			(vias allowed)
			(pads allowed)
			(copperpour not_allowed)
			(footprints allowed)
		)
		(placement
			(enabled no)
			(sheetname "")
		)
		(fill yes
			(thermal_gap 0.5)
			(thermal_bridge_width 0.5)
			(island_removal_mode 0)
		)
		(polygon
			(pts
				(arc
					(start 342.050624 -234.15625)
					(mid 341.397844 -234.15625)
					(end 342.050624 -234.15625)
				)
			)
		)
	)
	(zone
		(layers "B.Cu" "In6.Cu" "In11.Cu" "In13.Cu" "In15.Cu")
		(hatch none 0.5)
		(connect_pads
			(clearance 0)
		)
		(min_thickness 0.25)
		(keepout
			(tracks not_allowed)
			(vias allowed)
			(pads allowed)
			(copperpour not_allowed)
			(footprints allowed)
		)
		(placement
			(enabled no)
			(sheetname "")
		)
		(fill yes
			(thermal_gap 0.5)
			(thermal_bridge_width 0.5)
			(island_removal_mode 0)
		)
		(polygon
			(pts
				(arc
					(start 440.250072 -234.716574)
					(mid 439.597292 -234.716574)
					(end 440.250072 -234.716574)
				)
			)
		)
	)
	(zone
		(layers "B.Cu" "In6.Cu" "In11.Cu" "In13.Cu" "In15.Cu")
		(hatch none 0.5)
		(connect_pads
			(clearance 0)
		)
		(min_thickness 0.25)
		(keepout
			(tracks not_allowed)
			(vias allowed)
			(pads allowed)
			(copperpour not_allowed)
			(footprints allowed)
		)
		(placement
			(enabled no)
			(sheetname "")
		)
		(fill yes
			(thermal_gap 0.5)
			(thermal_bridge_width 0.5)
			(island_removal_mode 0)
		)
		(polygon
			(pts
				(arc
					(start 192.310004 -206.666592)
					(mid 191.657224 -206.666592)
					(end 192.310004 -206.666592)
				)
			)
		)
	)
	(zone
		(layers "B.Cu" "In6.Cu" "In11.Cu" "In13.Cu" "In15.Cu")
		(hatch none 0.5)
		(connect_pads
			(clearance 0)
		)
		(min_thickness 0.25)
		(keepout
			(tracks not_allowed)
			(vias allowed)
			(pads allowed)
			(copperpour not_allowed)
			(footprints allowed)
		)
		(placement
			(enabled no)
			(sheetname "")
		)
		(fill yes
			(thermal_gap 0.5)
			(thermal_bridge_width 0.5)
			(island_removal_mode 0)
		)
		(polygon
			(pts
				(arc
					(start 379.752606 -271.825212)
					(mid 379.099826 -271.825212)
					(end 379.752606 -271.825212)
				)
			)
		)
	)
	(zone
		(layers "B.Cu" "In6.Cu" "In11.Cu" "In13.Cu" "In15.Cu")
		(hatch none 0.5)
		(connect_pads
			(clearance 0)
		)
		(min_thickness 0.25)
		(keepout
			(tracks not_allowed)
			(vias allowed)
			(pads allowed)
			(copperpour not_allowed)
			(footprints allowed)
		)
		(placement
			(enabled no)
			(sheetname "")
		)
		(fill yes
			(thermal_gap 0.5)
			(thermal_bridge_width 0.5)
			(island_removal_mode 0)
		)
		(polygon
			(pts
				(arc
					(start 130.872738 -262.058658)
					(mid 130.219958 -262.058658)
					(end 130.872738 -262.058658)
				)
			)
		)
	)
	(zone
		(layers "B.Cu" "In6.Cu" "In11.Cu" "In13.Cu" "In15.Cu")
		(hatch none 0.5)
		(connect_pads
			(clearance 0)
		)
		(min_thickness 0.25)
		(keepout
			(tracks not_allowed)
			(vias allowed)
			(pads allowed)
			(copperpour not_allowed)
			(footprints allowed)
		)
		(placement
			(enabled no)
			(sheetname "")
		)
		(fill yes
			(thermal_gap 0.5)
			(thermal_bridge_width 0.5)
			(island_removal_mode 0)
		)
		(polygon
			(pts
				(arc
					(start 370.244624 -217.878406)
					(mid 369.591844 -217.878406)
					(end 370.244624 -217.878406)
				)
			)
		)
	)
	(zone
		(layers "B.Cu" "In6.Cu" "In11.Cu" "In13.Cu" "In15.Cu")
		(hatch none 0.5)
		(connect_pads
			(clearance 0)
		)
		(min_thickness 0.25)
		(keepout
			(tracks not_allowed)
			(vias allowed)
			(pads allowed)
			(copperpour not_allowed)
			(footprints allowed)
		)
		(placement
			(enabled no)
			(sheetname "")
		)
		(fill yes
			(thermal_gap 0.5)
			(thermal_bridge_width 0.5)
			(island_removal_mode 0)
		)
		(polygon
			(pts
				(arc
					(start 36.303204 -289.11677)
					(mid 35.650424 -289.11677)
					(end 36.303204 -289.11677)
				)
			)
		)
	)
	(zone
		(layers "B.Cu" "In6.Cu" "In11.Cu" "In13.Cu" "In15.Cu")
		(hatch none 0.5)
		(connect_pads
			(clearance 0)
		)
		(min_thickness 0.25)
		(keepout
			(tracks not_allowed)
			(vias allowed)
			(pads allowed)
			(copperpour not_allowed)
			(footprints allowed)
		)
		(placement
			(enabled no)
			(sheetname "")
		)
		(fill yes
			(thermal_gap 0.5)
			(thermal_bridge_width 0.5)
			(island_removal_mode 0)
		)
		(polygon
			(pts
				(arc
					(start 192.310004 -292.51656)
					(mid 191.657224 -292.51656)
					(end 192.310004 -292.51656)
				)
			)
		)
	)
	(zone
		(layers "B.Cu" "In6.Cu" "In11.Cu" "In13.Cu" "In15.Cu")
		(hatch none 0.5)
		(connect_pads
			(clearance 0)
		)
		(min_thickness 0.25)
		(keepout
			(tracks not_allowed)
			(vias allowed)
			(pads allowed)
			(copperpour not_allowed)
			(footprints allowed)
		)
		(placement
			(enabled no)
			(sheetname "")
		)
		(fill yes
			(thermal_gap 0.5)
			(thermal_bridge_width 0.5)
			(island_removal_mode 0)
		)
		(polygon
			(pts
				(arc
					(start 380.222252 -266.128246)
					(mid 379.569472 -266.128246)
					(end 380.222252 -266.128246)
				)
			)
		)
	)
	(zone
		(layers "B.Cu" "In6.Cu" "In11.Cu" "In13.Cu" "In15.Cu")
		(hatch none 0.5)
		(connect_pads
			(clearance 0)
		)
		(min_thickness 0.25)
		(keepout
			(tracks not_allowed)
			(vias allowed)
			(pads allowed)
			(copperpour not_allowed)
			(footprints allowed)
		)
		(placement
			(enabled no)
			(sheetname "")
		)
		(fill yes
			(thermal_gap 0.5)
			(thermal_bridge_width 0.5)
			(island_removal_mode 0)
		)
		(polygon
			(pts
				(arc
					(start 436.150004 -213.46668)
					(mid 435.497224 -213.46668)
					(end 436.150004 -213.46668)
				)
			)
		)
	)
	(zone
		(layers "B.Cu" "In6.Cu" "In11.Cu" "In13.Cu" "In15.Cu")
		(hatch none 0.5)
		(connect_pads
			(clearance 0)
		)
		(min_thickness 0.25)
		(keepout
			(tracks not_allowed)
			(vias allowed)
			(pads allowed)
			(copperpour not_allowed)
			(footprints allowed)
		)
		(placement
			(enabled no)
			(sheetname "")
		)
		(fill yes
			(thermal_gap 0.5)
			(thermal_bridge_width 0.5)
			(island_removal_mode 0)
		)
		(polygon
			(pts
				(arc
					(start 89.051638 -288.917126)
					(mid 88.398858 -288.917126)
					(end 89.051638 -288.917126)
				)
			)
		)
	)
	(zone
		(layers "B.Cu" "In6.Cu" "In11.Cu" "In13.Cu" "In15.Cu")
		(hatch none 0.5)
		(connect_pads
			(clearance 0)
		)
		(min_thickness 0.25)
		(keepout
			(tracks not_allowed)
			(vias allowed)
			(pads allowed)
			(copperpour not_allowed)
			(footprints allowed)
		)
		(placement
			(enabled no)
			(sheetname "")
		)
		(fill yes
			(thermal_gap 0.5)
			(thermal_bridge_width 0.5)
			(island_removal_mode 0)
		)
		(polygon
			(pts
				(arc
					(start 128.413002 -249.620024)
					(mid 127.760222 -249.620024)
					(end 128.413002 -249.620024)
				)
			)
		)
	)
	(zone
		(layers "B.Cu" "In6.Cu" "In11.Cu" "In13.Cu" "In15.Cu")
		(hatch none 0.5)
		(connect_pads
			(clearance 0)
		)
		(min_thickness 0.25)
		(keepout
			(tracks not_allowed)
			(vias allowed)
			(pads allowed)
			(copperpour not_allowed)
			(footprints allowed)
		)
		(placement
			(enabled no)
			(sheetname "")
		)
		(fill yes
			(thermal_gap 0.5)
			(thermal_bridge_width 0.5)
			(island_removal_mode 0)
		)
		(polygon
			(pts
				(arc
					(start 128.413002 -247.992138)
					(mid 127.760222 -247.992138)
					(end 128.413002 -247.992138)
				)
			)
		)
	)
	(zone
		(layers "B.Cu" "In6.Cu" "In11.Cu" "In13.Cu" "In15.Cu")
		(hatch none 0.5)
		(connect_pads
			(clearance 0)
		)
		(min_thickness 0.25)
		(keepout
			(tracks not_allowed)
			(vias allowed)
			(pads allowed)
			(copperpour not_allowed)
			(footprints allowed)
		)
		(placement
			(enabled no)
			(sheetname "")
		)
		(fill yes
			(thermal_gap 0.5)
			(thermal_bridge_width 0.5)
			(island_removal_mode 0)
		)
		(polygon
			(pts
				(arc
					(start 339.340952 -288.103056)
					(mid 338.688172 -288.103056)
					(end 339.340952 -288.103056)
				)
			)
		)
	)
	(zone
		(layers "B.Cu" "In6.Cu" "In11.Cu" "In13.Cu" "In15.Cu")
		(hatch none 0.5)
		(connect_pads
			(clearance 0)
		)
		(min_thickness 0.25)
		(keepout
			(tracks not_allowed)
			(vias allowed)
			(pads allowed)
			(copperpour not_allowed)
			(footprints allowed)
		)
		(placement
			(enabled no)
			(sheetname "")
		)
		(fill yes
			(thermal_gap 0.5)
			(thermal_bridge_width 0.5)
			(island_removal_mode 0)
		)
		(polygon
			(pts
				(arc
					(start 131.702556 -248.806208)
					(mid 131.049776 -248.806208)
					(end 131.702556 -248.806208)
				)
			)
		)
	)
	(zone
		(layers "B.Cu" "In6.Cu" "In11.Cu" "In13.Cu" "In15.Cu")
		(hatch none 0.5)
		(connect_pads
			(clearance 0)
		)
		(min_thickness 0.25)
		(keepout
			(tracks not_allowed)
			(vias allowed)
			(pads allowed)
			(copperpour not_allowed)
			(footprints allowed)
		)
		(placement
			(enabled no)
			(sheetname "")
		)
		(fill yes
			(thermal_gap 0.5)
			(thermal_bridge_width 0.5)
			(island_removal_mode 0)
		)
		(polygon
			(pts
				(arc
					(start 47.290736 -224.516696)
					(mid 46.637956 -224.516696)
					(end 47.290736 -224.516696)
				)
			)
		)
	)
	(zone
		(layers "B.Cu" "In6.Cu" "In11.Cu" "In13.Cu" "In15.Cu")
		(hatch none 0.5)
		(connect_pads
			(clearance 0)
		)
		(min_thickness 0.25)
		(keepout
			(tracks not_allowed)
			(vias allowed)
			(pads allowed)
			(copperpour not_allowed)
			(footprints allowed)
		)
		(placement
			(enabled no)
			(sheetname "")
		)
		(fill yes
			(thermal_gap 0.5)
			(thermal_bridge_width 0.5)
			(island_removal_mode 0)
		)
		(polygon
			(pts
				(arc
					(start 344.980006 -255.547622)
					(mid 344.327226 -255.547622)
					(end 344.980006 -255.547622)
				)
			)
		)
	)
	(zone
		(layers "B.Cu" "In6.Cu" "In11.Cu" "In13.Cu" "In15.Cu")
		(hatch none 0.5)
		(connect_pads
			(clearance 0)
		)
		(min_thickness 0.25)
		(keepout
			(tracks not_allowed)
			(vias allowed)
			(pads allowed)
			(copperpour not_allowed)
			(footprints allowed)
		)
		(placement
			(enabled no)
			(sheetname "")
		)
		(fill yes
			(thermal_gap 0.5)
			(thermal_bridge_width 0.5)
			(island_removal_mode 0)
		)
		(polygon
			(pts
				(arc
					(start 353.79787 -217.064336)
					(mid 353.14509 -217.064336)
					(end 353.79787 -217.064336)
				)
			)
		)
	)
	(zone
		(layers "B.Cu" "In6.Cu" "In11.Cu" "In13.Cu" "In15.Cu")
		(hatch none 0.5)
		(connect_pads
			(clearance 0)
		)
		(min_thickness 0.25)
		(keepout
			(tracks not_allowed)
			(vias allowed)
			(pads allowed)
			(copperpour not_allowed)
			(footprints allowed)
		)
		(placement
			(enabled no)
			(sheetname "")
		)
		(fill yes
			(thermal_gap 0.5)
			(thermal_bridge_width 0.5)
			(island_removal_mode 0)
		)
		(polygon
			(pts
				(arc
					(start 110.557056 -218.692222)
					(mid 109.904276 -218.692222)
					(end 110.557056 -218.692222)
				)
			)
		)
	)
	(zone
		(layers "B.Cu" "In6.Cu" "In11.Cu" "In13.Cu" "In15.Cu")
		(hatch none 0.5)
		(connect_pads
			(clearance 0)
		)
		(min_thickness 0.25)
		(keepout
			(tracks not_allowed)
			(vias allowed)
			(pads allowed)
			(copperpour not_allowed)
			(footprints allowed)
		)
		(placement
			(enabled no)
			(sheetname "")
		)
		(fill yes
			(thermal_gap 0.5)
			(thermal_bridge_width 0.5)
			(island_removal_mode 0)
		)
		(polygon
			(pts
				(arc
					(start 276.699472 -259.366766)
					(mid 276.046692 -259.366766)
					(end 276.699472 -259.366766)
				)
			)
		)
	)
	(zone
		(layers "B.Cu" "In6.Cu" "In11.Cu" "In13.Cu" "In15.Cu")
		(hatch none 0.5)
		(connect_pads
			(clearance 0)
		)
		(min_thickness 0.25)
		(keepout
			(tracks not_allowed)
			(vias allowed)
			(pads allowed)
			(copperpour not_allowed)
			(footprints allowed)
		)
		(placement
			(enabled no)
			(sheetname "")
		)
		(fill yes
			(thermal_gap 0.5)
			(thermal_bridge_width 0.5)
			(island_removal_mode 0)
		)
		(polygon
			(pts
				(arc
					(start 36.303204 -261.916672)
					(mid 35.650424 -261.916672)
					(end 36.303204 -261.916672)
				)
			)
		)
	)
	(zone
		(layers "B.Cu" "In6.Cu" "In11.Cu" "In13.Cu" "In15.Cu")
		(hatch none 0.5)
		(connect_pads
			(clearance 0)
		)
		(min_thickness 0.25)
		(keepout
			(tracks not_allowed)
			(vias allowed)
			(pads allowed)
			(copperpour not_allowed)
			(footprints allowed)
		)
		(placement
			(enabled no)
			(sheetname "")
		)
		(fill yes
			(thermal_gap 0.5)
			(thermal_bridge_width 0.5)
			(island_removal_mode 0)
		)
		(polygon
			(pts
				(arc
					(start 92.810584 -271.011396)
					(mid 92.157804 -271.011396)
					(end 92.810584 -271.011396)
				)
			)
		)
	)
	(zone
		(layers "B.Cu" "In6.Cu" "In11.Cu" "In13.Cu" "In15.Cu")
		(hatch none 0.5)
		(connect_pads
			(clearance 0)
		)
		(min_thickness 0.25)
		(keepout
			(tracks not_allowed)
			(vias allowed)
			(pads allowed)
			(copperpour not_allowed)
			(footprints allowed)
		)
		(placement
			(enabled no)
			(sheetname "")
		)
		(fill yes
			(thermal_gap 0.5)
			(thermal_bridge_width 0.5)
			(island_removal_mode 0)
		)
		(polygon
			(pts
				(arc
					(start 36.303204 -296.766742)
					(mid 35.650424 -296.766742)
					(end 36.303204 -296.766742)
				)
			)
		)
	)
	(zone
		(layers "B.Cu" "In6.Cu" "In11.Cu" "In13.Cu" "In15.Cu")
		(hatch none 0.5)
		(connect_pads
			(clearance 0)
		)
		(min_thickness 0.25)
		(keepout
			(tracks not_allowed)
			(vias allowed)
			(pads allowed)
			(copperpour not_allowed)
			(footprints allowed)
		)
		(placement
			(enabled no)
			(sheetname "")
		)
		(fill yes
			(thermal_gap 0.5)
			(thermal_bridge_width 0.5)
			(island_removal_mode 0)
		)
		(polygon
			(pts
				(arc
					(start 130.762756 -232.528364)
					(mid 130.109976 -232.528364)
					(end 130.762756 -232.528364)
				)
			)
		)
	)
	(zone
		(layers "B.Cu" "In6.Cu" "In11.Cu" "In13.Cu" "In15.Cu")
		(hatch none 0.5)
		(connect_pads
			(clearance 0)
		)
		(min_thickness 0.25)
		(keepout
			(tracks not_allowed)
			(vias allowed)
			(pads allowed)
			(copperpour not_allowed)
			(footprints allowed)
		)
		(placement
			(enabled no)
			(sheetname "")
		)
		(fill yes
			(thermal_gap 0.5)
			(thermal_bridge_width 0.5)
			(island_removal_mode 0)
		)
		(polygon
			(pts
				(arc
					(start 94.110556 -240.667286)
					(mid 93.457776 -240.667286)
					(end 94.110556 -240.667286)
				)
			)
		)
	)
	(zone
		(layers "B.Cu" "In6.Cu" "In11.Cu" "In13.Cu" "In15.Cu")
		(hatch none 0.5)
		(connect_pads
			(clearance 0)
		)
		(min_thickness 0.25)
		(keepout
			(tracks not_allowed)
			(vias allowed)
			(pads allowed)
			(copperpour not_allowed)
			(footprints allowed)
		)
		(placement
			(enabled no)
			(sheetname "")
		)
		(fill yes
			(thermal_gap 0.5)
			(thermal_bridge_width 0.5)
			(island_removal_mode 0)
		)
		(polygon
			(pts
				(arc
					(start 375.523506 -288.917126)
					(mid 374.870726 -288.917126)
					(end 375.523506 -288.917126)
				)
			)
		)
	)
	(zone
		(layers "B.Cu" "In6.Cu" "In11.Cu" "In13.Cu" "In15.Cu")
		(hatch none 0.5)
		(connect_pads
			(clearance 0)
		)
		(min_thickness 0.25)
		(keepout
			(tracks not_allowed)
			(vias allowed)
			(pads allowed)
			(copperpour not_allowed)
			(footprints allowed)
		)
		(placement
			(enabled no)
			(sheetname "")
		)
		(fill yes
			(thermal_gap 0.5)
			(thermal_bridge_width 0.5)
			(island_removal_mode 0)
		)
		(polygon
			(pts
				(arc
					(start 130.872738 -258.80314)
					(mid 130.219958 -258.80314)
					(end 130.872738 -258.80314)
				)
			)
		)
	)
	(zone
		(layers "B.Cu" "In6.Cu" "In11.Cu" "In13.Cu" "In15.Cu")
		(hatch none 0.5)
		(connect_pads
			(clearance 0)
		)
		(min_thickness 0.25)
		(keepout
			(tracks not_allowed)
			(vias allowed)
			(pads allowed)
			(copperpour not_allowed)
			(footprints allowed)
		)
		(placement
			(enabled no)
			(sheetname "")
		)
		(fill yes
			(thermal_gap 0.5)
			(thermal_bridge_width 0.5)
			(island_removal_mode 0)
		)
		(polygon
			(pts
				(arc
					(start 93.750638 -288.917126)
					(mid 93.097858 -288.917126)
					(end 93.750638 -288.917126)
				)
			)
		)
	)
	(zone
		(layers "B.Cu" "In6.Cu" "In11.Cu" "In13.Cu" "In15.Cu")
		(hatch none 0.5)
		(connect_pads
			(clearance 0)
		)
		(min_thickness 0.25)
		(keepout
			(tracks not_allowed)
			(vias allowed)
			(pads allowed)
			(copperpour not_allowed)
			(footprints allowed)
		)
		(placement
			(enabled no)
			(sheetname "")
		)
		(fill yes
			(thermal_gap 0.5)
			(thermal_bridge_width 0.5)
			(island_removal_mode 0)
		)
		(polygon
			(pts
				(arc
					(start 130.402584 -274.266914)
					(mid 129.749804 -274.266914)
					(end 130.402584 -274.266914)
				)
			)
		)
	)
	(zone
		(layers "B.Cu" "In6.Cu" "In11.Cu" "In13.Cu" "In15.Cu")
		(hatch none 0.5)
		(connect_pads
			(clearance 0)
		)
		(min_thickness 0.25)
		(keepout
			(tracks not_allowed)
			(vias allowed)
			(pads allowed)
			(copperpour not_allowed)
			(footprints allowed)
		)
		(placement
			(enabled no)
			(sheetname "")
		)
		(fill yes
			(thermal_gap 0.5)
			(thermal_bridge_width 0.5)
			(island_removal_mode 0)
		)
		(polygon
			(pts
				(arc
					(start 376.94489 5.031994)
					(mid 376.24131 5.031994)
					(end 376.94489 5.031994)
				)
			)
		)
	)
	(zone
		(layers "B.Cu" "In6.Cu" "In11.Cu" "In13.Cu" "In15.Cu")
		(hatch none 0.5)
		(connect_pads
			(clearance 0)
		)
		(min_thickness 0.25)
		(keepout
			(tracks not_allowed)
			(vias allowed)
			(pads allowed)
			(copperpour not_allowed)
			(footprints allowed)
		)
		(placement
			(enabled no)
			(sheetname "")
		)
		(fill yes
			(thermal_gap 0.5)
			(thermal_bridge_width 0.5)
			(island_removal_mode 0)
		)
		(polygon
			(pts
				(arc
					(start 32.203136 -312.066686)
					(mid 31.550356 -312.066686)
					(end 32.203136 -312.066686)
				)
			)
		)
	)
	(zone
		(layers "B.Cu" "In6.Cu" "In11.Cu" "In13.Cu" "In15.Cu")
		(hatch none 0.5)
		(connect_pads
			(clearance 0)
		)
		(min_thickness 0.25)
		(keepout
			(tracks not_allowed)
			(vias allowed)
			(pads allowed)
			(copperpour not_allowed)
			(footprints allowed)
		)
		(placement
			(enabled no)
			(sheetname "")
		)
		(fill yes
			(thermal_gap 0.5)
			(thermal_bridge_width 0.5)
			(island_removal_mode 0)
		)
		(polygon
			(pts
				(arc
					(start 188.209936 -314.616592)
					(mid 187.557156 -314.616592)
					(end 188.209936 -314.616592)
				)
			)
		)
	)
	(zone
		(layers "B.Cu" "In6.Cu" "In11.Cu" "In13.Cu" "In15.Cu")
		(hatch none 0.5)
		(connect_pads
			(clearance 0)
		)
		(min_thickness 0.25)
		(keepout
			(tracks not_allowed)
			(vias allowed)
			(pads allowed)
			(copperpour not_allowed)
			(footprints allowed)
		)
		(placement
			(enabled no)
			(sheetname "")
		)
		(fill yes
			(thermal_gap 0.5)
			(thermal_bridge_width 0.5)
			(island_removal_mode 0)
		)
		(polygon
			(pts
				(arc
					(start 352.388424 -217.878406)
					(mid 351.735644 -217.878406)
					(end 352.388424 -217.878406)
				)
			)
		)
	)
	(zone
		(layers "B.Cu" "In6.Cu" "In11.Cu" "In13.Cu" "In15.Cu")
		(hatch none 0.5)
		(connect_pads
			(clearance 0)
		)
		(min_thickness 0.25)
		(keepout
			(tracks not_allowed)
			(vias allowed)
			(pads allowed)
			(copperpour not_allowed)
			(footprints allowed)
		)
		(placement
			(enabled no)
			(sheetname "")
		)
		(fill yes
			(thermal_gap 0.5)
			(thermal_bridge_width 0.5)
			(island_removal_mode 0)
		)
		(polygon
			(pts
				(arc
					(start 36.303204 -208.366614)
					(mid 35.650424 -208.366614)
					(end 36.303204 -208.366614)
				)
			)
		)
	)
	(zone
		(layers "B.Cu" "In6.Cu" "In11.Cu" "In13.Cu" "In15.Cu")
		(hatch none 0.5)
		(connect_pads
			(clearance 0)
		)
		(min_thickness 0.25)
		(keepout
			(tracks not_allowed)
			(vias allowed)
			(pads allowed)
			(copperpour not_allowed)
			(footprints allowed)
		)
		(placement
			(enabled no)
			(sheetname "")
		)
		(fill yes
			(thermal_gap 0.5)
			(thermal_bridge_width 0.5)
			(island_removal_mode 0)
		)
		(polygon
			(pts
				(arc
					(start 377.763024 -232.528364)
					(mid 377.110244 -232.528364)
					(end 377.763024 -232.528364)
				)
			)
		)
	)
	(zone
		(layers "B.Cu" "In6.Cu" "In11.Cu" "In13.Cu" "In15.Cu")
		(hatch none 0.5)
		(connect_pads
			(clearance 0)
		)
		(min_thickness 0.25)
		(keepout
			(tracks not_allowed)
			(vias allowed)
			(pads allowed)
			(copperpour not_allowed)
			(footprints allowed)
		)
		(placement
			(enabled no)
			(sheetname "")
		)
		(fill yes
			(thermal_gap 0.5)
			(thermal_bridge_width 0.5)
			(island_removal_mode 0)
		)
		(polygon
			(pts
				(arc
					(start 192.310004 -209.216752)
					(mid 191.657224 -209.216752)
					(end 192.310004 -209.216752)
				)
			)
		)
	)
	(zone
		(layers "B.Cu" "In6.Cu" "In11.Cu" "In13.Cu" "In15.Cu")
		(hatch none 0.5)
		(connect_pads
			(clearance 0)
		)
		(min_thickness 0.25)
		(keepout
			(tracks not_allowed)
			(vias allowed)
			(pads allowed)
			(copperpour not_allowed)
			(footprints allowed)
		)
		(placement
			(enabled no)
			(sheetname "")
		)
		(fill yes
			(thermal_gap 0.5)
			(thermal_bridge_width 0.5)
			(island_removal_mode 0)
		)
		(polygon
			(pts
				(arc
					(start 284.243272 -238.966756)
					(mid 283.590492 -238.966756)
					(end 284.243272 -238.966756)
				)
			)
		)
	)
	(zone
		(layers "B.Cu" "In6.Cu" "In11.Cu" "In13.Cu" "In15.Cu")
		(hatch none 0.5)
		(connect_pads
			(clearance 0)
		)
		(min_thickness 0.25)
		(keepout
			(tracks not_allowed)
			(vias allowed)
			(pads allowed)
			(copperpour not_allowed)
			(footprints allowed)
		)
		(placement
			(enabled no)
			(sheetname "")
		)
		(fill yes
			(thermal_gap 0.5)
			(thermal_bridge_width 0.5)
			(island_removal_mode 0)
		)
		(polygon
			(pts
				(arc
					(start 440.250072 -315.46673)
					(mid 439.597292 -315.46673)
					(end 440.250072 -315.46673)
				)
			)
		)
	)
	(zone
		(layers "B.Cu" "In6.Cu" "In11.Cu" "In13.Cu" "In15.Cu")
		(hatch none 0.5)
		(connect_pads
			(clearance 0)
		)
		(min_thickness 0.25)
		(keepout
			(tracks not_allowed)
			(vias allowed)
			(pads allowed)
			(copperpour not_allowed)
			(footprints allowed)
		)
		(placement
			(enabled no)
			(sheetname "")
		)
		(fill yes
			(thermal_gap 0.5)
			(thermal_bridge_width 0.5)
			(island_removal_mode 0)
		)
		(polygon
			(pts
				(arc
					(start 126.643638 -288.917126)
					(mid 125.990858 -288.917126)
					(end 126.643638 -288.917126)
				)
			)
		)
	)
	(zone
		(layers "B.Cu" "In6.Cu" "In11.Cu" "In13.Cu" "In15.Cu")
		(hatch none 0.5)
		(connect_pads
			(clearance 0)
		)
		(min_thickness 0.25)
		(keepout
			(tracks not_allowed)
			(vias allowed)
			(pads allowed)
			(copperpour not_allowed)
			(footprints allowed)
		)
		(placement
			(enabled no)
			(sheetname "")
		)
		(fill yes
			(thermal_gap 0.5)
			(thermal_bridge_width 0.5)
			(island_removal_mode 0)
		)
		(polygon
			(pts
				(arc
					(start 343.061544 -46.100492)
					(mid 342.408764 -46.100492)
					(end 343.061544 -46.100492)
				)
			)
		)
	)
	(zone
		(layers "B.Cu" "In6.Cu" "In11.Cu" "In13.Cu" "In15.Cu")
		(hatch none 0.5)
		(connect_pads
			(clearance 0)
		)
		(min_thickness 0.25)
		(keepout
			(tracks not_allowed)
			(vias allowed)
			(pads allowed)
			(copperpour not_allowed)
			(footprints allowed)
		)
		(placement
			(enabled no)
			(sheetname "")
		)
		(fill yes
			(thermal_gap 0.5)
			(thermal_bridge_width 0.5)
			(island_removal_mode 0)
		)
		(polygon
			(pts
				(arc
					(start 440.250072 -312.066686)
					(mid 439.597292 -312.066686)
					(end 440.250072 -312.066686)
				)
			)
		)
	)
	(zone
		(layers "B.Cu" "In6.Cu" "In11.Cu" "In13.Cu" "In15.Cu")
		(hatch none 0.5)
		(connect_pads
			(clearance 0)
		)
		(min_thickness 0.25)
		(keepout
			(tracks not_allowed)
			(vias allowed)
			(pads allowed)
			(copperpour not_allowed)
			(footprints allowed)
		)
		(placement
			(enabled no)
			(sheetname "")
		)
		(fill yes
			(thermal_gap 0.5)
			(thermal_bridge_width 0.5)
			(island_removal_mode 0)
		)
		(polygon
			(pts
				(arc
					(start 177.222404 -300.166532)
					(mid 176.569624 -300.166532)
					(end 177.222404 -300.166532)
				)
			)
		)
	)
	(zone
		(layers "B.Cu" "In6.Cu" "In11.Cu" "In13.Cu" "In15.Cu")
		(hatch none 0.5)
		(connect_pads
			(clearance 0)
		)
		(min_thickness 0.25)
		(keepout
			(tracks not_allowed)
			(vias allowed)
			(pads allowed)
			(copperpour not_allowed)
			(footprints allowed)
		)
		(placement
			(enabled no)
			(sheetname "")
		)
		(fill yes
			(thermal_gap 0.5)
			(thermal_bridge_width 0.5)
			(island_removal_mode 0)
		)
		(polygon
			(pts
				(arc
					(start 373.174006 -288.103056)
					(mid 372.521226 -288.103056)
					(end 373.174006 -288.103056)
				)
			)
		)
	)
	(zone
		(layers "B.Cu" "In6.Cu" "In11.Cu" "In13.Cu" "In15.Cu")
		(hatch none 0.5)
		(connect_pads
			(clearance 0)
		)
		(min_thickness 0.25)
		(keepout
			(tracks not_allowed)
			(vias allowed)
			(pads allowed)
			(copperpour not_allowed)
			(footprints allowed)
		)
		(placement
			(enabled no)
			(sheetname "")
		)
		(fill yes
			(thermal_gap 0.5)
			(thermal_bridge_width 0.5)
			(island_removal_mode 0)
		)
		(polygon
			(pts
				(arc
					(start 339.231224 -217.878406)
					(mid 338.578444 -217.878406)
					(end 339.231224 -217.878406)
				)
			)
		)
	)
	(zone
		(layers "B.Cu" "In6.Cu" "In11.Cu" "In13.Cu" "In15.Cu")
		(hatch none 0.5)
		(connect_pads
			(clearance 0)
		)
		(min_thickness 0.25)
		(keepout
			(tracks not_allowed)
			(vias allowed)
			(pads allowed)
			(copperpour not_allowed)
			(footprints allowed)
		)
		(placement
			(enabled no)
			(sheetname "")
		)
		(fill yes
			(thermal_gap 0.5)
			(thermal_bridge_width 0.5)
			(island_removal_mode 0)
		)
		(polygon
			(pts
				(arc
					(start 341.690452 -279.150318)
					(mid 341.037672 -279.150318)
					(end 341.690452 -279.150318)
				)
			)
		)
	)
	(zone
		(layers "B.Cu" "In6.Cu" "In11.Cu" "In13.Cu" "In15.Cu")
		(hatch none 0.5)
		(connect_pads
			(clearance 0)
		)
		(min_thickness 0.25)
		(keepout
			(tracks not_allowed)
			(vias allowed)
			(pads allowed)
			(copperpour not_allowed)
			(footprints allowed)
		)
		(placement
			(enabled no)
			(sheetname "")
		)
		(fill yes
			(thermal_gap 0.5)
			(thermal_bridge_width 0.5)
			(island_removal_mode 0)
		)
		(polygon
			(pts
				(arc
					(start 51.390804 -199.866758)
					(mid 50.738024 -199.866758)
					(end 51.390804 -199.866758)
				)
			)
		)
	)
	(zone
		(layers "B.Cu" "In6.Cu" "In11.Cu" "In13.Cu" "In15.Cu")
		(hatch none 0.5)
		(connect_pads
			(clearance 0)
		)
		(min_thickness 0.25)
		(keepout
			(tracks not_allowed)
			(vias allowed)
			(pads allowed)
			(copperpour not_allowed)
			(footprints allowed)
		)
		(placement
			(enabled no)
			(sheetname "")
		)
		(fill yes
			(thermal_gap 0.5)
			(thermal_bridge_width 0.5)
			(island_removal_mode 0)
		)
		(polygon
			(pts
				(arc
					(start 340.64067 -231.714548)
					(mid 339.98789 -231.714548)
					(end 340.64067 -231.714548)
				)
			)
		)
	)
	(zone
		(layers "B.Cu" "In6.Cu" "In11.Cu" "In13.Cu" "In15.Cu")
		(hatch none 0.5)
		(connect_pads
			(clearance 0)
		)
		(min_thickness 0.25)
		(keepout
			(tracks not_allowed)
			(vias allowed)
			(pads allowed)
			(copperpour not_allowed)
			(footprints allowed)
		)
		(placement
			(enabled no)
			(sheetname "")
		)
		(fill yes
			(thermal_gap 0.5)
			(thermal_bridge_width 0.5)
			(island_removal_mode 0)
		)
		(polygon
			(pts
				(arc
					(start 299.330872 -225.36658)
					(mid 298.678092 -225.36658)
					(end 299.330872 -225.36658)
				)
			)
		)
	)
	(zone
		(layers "B.Cu" "In6.Cu" "In11.Cu" "In13.Cu" "In15.Cu")
		(hatch none 0.5)
		(connect_pads
			(clearance 0)
		)
		(min_thickness 0.25)
		(keepout
			(tracks not_allowed)
			(vias allowed)
			(pads allowed)
			(copperpour not_allowed)
			(footprints allowed)
		)
		(placement
			(enabled no)
			(sheetname "")
		)
		(fill yes
			(thermal_gap 0.5)
			(thermal_bridge_width 0.5)
			(island_removal_mode 0)
		)
		(polygon
			(pts
				(arc
					(start 130.872738 -265.314176)
					(mid 130.219958 -265.314176)
					(end 130.872738 -265.314176)
				)
			)
		)
	)
	(zone
		(layers "B.Cu" "In6.Cu" "In11.Cu" "In13.Cu" "In15.Cu")
		(hatch none 0.5)
		(connect_pads
			(clearance 0)
		)
		(min_thickness 0.25)
		(keepout
			(tracks not_allowed)
			(vias allowed)
			(pads allowed)
			(copperpour not_allowed)
			(footprints allowed)
		)
		(placement
			(enabled no)
			(sheetname "")
		)
		(fill yes
			(thermal_gap 0.5)
			(thermal_bridge_width 0.5)
			(island_removal_mode 0)
		)
		(polygon
			(pts
				(arc
					(start 379.642624 -239.0394)
					(mid 378.989844 -239.0394)
					(end 379.642624 -239.0394)
				)
			)
		)
	)
	(zone
		(layers "B.Cu" "In6.Cu" "In11.Cu" "In13.Cu" "In15.Cu")
		(hatch none 0.5)
		(connect_pads
			(clearance 0)
		)
		(min_thickness 0.25)
		(keepout
			(tracks not_allowed)
			(vias allowed)
			(pads allowed)
			(copperpour not_allowed)
			(footprints allowed)
		)
		(placement
			(enabled no)
			(sheetname "")
		)
		(fill yes
			(thermal_gap 0.5)
			(thermal_bridge_width 0.5)
			(island_removal_mode 0)
		)
		(polygon
			(pts
				(arc
					(start 348.739206 -288.103056)
					(mid 348.086426 -288.103056)
					(end 348.739206 -288.103056)
				)
			)
		)
	)
	(zone
		(layers "B.Cu" "In6.Cu" "In11.Cu" "In13.Cu" "In15.Cu")
		(hatch none 0.5)
		(connect_pads
			(clearance 0)
		)
		(min_thickness 0.25)
		(keepout
			(tracks not_allowed)
			(vias allowed)
			(pads allowed)
			(copperpour not_allowed)
			(footprints allowed)
		)
		(placement
			(enabled no)
			(sheetname "")
		)
		(fill yes
			(thermal_gap 0.5)
			(thermal_bridge_width 0.5)
			(island_removal_mode 0)
		)
		(polygon
			(pts
				(arc
					(start 374.47347 -217.064336)
					(mid 373.82069 -217.064336)
					(end 374.47347 -217.064336)
				)
			)
		)
	)
	(zone
		(layers "B.Cu" "In6.Cu" "In11.Cu" "In13.Cu" "In15.Cu")
		(hatch none 0.5)
		(connect_pads
			(clearance 0)
		)
		(min_thickness 0.25)
		(keepout
			(tracks not_allowed)
			(vias allowed)
			(pads allowed)
			(copperpour not_allowed)
			(footprints allowed)
		)
		(placement
			(enabled no)
			(sheetname "")
		)
		(fill yes
			(thermal_gap 0.5)
			(thermal_bridge_width 0.5)
			(island_removal_mode 0)
		)
		(polygon
			(pts
				(arc
					(start 36.303204 -233.016806)
					(mid 35.650424 -233.016806)
					(end 36.303204 -233.016806)
				)
			)
		)
	)
	(zone
		(layers "B.Cu" "In6.Cu" "In11.Cu" "In13.Cu" "In15.Cu")
		(hatch none 0.5)
		(connect_pads
			(clearance 0)
		)
		(min_thickness 0.25)
		(keepout
			(tracks not_allowed)
			(vias allowed)
			(pads allowed)
			(copperpour not_allowed)
			(footprints allowed)
		)
		(placement
			(enabled no)
			(sheetname "")
		)
		(fill yes
			(thermal_gap 0.5)
			(thermal_bridge_width 0.5)
			(island_removal_mode 0)
		)
		(polygon
			(pts
				(arc
					(start 131.342638 -288.917126)
					(mid 130.689858 -288.917126)
					(end 131.342638 -288.917126)
				)
			)
		)
	)
	(zone
		(layers "B.Cu" "In6.Cu" "In11.Cu" "In13.Cu" "In15.Cu")
		(hatch none 0.5)
		(connect_pads
			(clearance 0)
		)
		(min_thickness 0.25)
		(keepout
			(tracks not_allowed)
			(vias allowed)
			(pads allowed)
			(copperpour not_allowed)
			(footprints allowed)
		)
		(placement
			(enabled no)
			(sheetname "")
		)
		(fill yes
			(thermal_gap 0.5)
			(thermal_bridge_width 0.5)
			(island_removal_mode 0)
		)
		(polygon
			(pts
				(arc
					(start 133.582156 -217.878406)
					(mid 132.929376 -217.878406)
					(end 133.582156 -217.878406)
				)
			)
		)
	)
	(zone
		(layers "B.Cu" "In6.Cu" "In11.Cu" "In13.Cu" "In15.Cu")
		(hatch none 0.5)
		(connect_pads
			(clearance 0)
		)
		(min_thickness 0.25)
		(keepout
			(tracks not_allowed)
			(vias allowed)
			(pads allowed)
			(copperpour not_allowed)
			(footprints allowed)
		)
		(placement
			(enabled no)
			(sheetname "")
		)
		(fill yes
			(thermal_gap 0.5)
			(thermal_bridge_width 0.5)
			(island_removal_mode 0)
		)
		(polygon
			(pts
				(arc
					(start 379.752606 -273.453098)
					(mid 379.099826 -273.453098)
					(end 379.752606 -273.453098)
				)
			)
		)
	)
	(zone
		(layers "B.Cu" "In6.Cu" "In11.Cu" "In13.Cu" "In15.Cu")
		(hatch none 0.5)
		(connect_pads
			(clearance 0)
		)
		(min_thickness 0.25)
		(keepout
			(tracks not_allowed)
			(vias allowed)
			(pads allowed)
			(copperpour not_allowed)
			(footprints allowed)
		)
		(placement
			(enabled no)
			(sheetname "")
		)
		(fill yes
			(thermal_gap 0.5)
			(thermal_bridge_width 0.5)
			(island_removal_mode 0)
		)
		(polygon
			(pts
				(arc
					(start 47.290736 -282.316682)
					(mid 46.637956 -282.316682)
					(end 47.290736 -282.316682)
				)
			)
		)
	)
	(zone
		(layers "B.Cu" "In6.Cu" "In11.Cu" "In13.Cu" "In15.Cu")
		(hatch none 0.5)
		(connect_pads
			(clearance 0)
		)
		(min_thickness 0.25)
		(keepout
			(tracks not_allowed)
			(vias allowed)
			(pads allowed)
			(copperpour not_allowed)
			(footprints allowed)
		)
		(placement
			(enabled no)
			(sheetname "")
		)
		(fill yes
			(thermal_gap 0.5)
			(thermal_bridge_width 0.5)
			(island_removal_mode 0)
		)
		(polygon
			(pts
				(arc
					(start 36.303204 -240.666778)
					(mid 35.650424 -240.666778)
					(end 36.303204 -240.666778)
				)
			)
		)
	)
	(zone
		(layers "B.Cu" "In6.Cu" "In11.Cu" "In13.Cu" "In15.Cu")
		(hatch none 0.5)
		(connect_pads
			(clearance 0)
		)
		(min_thickness 0.25)
		(keepout
			(tracks not_allowed)
			(vias allowed)
			(pads allowed)
			(copperpour not_allowed)
			(footprints allowed)
		)
		(placement
			(enabled no)
			(sheetname "")
		)
		(fill yes
			(thermal_gap 0.5)
			(thermal_bridge_width 0.5)
			(island_removal_mode 0)
		)
		(polygon
			(pts
				(arc
					(start 177.222404 -281.466544)
					(mid 176.569624 -281.466544)
					(end 177.222404 -281.466544)
				)
			)
		)
	)
	(zone
		(layers "B.Cu" "In6.Cu" "In11.Cu" "In13.Cu" "In15.Cu")
		(hatch none 0.5)
		(connect_pads
			(clearance 0)
		)
		(min_thickness 0.25)
		(keepout
			(tracks not_allowed)
			(vias allowed)
			(pads allowed)
			(copperpour not_allowed)
			(footprints allowed)
		)
		(placement
			(enabled no)
			(sheetname "")
		)
		(fill yes
			(thermal_gap 0.5)
			(thermal_bridge_width 0.5)
			(island_removal_mode 0)
		)
		(polygon
			(pts
				(arc
					(start 131.812538 -260.430772)
					(mid 131.159758 -260.430772)
					(end 131.812538 -260.430772)
				)
			)
		)
	)
	(zone
		(layers "B.Cu" "In6.Cu" "In11.Cu" "In13.Cu" "In15.Cu")
		(hatch none 0.5)
		(connect_pads
			(clearance 0)
		)
		(min_thickness 0.25)
		(keepout
			(tracks not_allowed)
			(vias allowed)
			(pads allowed)
			(copperpour not_allowed)
			(footprints allowed)
		)
		(placement
			(enabled no)
			(sheetname "")
		)
		(fill yes
			(thermal_gap 0.5)
			(thermal_bridge_width 0.5)
			(island_removal_mode 0)
		)
		(polygon
			(pts
				(arc
					(start 132.642356 -232.528364)
					(mid 131.989576 -232.528364)
					(end 132.642356 -232.528364)
				)
			)
		)
	)
	(zone
		(layers "B.Cu" "In6.Cu" "In11.Cu" "In13.Cu" "In15.Cu")
		(hatch none 0.5)
		(connect_pads
			(clearance 0)
		)
		(min_thickness 0.25)
		(keepout
			(tracks not_allowed)
			(vias allowed)
			(pads allowed)
			(copperpour not_allowed)
			(footprints allowed)
		)
		(placement
			(enabled no)
			(sheetname "")
		)
		(fill yes
			(thermal_gap 0.5)
			(thermal_bridge_width 0.5)
			(island_removal_mode 0)
		)
		(polygon
			(pts
				(arc
					(start 379.752606 -263.686544)
					(mid 379.099826 -263.686544)
					(end 379.752606 -263.686544)
				)
			)
		)
	)
	(zone
		(layers "B.Cu" "In6.Cu" "In11.Cu" "In13.Cu" "In15.Cu")
		(hatch none 0.5)
		(connect_pads
			(clearance 0)
		)
		(min_thickness 0.25)
		(keepout
			(tracks not_allowed)
			(vias allowed)
			(pads allowed)
			(copperpour not_allowed)
			(footprints allowed)
		)
		(placement
			(enabled no)
			(sheetname "")
		)
		(fill yes
			(thermal_gap 0.5)
			(thermal_bridge_width 0.5)
			(island_removal_mode 0)
		)
		(polygon
			(pts
				(arc
					(start 358.967024 -217.878406)
					(mid 358.314244 -217.878406)
					(end 358.967024 -217.878406)
				)
			)
		)
	)
	(zone
		(layers "B.Cu" "In6.Cu" "In11.Cu" "In13.Cu" "In15.Cu")
		(hatch none 0.5)
		(connect_pads
			(clearance 0)
		)
		(min_thickness 0.25)
		(keepout
			(tracks not_allowed)
			(vias allowed)
			(pads allowed)
			(copperpour not_allowed)
			(footprints allowed)
		)
		(placement
			(enabled no)
			(sheetname "")
		)
		(fill yes
			(thermal_gap 0.5)
			(thermal_bridge_width 0.5)
			(island_removal_mode 0)
		)
		(polygon
			(pts
				(arc
					(start 192.310004 -267.016738)
					(mid 191.657224 -267.016738)
					(end 192.310004 -267.016738)
				)
			)
		)
	)
	(zone
		(layers "B.Cu" "In6.Cu" "In11.Cu" "In13.Cu" "In15.Cu")
		(hatch none 0.5)
		(connect_pads
			(clearance 0)
		)
		(min_thickness 0.25)
		(keepout
			(tracks not_allowed)
			(vias allowed)
			(pads allowed)
			(copperpour not_allowed)
			(footprints allowed)
		)
		(placement
			(enabled no)
			(sheetname "")
		)
		(fill yes
			(thermal_gap 0.5)
			(thermal_bridge_width 0.5)
			(island_removal_mode 0)
		)
		(polygon
			(pts
				(arc
					(start 440.250072 -209.216752)
					(mid 439.597292 -209.216752)
					(end 440.250072 -209.216752)
				)
			)
		)
	)
	(zone
		(layers "B.Cu" "In6.Cu" "In11.Cu" "In13.Cu" "In15.Cu")
		(hatch none 0.5)
		(connect_pads
			(clearance 0)
		)
		(min_thickness 0.25)
		(keepout
			(tracks not_allowed)
			(vias allowed)
			(pads allowed)
			(copperpour not_allowed)
			(footprints allowed)
		)
		(placement
			(enabled no)
			(sheetname "")
		)
		(fill yes
			(thermal_gap 0.5)
			(thermal_bridge_width 0.5)
			(island_removal_mode 0)
		)
		(polygon
			(pts
				(arc
					(start 97.039938 -255.547622)
					(mid 96.387158 -255.547622)
					(end 97.039938 -255.547622)
				)
			)
		)
	)
	(zone
		(layers "B.Cu" "In6.Cu" "In11.Cu" "In13.Cu" "In15.Cu")
		(hatch none 0.5)
		(connect_pads
			(clearance 0)
		)
		(min_thickness 0.25)
		(keepout
			(tracks not_allowed)
			(vias allowed)
			(pads allowed)
			(copperpour not_allowed)
			(footprints allowed)
		)
		(placement
			(enabled no)
			(sheetname "")
		)
		(fill yes
			(thermal_gap 0.5)
			(thermal_bridge_width 0.5)
			(island_removal_mode 0)
		)
		(polygon
			(pts
				(arc
					(start 188.209936 -205.816708)
					(mid 187.557156 -205.816708)
					(end 188.209936 -205.816708)
				)
			)
		)
	)
	(zone
		(layers "B.Cu" "In6.Cu" "In11.Cu" "In13.Cu" "In15.Cu")
		(hatch none 0.5)
		(connect_pads
			(clearance 0)
		)
		(min_thickness 0.25)
		(keepout
			(tracks not_allowed)
			(vias allowed)
			(pads allowed)
			(copperpour not_allowed)
			(footprints allowed)
		)
		(placement
			(enabled no)
			(sheetname "")
		)
		(fill yes
			(thermal_gap 0.5)
			(thermal_bridge_width 0.5)
			(island_removal_mode 0)
		)
		(polygon
			(pts
				(arc
					(start 380.582424 -242.294918)
					(mid 379.929644 -242.294918)
					(end 380.582424 -242.294918)
				)
			)
		)
	)
	(zone
		(layers "B.Cu" "In6.Cu" "In11.Cu" "In13.Cu" "In15.Cu")
		(hatch none 0.5)
		(connect_pads
			(clearance 0)
		)
		(min_thickness 0.25)
		(keepout
			(tracks not_allowed)
			(vias allowed)
			(pads allowed)
			(copperpour not_allowed)
			(footprints allowed)
		)
		(placement
			(enabled no)
			(sheetname "")
		)
		(fill yes
			(thermal_gap 0.5)
			(thermal_bridge_width 0.5)
			(island_removal_mode 0)
		)
		(polygon
			(pts
				(arc
					(start 348.15907 -217.064336)
					(mid 347.50629 -217.064336)
					(end 348.15907 -217.064336)
				)
			)
		)
	)
	(zone
		(layers "B.Cu" "In6.Cu" "In11.Cu" "In13.Cu" "In15.Cu")
		(hatch none 0.5)
		(connect_pads
			(clearance 0)
		)
		(min_thickness 0.25)
		(keepout
			(tracks not_allowed)
			(vias allowed)
			(pads allowed)
			(copperpour not_allowed)
			(footprints allowed)
		)
		(placement
			(enabled no)
			(sheetname "")
		)
		(fill yes
			(thermal_gap 0.5)
			(thermal_bridge_width 0.5)
			(island_removal_mode 0)
		)
		(polygon
			(pts
				(arc
					(start 334.062324 -226.831144)
					(mid 333.409544 -226.831144)
					(end 334.062324 -226.831144)
				)
			)
		)
	)
	(zone
		(layers "B.Cu" "In6.Cu" "In11.Cu" "In13.Cu" "In15.Cu")
		(hatch none 0.5)
		(connect_pads
			(clearance 0)
		)
		(min_thickness 0.25)
		(keepout
			(tracks not_allowed)
			(vias allowed)
			(pads allowed)
			(copperpour not_allowed)
			(footprints allowed)
		)
		(placement
			(enabled no)
			(sheetname "")
		)
		(fill yes
			(thermal_gap 0.5)
			(thermal_bridge_width 0.5)
			(island_removal_mode 0)
		)
		(polygon
			(pts
				(arc
					(start 340.281006 -271.825212)
					(mid 339.628226 -271.825212)
					(end 340.281006 -271.825212)
				)
			)
		)
	)
	(zone
		(layers "B.Cu" "In6.Cu" "In11.Cu" "In13.Cu" "In15.Cu")
		(hatch none 0.5)
		(connect_pads
			(clearance 0)
		)
		(min_thickness 0.25)
		(keepout
			(tracks not_allowed)
			(vias allowed)
			(pads allowed)
			(copperpour not_allowed)
			(footprints allowed)
		)
		(placement
			(enabled no)
			(sheetname "")
		)
		(fill yes
			(thermal_gap 0.5)
			(thermal_bridge_width 0.5)
			(island_removal_mode 0)
		)
		(polygon
			(pts
				(arc
					(start 295.230804 -199.866758)
					(mid 294.578024 -199.866758)
					(end 295.230804 -199.866758)
				)
			)
		)
	)
	(zone
		(layers "B.Cu" "In6.Cu" "In11.Cu" "In13.Cu" "In15.Cu")
		(hatch none 0.5)
		(connect_pads
			(clearance 0)
		)
		(min_thickness 0.25)
		(keepout
			(tracks not_allowed)
			(vias allowed)
			(pads allowed)
			(copperpour not_allowed)
			(footprints allowed)
		)
		(placement
			(enabled no)
			(sheetname "")
		)
		(fill yes
			(thermal_gap 0.5)
			(thermal_bridge_width 0.5)
			(island_removal_mode 0)
		)
		(polygon
			(pts
				(arc
					(start 130.872738 -271.825212)
					(mid 130.219958 -271.825212)
					(end 130.872738 -271.825212)
				)
			)
		)
	)
	(zone
		(layers "B.Cu" "In6.Cu" "In11.Cu" "In13.Cu" "In15.Cu")
		(hatch none 0.5)
		(connect_pads
			(clearance 0)
		)
		(min_thickness 0.25)
		(keepout
			(tracks not_allowed)
			(vias allowed)
			(pads allowed)
			(copperpour not_allowed)
			(footprints allowed)
		)
		(placement
			(enabled no)
			(sheetname "")
		)
		(fill yes
			(thermal_gap 0.5)
			(thermal_bridge_width 0.5)
			(island_removal_mode 0)
		)
		(polygon
			(pts
				(arc
					(start 280.143204 -312.91657)
					(mid 279.490424 -312.91657)
					(end 280.143204 -312.91657)
				)
			)
		)
	)
	(zone
		(layers "B.Cu" "In6.Cu" "In11.Cu" "In13.Cu" "In15.Cu")
		(hatch none 0.5)
		(connect_pads
			(clearance 0)
		)
		(min_thickness 0.25)
		(keepout
			(tracks not_allowed)
			(vias allowed)
			(pads allowed)
			(copperpour not_allowed)
			(footprints allowed)
		)
		(placement
			(enabled no)
			(sheetname "")
		)
		(fill yes
			(thermal_gap 0.5)
			(thermal_bridge_width 0.5)
			(island_removal_mode 0)
		)
		(polygon
			(pts
				(arc
					(start 295.230804 -232.166668)
					(mid 294.578024 -232.166668)
					(end 295.230804 -232.166668)
				)
			)
		)
	)
	(zone
		(layers "B.Cu" "In6.Cu" "In11.Cu" "In13.Cu" "In15.Cu")
		(hatch none 0.5)
		(connect_pads
			(clearance 0)
		)
		(min_thickness 0.25)
		(keepout
			(tracks not_allowed)
			(vias allowed)
			(pads allowed)
			(copperpour not_allowed)
			(footprints allowed)
		)
		(placement
			(enabled no)
			(sheetname "")
		)
		(fill yes
			(thermal_gap 0.5)
			(thermal_bridge_width 0.5)
			(island_removal_mode 0)
		)
		(polygon
			(pts
				(arc
					(start 380.11227 -236.597952)
					(mid 379.45949 -236.597952)
					(end 380.11227 -236.597952)
				)
			)
		)
	)
	(zone
		(layers "B.Cu" "In6.Cu" "In11.Cu" "In13.Cu" "In15.Cu")
		(hatch none 0.5)
		(connect_pads
			(clearance 0)
		)
		(min_thickness 0.25)
		(keepout
			(tracks not_allowed)
			(vias allowed)
			(pads allowed)
			(copperpour not_allowed)
			(footprints allowed)
		)
		(placement
			(enabled no)
			(sheetname "")
		)
		(fill yes
			(thermal_gap 0.5)
			(thermal_bridge_width 0.5)
			(island_removal_mode 0)
		)
		(polygon
			(pts
				(arc
					(start 345.33967 -218.692222)
					(mid 344.68689 -218.692222)
					(end 345.33967 -218.692222)
				)
			)
		)
	)
	(zone
		(layers "B.Cu" "In6.Cu" "In11.Cu" "In13.Cu" "In15.Cu")
		(hatch none 0.5)
		(connect_pads
			(clearance 0)
		)
		(min_thickness 0.25)
		(keepout
			(tracks not_allowed)
			(vias allowed)
			(pads allowed)
			(copperpour not_allowed)
			(footprints allowed)
		)
		(placement
			(enabled no)
			(sheetname "")
		)
		(fill yes
			(thermal_gap 0.5)
			(thermal_bridge_width 0.5)
			(island_removal_mode 0)
		)
		(polygon
			(pts
				(arc
					(start 242.66017 -52.03825)
					(mid 241.95659 -52.03825)
					(end 242.66017 -52.03825)
				)
			)
		)
	)
	(zone
		(layers "B.Cu" "In6.Cu" "In11.Cu" "In13.Cu" "In15.Cu")
		(hatch none 0.5)
		(connect_pads
			(clearance 0)
		)
		(min_thickness 0.25)
		(keepout
			(tracks not_allowed)
			(vias allowed)
			(pads allowed)
			(copperpour not_allowed)
			(footprints allowed)
		)
		(placement
			(enabled no)
			(sheetname "")
		)
		(fill yes
			(thermal_gap 0.5)
			(thermal_bridge_width 0.5)
			(island_removal_mode 0)
		)
		(polygon
			(pts
				(arc
					(start 381.05207 -226.831144)
					(mid 380.39929 -226.831144)
					(end 381.05207 -226.831144)
				)
			)
		)
	)
	(zone
		(layers "B.Cu" "In6.Cu" "In11.Cu" "In13.Cu" "In15.Cu")
		(hatch none 0.5)
		(connect_pads
			(clearance 0)
		)
		(min_thickness 0.25)
		(keepout
			(tracks not_allowed)
			(vias allowed)
			(pads allowed)
			(copperpour not_allowed)
			(footprints allowed)
		)
		(placement
			(enabled no)
			(sheetname "")
		)
		(fill yes
			(thermal_gap 0.5)
			(thermal_bridge_width 0.5)
			(island_removal_mode 0)
		)
		(polygon
			(pts
				(arc
					(start 130.762756 -217.878406)
					(mid 130.109976 -217.878406)
					(end 130.762756 -217.878406)
				)
			)
		)
	)
	(zone
		(layers "B.Cu" "In6.Cu" "In11.Cu" "In13.Cu" "In15.Cu")
		(hatch none 0.5)
		(connect_pads
			(clearance 0)
		)
		(min_thickness 0.25)
		(keepout
			(tracks not_allowed)
			(vias allowed)
			(pads allowed)
			(copperpour not_allowed)
			(footprints allowed)
		)
		(placement
			(enabled no)
			(sheetname "")
		)
		(fill yes
			(thermal_gap 0.5)
			(thermal_bridge_width 0.5)
			(island_removal_mode 0)
		)
		(polygon
			(pts
				(arc
					(start 89.521284 -288.103056)
					(mid 88.868504 -288.103056)
					(end 89.521284 -288.103056)
				)
			)
		)
	)
	(zone
		(layers "B.Cu" "In6.Cu" "In11.Cu" "In13.Cu" "In15.Cu")
		(hatch none 0.5)
		(connect_pads
			(clearance 0)
		)
		(min_thickness 0.25)
		(keepout
			(tracks not_allowed)
			(vias allowed)
			(pads allowed)
			(copperpour not_allowed)
			(footprints allowed)
		)
		(placement
			(enabled no)
			(sheetname "")
		)
		(fill yes
			(thermal_gap 0.5)
			(thermal_bridge_width 0.5)
			(island_removal_mode 0)
		)
		(polygon
			(pts
				(arc
					(start 284.243272 -233.016806)
					(mid 283.590492 -233.016806)
					(end 284.243272 -233.016806)
				)
			)
		)
	)
	(zone
		(layers "B.Cu" "In6.Cu" "In11.Cu" "In13.Cu" "In15.Cu")
		(hatch none 0.5)
		(connect_pads
			(clearance 0)
		)
		(min_thickness 0.25)
		(keepout
			(tracks not_allowed)
			(vias allowed)
			(pads allowed)
			(copperpour not_allowed)
			(footprints allowed)
		)
		(placement
			(enabled no)
			(sheetname "")
		)
		(fill yes
			(thermal_gap 0.5)
			(thermal_bridge_width 0.5)
			(island_removal_mode 0)
		)
		(polygon
			(pts
				(arc
					(start 378.812806 -266.941808)
					(mid 378.160026 -266.941808)
					(end 378.812806 -266.941808)
				)
			)
		)
	)
	(zone
		(layers "B.Cu" "In6.Cu" "In11.Cu" "In13.Cu" "In15.Cu")
		(hatch none 0.5)
		(connect_pads
			(clearance 0)
		)
		(min_thickness 0.25)
		(keepout
			(tracks not_allowed)
			(vias allowed)
			(pads allowed)
			(copperpour not_allowed)
			(footprints allowed)
		)
		(placement
			(enabled no)
			(sheetname "")
		)
		(fill yes
			(thermal_gap 0.5)
			(thermal_bridge_width 0.5)
			(island_removal_mode 0)
		)
		(polygon
			(pts
				(arc
					(start 89.881202 -218.692222)
					(mid 89.228422 -218.692222)
					(end 89.881202 -218.692222)
				)
			)
		)
	)
	(zone
		(layers "B.Cu" "In6.Cu" "In11.Cu" "In13.Cu" "In15.Cu")
		(hatch none 0.5)
		(connect_pads
			(clearance 0)
		)
		(min_thickness 0.25)
		(keepout
			(tracks not_allowed)
			(vias allowed)
			(pads allowed)
			(copperpour not_allowed)
			(footprints allowed)
		)
		(placement
			(enabled no)
			(sheetname "")
		)
		(fill yes
			(thermal_gap 0.5)
			(thermal_bridge_width 0.5)
			(island_removal_mode 0)
		)
		(polygon
			(pts
				(arc
					(start 378.342652 -259.616956)
					(mid 377.689872 -259.616956)
					(end 378.342652 -259.616956)
				)
			)
		)
	)
	(zone
		(layers "B.Cu" "In6.Cu" "In11.Cu" "In13.Cu" "In15.Cu")
		(hatch none 0.5)
		(connect_pads
			(clearance 0)
		)
		(min_thickness 0.25)
		(keepout
			(tracks not_allowed)
			(vias allowed)
			(pads allowed)
			(copperpour not_allowed)
			(footprints allowed)
		)
		(placement
			(enabled no)
			(sheetname "")
		)
		(fill yes
			(thermal_gap 0.5)
			(thermal_bridge_width 0.5)
			(island_removal_mode 0)
		)
		(polygon
			(pts
				(arc
					(start 173.122336 -227.91674)
					(mid 172.469556 -227.91674)
					(end 173.122336 -227.91674)
				)
			)
		)
	)
	(zone
		(layers "B.Cu" "In6.Cu" "In11.Cu" "In13.Cu" "In15.Cu")
		(hatch none 0.5)
		(connect_pads
			(clearance 0)
		)
		(min_thickness 0.25)
		(keepout
			(tracks not_allowed)
			(vias allowed)
			(pads allowed)
			(copperpour not_allowed)
			(footprints allowed)
		)
		(placement
			(enabled no)
			(sheetname "")
		)
		(fill yes
			(thermal_gap 0.5)
			(thermal_bridge_width 0.5)
			(island_removal_mode 0)
		)
		(polygon
			(pts
				(arc
					(start 299.330872 -227.066602)
					(mid 298.678092 -227.066602)
					(end 299.330872 -227.066602)
				)
			)
		)
	)
	(zone
		(layers "B.Cu" "In6.Cu" "In11.Cu" "In13.Cu" "In15.Cu")
		(hatch none 0.5)
		(connect_pads
			(clearance 0)
		)
		(min_thickness 0.25)
		(keepout
			(tracks not_allowed)
			(vias allowed)
			(pads allowed)
			(copperpour not_allowed)
			(footprints allowed)
		)
		(placement
			(enabled no)
			(sheetname "")
		)
		(fill yes
			(thermal_gap 0.5)
			(thermal_bridge_width 0.5)
			(island_removal_mode 0)
		)
		(polygon
			(pts
				(arc
					(start 440.250072 -236.416596)
					(mid 439.597292 -236.416596)
					(end 440.250072 -236.416596)
				)
			)
		)
	)
	(zone
		(layers "B.Cu" "In6.Cu" "In11.Cu" "In13.Cu" "In15.Cu")
		(hatch none 0.5)
		(connect_pads
			(clearance 0)
		)
		(min_thickness 0.25)
		(keepout
			(tracks not_allowed)
			(vias allowed)
			(pads allowed)
			(copperpour not_allowed)
			(footprints allowed)
		)
		(placement
			(enabled no)
			(sheetname "")
		)
		(fill yes
			(thermal_gap 0.5)
			(thermal_bridge_width 0.5)
			(island_removal_mode 0)
		)
		(polygon
			(pts
				(arc
					(start 115.255802 -217.064336)
					(mid 114.603022 -217.064336)
					(end 115.255802 -217.064336)
				)
			)
		)
	)
	(zone
		(layers "B.Cu" "In6.Cu" "In11.Cu" "In13.Cu" "In15.Cu")
		(hatch none 0.5)
		(connect_pads
			(clearance 0)
		)
		(min_thickness 0.25)
		(keepout
			(tracks not_allowed)
			(vias allowed)
			(pads allowed)
			(copperpour not_allowed)
			(footprints allowed)
		)
		(placement
			(enabled no)
			(sheetname "")
		)
		(fill yes
			(thermal_gap 0.5)
			(thermal_bridge_width 0.5)
			(island_removal_mode 0)
		)
		(polygon
			(pts
				(arc
					(start 134.051802 -217.064336)
					(mid 133.399022 -217.064336)
					(end 134.051802 -217.064336)
				)
			)
		)
	)
	(zone
		(layers "B.Cu" "In6.Cu" "In11.Cu" "In13.Cu" "In15.Cu")
		(hatch none 0.5)
		(connect_pads
			(clearance 0)
		)
		(min_thickness 0.25)
		(keepout
			(tracks not_allowed)
			(vias allowed)
			(pads allowed)
			(copperpour not_allowed)
			(footprints allowed)
		)
		(placement
			(enabled no)
			(sheetname "")
		)
		(fill yes
			(thermal_gap 0.5)
			(thermal_bridge_width 0.5)
			(island_removal_mode 0)
		)
		(polygon
			(pts
				(arc
					(start 342.52027 -239.853216)
					(mid 341.86749 -239.853216)
					(end 342.52027 -239.853216)
				)
			)
		)
	)
	(zone
		(layers "B.Cu" "In6.Cu" "In11.Cu" "In13.Cu" "In15.Cu")
		(hatch none 0.5)
		(connect_pads
			(clearance 0)
		)
		(min_thickness 0.25)
		(keepout
			(tracks not_allowed)
			(vias allowed)
			(pads allowed)
			(copperpour not_allowed)
			(footprints allowed)
		)
		(placement
			(enabled no)
			(sheetname "")
		)
		(fill yes
			(thermal_gap 0.5)
			(thermal_bridge_width 0.5)
			(island_removal_mode 0)
		)
		(polygon
			(pts
				(arc
					(start 132.752338 -270.19758)
					(mid 132.099558 -270.19758)
					(end 132.752338 -270.19758)
				)
			)
		)
	)
	(zone
		(layers "B.Cu" "In6.Cu" "In11.Cu" "In13.Cu" "In15.Cu")
		(hatch none 0.5)
		(connect_pads
			(clearance 0)
		)
		(min_thickness 0.25)
		(keepout
			(tracks not_allowed)
			(vias allowed)
			(pads allowed)
			(copperpour not_allowed)
			(footprints allowed)
		)
		(placement
			(enabled no)
			(sheetname "")
		)
		(fill yes
			(thermal_gap 0.5)
			(thermal_bridge_width 0.5)
			(island_removal_mode 0)
		)
		(polygon
			(pts
				(arc
					(start 91.760802 -234.970066)
					(mid 91.108022 -234.970066)
					(end 91.760802 -234.970066)
				)
			)
		)
	)
	(zone
		(layers "B.Cu" "In6.Cu" "In11.Cu" "In13.Cu" "In15.Cu")
		(hatch none 0.5)
		(connect_pads
			(clearance 0)
		)
		(min_thickness 0.25)
		(keepout
			(tracks not_allowed)
			(vias allowed)
			(pads allowed)
			(copperpour not_allowed)
			(footprints allowed)
		)
		(placement
			(enabled no)
			(sheetname "")
		)
		(fill yes
			(thermal_gap 0.5)
			(thermal_bridge_width 0.5)
			(island_removal_mode 0)
		)
		(polygon
			(pts
				(arc
					(start 348.629224 -217.878406)
					(mid 347.976444 -217.878406)
					(end 348.629224 -217.878406)
				)
			)
		)
	)
	(zone
		(layers "B.Cu" "In6.Cu" "In11.Cu" "In13.Cu" "In15.Cu")
		(hatch none 0.5)
		(connect_pads
			(clearance 0)
		)
		(min_thickness 0.25)
		(keepout
			(tracks not_allowed)
			(vias allowed)
			(pads allowed)
			(copperpour not_allowed)
			(footprints allowed)
		)
		(placement
			(enabled no)
			(sheetname "")
		)
		(fill yes
			(thermal_gap 0.5)
			(thermal_bridge_width 0.5)
			(island_removal_mode 0)
		)
		(polygon
			(pts
				(arc
					(start 120.534684 -289.807142)
					(mid 119.881904 -289.807142)
					(end 120.534684 -289.807142)
				)
			)
		)
	)
	(zone
		(layers "B.Cu" "In6.Cu" "In11.Cu" "In13.Cu" "In15.Cu")
		(hatch none 0.5)
		(connect_pads
			(clearance 0)
		)
		(min_thickness 0.25)
		(keepout
			(tracks not_allowed)
			(vias allowed)
			(pads allowed)
			(copperpour not_allowed)
			(footprints allowed)
		)
		(placement
			(enabled no)
			(sheetname "")
		)
		(fill yes
			(thermal_gap 0.5)
			(thermal_bridge_width 0.5)
			(island_removal_mode 0)
		)
		(polygon
			(pts
				(arc
					(start 341.690452 -256.361438)
					(mid 341.037672 -256.361438)
					(end 341.690452 -256.361438)
				)
			)
		)
	)
	(zone
		(layers "B.Cu" "In6.Cu" "In11.Cu" "In13.Cu" "In15.Cu")
		(hatch none 0.5)
		(connect_pads
			(clearance 0)
		)
		(min_thickness 0.25)
		(keepout
			(tracks not_allowed)
			(vias allowed)
			(pads allowed)
			(copperpour not_allowed)
			(footprints allowed)
		)
		(placement
			(enabled no)
			(sheetname "")
		)
		(fill yes
			(thermal_gap 0.5)
			(thermal_bridge_width 0.5)
			(island_removal_mode 0)
		)
		(polygon
			(pts
				(arc
					(start 47.290736 -227.91674)
					(mid 46.637956 -227.91674)
					(end 47.290736 -227.91674)
				)
			)
		)
	)
	(zone
		(layers "B.Cu" "In6.Cu" "In11.Cu" "In13.Cu" "In15.Cu")
		(hatch none 0.5)
		(connect_pads
			(clearance 0)
		)
		(min_thickness 0.25)
		(keepout
			(tracks not_allowed)
			(vias allowed)
			(pads allowed)
			(copperpour not_allowed)
			(footprints allowed)
		)
		(placement
			(enabled no)
			(sheetname "")
		)
		(fill yes
			(thermal_gap 0.5)
			(thermal_bridge_width 0.5)
			(island_removal_mode 0)
		)
		(polygon
			(pts
				(arc
					(start 192.310004 -293.366698)
					(mid 191.657224 -293.366698)
					(end 192.310004 -293.366698)
				)
			)
		)
	)
	(zone
		(layers "B.Cu" "In6.Cu" "In11.Cu" "In13.Cu" "In15.Cu")
		(hatch none 0.5)
		(connect_pads
			(clearance 0)
		)
		(min_thickness 0.25)
		(keepout
			(tracks not_allowed)
			(vias allowed)
			(pads allowed)
			(copperpour not_allowed)
			(footprints allowed)
		)
		(placement
			(enabled no)
			(sheetname "")
		)
		(fill yes
			(thermal_gap 0.5)
			(thermal_bridge_width 0.5)
			(island_removal_mode 0)
		)
		(polygon
			(pts
				(arc
					(start 334.062324 -225.203258)
					(mid 333.409544 -225.203258)
					(end 334.062324 -225.203258)
				)
			)
		)
	)
	(zone
		(layers "B.Cu" "In6.Cu" "In11.Cu" "In13.Cu" "In15.Cu")
		(hatch none 0.5)
		(connect_pads
			(clearance 0)
		)
		(min_thickness 0.25)
		(keepout
			(tracks not_allowed)
			(vias allowed)
			(pads allowed)
			(copperpour not_allowed)
			(footprints allowed)
		)
		(placement
			(enabled no)
			(sheetname "")
		)
		(fill yes
			(thermal_gap 0.5)
			(thermal_bridge_width 0.5)
			(island_removal_mode 0)
		)
		(polygon
			(pts
				(arc
					(start 380.11227 -238.225584)
					(mid 379.45949 -238.225584)
					(end 380.11227 -238.225584)
				)
			)
		)
	)
	(zone
		(layers "B.Cu" "In6.Cu" "In11.Cu" "In13.Cu" "In15.Cu")
		(hatch none 0.5)
		(connect_pads
			(clearance 0)
		)
		(min_thickness 0.25)
		(keepout
			(tracks not_allowed)
			(vias allowed)
			(pads allowed)
			(copperpour not_allowed)
			(footprints allowed)
		)
		(placement
			(enabled no)
			(sheetname "")
		)
		(fill yes
			(thermal_gap 0.5)
			(thermal_bridge_width 0.5)
			(island_removal_mode 0)
		)
		(polygon
			(pts
				(arc
					(start 188.209936 -312.066686)
					(mid 187.557156 -312.066686)
					(end 188.209936 -312.066686)
				)
			)
		)
	)
	(zone
		(layers "B.Cu" "In6.Cu" "In11.Cu" "In13.Cu" "In15.Cu")
		(hatch none 0.5)
		(connect_pads
			(clearance 0)
		)
		(min_thickness 0.25)
		(keepout
			(tracks not_allowed)
			(vias allowed)
			(pads allowed)
			(copperpour not_allowed)
			(footprints allowed)
		)
		(placement
			(enabled no)
			(sheetname "")
		)
		(fill yes
			(thermal_gap 0.5)
			(thermal_bridge_width 0.5)
			(island_removal_mode 0)
		)
		(polygon
			(pts
				(arc
					(start 328.085704 5.031994)
					(mid 327.382124 5.031994)
					(end 328.085704 5.031994)
				)
			)
		)
	)
	(zone
		(layers "B.Cu" "In6.Cu" "In11.Cu" "In13.Cu" "In15.Cu")
		(hatch none 0.5)
		(connect_pads
			(clearance 0)
		)
		(min_thickness 0.25)
		(keepout
			(tracks not_allowed)
			(vias allowed)
			(pads allowed)
			(copperpour not_allowed)
			(footprints allowed)
		)
		(placement
			(enabled no)
			(sheetname "")
		)
		(fill yes
			(thermal_gap 0.5)
			(thermal_bridge_width 0.5)
			(island_removal_mode 0)
		)
		(polygon
			(pts
				(arc
					(start 374.113552 -289.807142)
					(mid 373.460772 -289.807142)
					(end 374.113552 -289.807142)
				)
			)
		)
	)
	(zone
		(layers "B.Cu" "In6.Cu" "In11.Cu" "In13.Cu" "In15.Cu")
		(hatch none 0.5)
		(connect_pads
			(clearance 0)
		)
		(min_thickness 0.25)
		(keepout
			(tracks not_allowed)
			(vias allowed)
			(pads allowed)
			(copperpour not_allowed)
			(footprints allowed)
		)
		(placement
			(enabled no)
			(sheetname "")
		)
		(fill yes
			(thermal_gap 0.5)
			(thermal_bridge_width 0.5)
			(island_removal_mode 0)
		)
		(polygon
			(pts
				(arc
					(start 188.209936 -237.266734)
					(mid 187.557156 -237.266734)
					(end 188.209936 -237.266734)
				)
			)
		)
	)
	(zone
		(layers "B.Cu" "In6.Cu" "In11.Cu" "In13.Cu" "In15.Cu")
		(hatch none 0.5)
		(connect_pads
			(clearance 0)
		)
		(min_thickness 0.25)
		(keepout
			(tracks not_allowed)
			(vias allowed)
			(pads allowed)
			(copperpour not_allowed)
			(footprints allowed)
		)
		(placement
			(enabled no)
			(sheetname "")
		)
		(fill yes
			(thermal_gap 0.5)
			(thermal_bridge_width 0.5)
			(island_removal_mode 0)
		)
		(polygon
			(pts
				(arc
					(start 340.171024 -217.878406)
					(mid 339.518244 -217.878406)
					(end 340.171024 -217.878406)
				)
			)
		)
	)
	(zone
		(layers "B.Cu" "In6.Cu" "In11.Cu" "In13.Cu" "In15.Cu")
		(hatch none 0.5)
		(connect_pads
			(clearance 0)
		)
		(min_thickness 0.25)
		(keepout
			(tracks not_allowed)
			(vias allowed)
			(pads allowed)
			(copperpour not_allowed)
			(footprints allowed)
		)
		(placement
			(enabled no)
			(sheetname "")
		)
		(fill yes
			(thermal_gap 0.5)
			(thermal_bridge_width 0.5)
			(island_removal_mode 0)
		)
		(polygon
			(pts
				(arc
					(start 342.160606 -257.175254)
					(mid 341.507826 -257.175254)
					(end 342.160606 -257.175254)
				)
			)
		)
	)
	(zone
		(layers "B.Cu" "In6.Cu" "In11.Cu" "In13.Cu" "In15.Cu")
		(hatch none 0.5)
		(connect_pads
			(clearance 0)
		)
		(min_thickness 0.25)
		(keepout
			(tracks not_allowed)
			(vias allowed)
			(pads allowed)
			(copperpour not_allowed)
			(footprints allowed)
		)
		(placement
			(enabled no)
			(sheetname "")
		)
		(fill yes
			(thermal_gap 0.5)
			(thermal_bridge_width 0.5)
			(island_removal_mode 0)
		)
		(polygon
			(pts
				(arc
					(start 188.209936 -261.066788)
					(mid 187.557156 -261.066788)
					(end 188.209936 -261.066788)
				)
			)
		)
	)
	(zone
		(layers "B.Cu" "In6.Cu" "In11.Cu" "In13.Cu" "In15.Cu")
		(hatch none 0.5)
		(connect_pads
			(clearance 0)
		)
		(min_thickness 0.25)
		(keepout
			(tracks not_allowed)
			(vias allowed)
			(pads allowed)
			(copperpour not_allowed)
			(footprints allowed)
		)
		(placement
			(enabled no)
			(sheetname "")
		)
		(fill yes
			(thermal_gap 0.5)
			(thermal_bridge_width 0.5)
			(island_removal_mode 0)
		)
		(polygon
			(pts
				(arc
					(start 378.702824 -227.64496)
					(mid 378.050044 -227.64496)
					(end 378.702824 -227.64496)
				)
			)
		)
	)
	(zone
		(layers "B.Cu" "In6.Cu" "In11.Cu" "In13.Cu" "In15.Cu")
		(hatch none 0.5)
		(connect_pads
			(clearance 0)
		)
		(min_thickness 0.25)
		(keepout
			(tracks not_allowed)
			(vias allowed)
			(pads allowed)
			(copperpour not_allowed)
			(footprints allowed)
		)
		(placement
			(enabled no)
			(sheetname "")
		)
		(fill yes
			(thermal_gap 0.5)
			(thermal_bridge_width 0.5)
			(island_removal_mode 0)
		)
		(polygon
			(pts
				(arc
					(start 94.220538 -253.919736)
					(mid 93.567758 -253.919736)
					(end 94.220538 -253.919736)
				)
			)
		)
	)
	(zone
		(layers "B.Cu" "In6.Cu" "In11.Cu" "In13.Cu" "In15.Cu")
		(hatch none 0.5)
		(connect_pads
			(clearance 0)
		)
		(min_thickness 0.25)
		(keepout
			(tracks not_allowed)
			(vias allowed)
			(pads allowed)
			(copperpour not_allowed)
			(footprints allowed)
		)
		(placement
			(enabled no)
			(sheetname "")
		)
		(fill yes
			(thermal_gap 0.5)
			(thermal_bridge_width 0.5)
			(island_removal_mode 0)
		)
		(polygon
			(pts
				(arc
					(start 188.209936 -259.366766)
					(mid 187.557156 -259.366766)
					(end 188.209936 -259.366766)
				)
			)
		)
	)
	(zone
		(layers "B.Cu" "In6.Cu" "In11.Cu" "In13.Cu" "In15.Cu")
		(hatch none 0.5)
		(connect_pads
			(clearance 0)
		)
		(min_thickness 0.25)
		(keepout
			(tracks not_allowed)
			(vias allowed)
			(pads allowed)
			(copperpour not_allowed)
			(footprints allowed)
		)
		(placement
			(enabled no)
			(sheetname "")
		)
		(fill yes
			(thermal_gap 0.5)
			(thermal_bridge_width 0.5)
			(island_removal_mode 0)
		)
		(polygon
			(pts
				(arc
					(start 345.919552 -289.807142)
					(mid 345.266772 -289.807142)
					(end 345.919552 -289.807142)
				)
			)
		)
	)
	(zone
		(layers "B.Cu" "In6.Cu" "In11.Cu" "In13.Cu" "In15.Cu")
		(hatch none 0.5)
		(connect_pads
			(clearance 0)
		)
		(min_thickness 0.25)
		(keepout
			(tracks not_allowed)
			(vias allowed)
			(pads allowed)
			(copperpour not_allowed)
			(footprints allowed)
		)
		(placement
			(enabled no)
			(sheetname "")
		)
		(fill yes
			(thermal_gap 0.5)
			(thermal_bridge_width 0.5)
			(island_removal_mode 0)
		)
		(polygon
			(pts
				(arc
					(start 284.243272 -236.416596)
					(mid 283.590492 -236.416596)
					(end 284.243272 -236.416596)
				)
			)
		)
	)
	(zone
		(layers "B.Cu" "In6.Cu" "In11.Cu" "In13.Cu" "In15.Cu")
		(hatch none 0.5)
		(connect_pads
			(clearance 0)
		)
		(min_thickness 0.25)
		(keepout
			(tracks not_allowed)
			(vias allowed)
			(pads allowed)
			(copperpour not_allowed)
			(footprints allowed)
		)
		(placement
			(enabled no)
			(sheetname "")
		)
		(fill yes
			(thermal_gap 0.5)
			(thermal_bridge_width 0.5)
			(island_removal_mode 0)
		)
		(polygon
			(pts
				(arc
					(start 378.23267 -231.714548)
					(mid 377.57989 -231.714548)
					(end 378.23267 -231.714548)
				)
			)
		)
	)
	(zone
		(layers "B.Cu" "In6.Cu" "In11.Cu" "In13.Cu" "In15.Cu")
		(hatch none 0.5)
		(connect_pads
			(clearance 0)
		)
		(min_thickness 0.25)
		(keepout
			(tracks not_allowed)
			(vias allowed)
			(pads allowed)
			(copperpour not_allowed)
			(footprints allowed)
		)
		(placement
			(enabled no)
			(sheetname "")
		)
		(fill yes
			(thermal_gap 0.5)
			(thermal_bridge_width 0.5)
			(island_removal_mode 0)
		)
		(polygon
			(pts
				(arc
					(start 349.209106 -288.917126)
					(mid 348.556326 -288.917126)
					(end 349.209106 -288.917126)
				)
			)
		)
	)
	(zone
		(layers "B.Cu" "In6.Cu" "In11.Cu" "In13.Cu" "In15.Cu")
		(hatch none 0.5)
		(connect_pads
			(clearance 0)
		)
		(min_thickness 0.25)
		(keepout
			(tracks not_allowed)
			(vias allowed)
			(pads allowed)
			(copperpour not_allowed)
			(footprints allowed)
		)
		(placement
			(enabled no)
			(sheetname "")
		)
		(fill yes
			(thermal_gap 0.5)
			(thermal_bridge_width 0.5)
			(island_removal_mode 0)
		)
		(polygon
			(pts
				(arc
					(start 342.050624 -243.922804)
					(mid 341.397844 -243.922804)
					(end 342.050624 -243.922804)
				)
			)
		)
	)
	(zone
		(layers "B.Cu" "In6.Cu" "In11.Cu" "In13.Cu" "In15.Cu")
		(hatch none 0.5)
		(connect_pads
			(clearance 0)
		)
		(min_thickness 0.25)
		(keepout
			(tracks not_allowed)
			(vias allowed)
			(pads allowed)
			(copperpour not_allowed)
			(footprints allowed)
		)
		(placement
			(enabled no)
			(sheetname "")
		)
		(fill yes
			(thermal_gap 0.5)
			(thermal_bridge_width 0.5)
			(island_removal_mode 0)
		)
		(polygon
			(pts
				(arc
					(start 188.209936 -316.316614)
					(mid 187.557156 -316.316614)
					(end 188.209936 -316.316614)
				)
			)
		)
	)
	(zone
		(layers "B.Cu" "In6.Cu" "In11.Cu" "In13.Cu" "In15.Cu")
		(hatch none 0.5)
		(connect_pads
			(clearance 0)
		)
		(min_thickness 0.25)
		(keepout
			(tracks not_allowed)
			(vias allowed)
			(pads allowed)
			(copperpour not_allowed)
			(footprints allowed)
		)
		(placement
			(enabled no)
			(sheetname "")
		)
		(fill yes
			(thermal_gap 0.5)
			(thermal_bridge_width 0.5)
			(island_removal_mode 0)
		)
		(polygon
			(pts
				(arc
					(start 440.250072 -260.21665)
					(mid 439.597292 -260.21665)
					(end 440.250072 -260.21665)
				)
			)
		)
	)
	(zone
		(layers "B.Cu" "In6.Cu" "In11.Cu" "In13.Cu" "In15.Cu")
		(hatch none 0.5)
		(connect_pads
			(clearance 0)
		)
		(min_thickness 0.25)
		(keepout
			(tracks not_allowed)
			(vias allowed)
			(pads allowed)
			(copperpour not_allowed)
			(footprints allowed)
		)
		(placement
			(enabled no)
			(sheetname "")
		)
		(fill yes
			(thermal_gap 0.5)
			(thermal_bridge_width 0.5)
			(island_removal_mode 0)
		)
		(polygon
			(pts
				(arc
					(start 425.162472 -199.01662)
					(mid 424.509692 -199.01662)
					(end 425.162472 -199.01662)
				)
			)
		)
	)
	(zone
		(layers "B.Cu" "In6.Cu" "In11.Cu" "In13.Cu" "In15.Cu")
		(hatch none 0.5)
		(connect_pads
			(clearance 0)
		)
		(min_thickness 0.25)
		(keepout
			(tracks not_allowed)
			(vias allowed)
			(pads allowed)
			(copperpour not_allowed)
			(footprints allowed)
		)
		(placement
			(enabled no)
			(sheetname "")
		)
		(fill yes
			(thermal_gap 0.5)
			(thermal_bridge_width 0.5)
			(island_removal_mode 0)
		)
		(polygon
			(pts
				(arc
					(start 378.702824 -243.922804)
					(mid 378.050044 -243.922804)
					(end 378.702824 -243.922804)
				)
			)
		)
	)
	(zone
		(layers "B.Cu" "In6.Cu" "In11.Cu" "In13.Cu" "In15.Cu")
		(hatch none 0.5)
		(connect_pads
			(clearance 0)
		)
		(min_thickness 0.25)
		(keepout
			(tracks not_allowed)
			(vias allowed)
			(pads allowed)
			(copperpour not_allowed)
			(footprints allowed)
		)
		(placement
			(enabled no)
			(sheetname "")
		)
		(fill yes
			(thermal_gap 0.5)
			(thermal_bridge_width 0.5)
			(island_removal_mode 0)
		)
		(polygon
			(pts
				(arc
					(start 340.750906 -288.917126)
					(mid 340.098126 -288.917126)
					(end 340.750906 -288.917126)
				)
			)
		)
	)
	(zone
		(layers "B.Cu" "In6.Cu" "In11.Cu" "In13.Cu" "In15.Cu")
		(hatch none 0.5)
		(connect_pads
			(clearance 0)
		)
		(min_thickness 0.25)
		(keepout
			(tracks not_allowed)
			(vias allowed)
			(pads allowed)
			(copperpour not_allowed)
			(footprints allowed)
		)
		(placement
			(enabled no)
			(sheetname "")
		)
		(fill yes
			(thermal_gap 0.5)
			(thermal_bridge_width 0.5)
			(island_removal_mode 0)
		)
		(polygon
			(pts
				(arc
					(start 375.523252 -259.616956)
					(mid 374.870472 -259.616956)
					(end 375.523252 -259.616956)
				)
			)
		)
	)
	(zone
		(layers "B.Cu" "In6.Cu" "In11.Cu" "In13.Cu" "In15.Cu")
		(hatch none 0.5)
		(connect_pads
			(clearance 0)
		)
		(min_thickness 0.25)
		(keepout
			(tracks not_allowed)
			(vias allowed)
			(pads allowed)
			(copperpour not_allowed)
			(footprints allowed)
		)
		(placement
			(enabled no)
			(sheetname "")
		)
		(fill yes
			(thermal_gap 0.5)
			(thermal_bridge_width 0.5)
			(island_removal_mode 0)
		)
		(polygon
			(pts
				(arc
					(start 349.569024 -217.878406)
					(mid 348.916244 -217.878406)
					(end 349.569024 -217.878406)
				)
			)
		)
	)
	(zone
		(layers "B.Cu" "In6.Cu" "In11.Cu" "In13.Cu" "In15.Cu")
		(hatch none 0.5)
		(connect_pads
			(clearance 0)
		)
		(min_thickness 0.25)
		(keepout
			(tracks not_allowed)
			(vias allowed)
			(pads allowed)
			(copperpour not_allowed)
			(footprints allowed)
		)
		(placement
			(enabled no)
			(sheetname "")
		)
		(fill yes
			(thermal_gap 0.5)
			(thermal_bridge_width 0.5)
			(island_removal_mode 0)
		)
		(polygon
			(pts
				(arc
					(start 436.150004 -259.366766)
					(mid 435.497224 -259.366766)
					(end 436.150004 -259.366766)
				)
			)
		)
	)
	(zone
		(layers "B.Cu" "In6.Cu" "In11.Cu" "In13.Cu" "In15.Cu")
		(hatch none 0.5)
		(connect_pads
			(clearance 0)
		)
		(min_thickness 0.25)
		(keepout
			(tracks not_allowed)
			(vias allowed)
			(pads allowed)
			(copperpour not_allowed)
			(footprints allowed)
		)
		(placement
			(enabled no)
			(sheetname "")
		)
		(fill yes
			(thermal_gap 0.5)
			(thermal_bridge_width 0.5)
			(island_removal_mode 0)
		)
		(polygon
			(pts
				(arc
					(start 295.230804 -284.866588)
					(mid 294.578024 -284.866588)
					(end 295.230804 -284.866588)
				)
			)
		)
	)
	(zone
		(layers "B.Cu" "In6.Cu" "In11.Cu" "In13.Cu" "In15.Cu")
		(hatch none 0.5)
		(connect_pads
			(clearance 0)
		)
		(min_thickness 0.25)
		(keepout
			(tracks not_allowed)
			(vias allowed)
			(pads allowed)
			(copperpour not_allowed)
			(footprints allowed)
		)
		(placement
			(enabled no)
			(sheetname "")
		)
		(fill yes
			(thermal_gap 0.5)
			(thermal_bridge_width 0.5)
			(island_removal_mode 0)
		)
		(polygon
			(pts
				(arc
					(start 92.810584 -274.266914)
					(mid 92.157804 -274.266914)
					(end 92.810584 -274.266914)
				)
			)
		)
	)
	(zone
		(layers "B.Cu" "In6.Cu" "In11.Cu" "In13.Cu" "In15.Cu")
		(hatch none 0.5)
		(connect_pads
			(clearance 0)
		)
		(min_thickness 0.25)
		(keepout
			(tracks not_allowed)
			(vias allowed)
			(pads allowed)
			(copperpour not_allowed)
			(footprints allowed)
		)
		(placement
			(enabled no)
			(sheetname "")
		)
		(fill yes
			(thermal_gap 0.5)
			(thermal_bridge_width 0.5)
			(island_removal_mode 0)
		)
		(polygon
			(pts
				(arc
					(start 379.17247 -218.692222)
					(mid 378.51969 -218.692222)
					(end 379.17247 -218.692222)
				)
			)
		)
	)
	(zone
		(layers "B.Cu" "In6.Cu" "In11.Cu" "In13.Cu" "In15.Cu")
		(hatch none 0.5)
		(connect_pads
			(clearance 0)
		)
		(min_thickness 0.25)
		(keepout
			(tracks not_allowed)
			(vias allowed)
			(pads allowed)
			(copperpour not_allowed)
			(footprints allowed)
		)
		(placement
			(enabled no)
			(sheetname "")
		)
		(fill yes
			(thermal_gap 0.5)
			(thermal_bridge_width 0.5)
			(island_removal_mode 0)
		)
		(polygon
			(pts
				(arc
					(start 92.340938 -257.175254)
					(mid 91.688158 -257.175254)
					(end 92.340938 -257.175254)
				)
			)
		)
	)
	(zone
		(layers "B.Cu" "In6.Cu" "In11.Cu" "In13.Cu" "In15.Cu")
		(hatch none 0.5)
		(connect_pads
			(clearance 0)
		)
		(min_thickness 0.25)
		(keepout
			(tracks not_allowed)
			(vias allowed)
			(pads allowed)
			(copperpour not_allowed)
			(footprints allowed)
		)
		(placement
			(enabled no)
			(sheetname "")
		)
		(fill yes
			(thermal_gap 0.5)
			(thermal_bridge_width 0.5)
			(island_removal_mode 0)
		)
		(polygon
			(pts
				(arc
					(start 47.290736 -199.866758)
					(mid 46.637956 -199.866758)
					(end 47.290736 -199.866758)
				)
			)
		)
	)
	(zone
		(layers "B.Cu" "In6.Cu" "In11.Cu" "In13.Cu" "In15.Cu")
		(hatch none 0.5)
		(connect_pads
			(clearance 0)
		)
		(min_thickness 0.25)
		(keepout
			(tracks not_allowed)
			(vias allowed)
			(pads allowed)
			(copperpour not_allowed)
			(footprints allowed)
		)
		(placement
			(enabled no)
			(sheetname "")
		)
		(fill yes
			(thermal_gap 0.5)
			(thermal_bridge_width 0.5)
			(island_removal_mode 0)
		)
		(polygon
			(pts
				(arc
					(start 51.390804 -199.01662)
					(mid 50.738024 -199.01662)
					(end 51.390804 -199.01662)
				)
			)
		)
	)
	(zone
		(layers "B.Cu" "In6.Cu" "In11.Cu" "In13.Cu" "In15.Cu")
		(hatch none 0.5)
		(connect_pads
			(clearance 0)
		)
		(min_thickness 0.25)
		(keepout
			(tracks not_allowed)
			(vias allowed)
			(pads allowed)
			(copperpour not_allowed)
			(footprints allowed)
		)
		(placement
			(enabled no)
			(sheetname "")
		)
		(fill yes
			(thermal_gap 0.5)
			(thermal_bridge_width 0.5)
			(island_removal_mode 0)
		)
		(polygon
			(pts
				(arc
					(start 130.402584 -275.8948)
					(mid 129.749804 -275.8948)
					(end 130.402584 -275.8948)
				)
			)
		)
	)
	(zone
		(layers "B.Cu" "In6.Cu" "In11.Cu" "In13.Cu" "In15.Cu")
		(hatch none 0.5)
		(connect_pads
			(clearance 0)
		)
		(min_thickness 0.25)
		(keepout
			(tracks not_allowed)
			(vias allowed)
			(pads allowed)
			(copperpour not_allowed)
			(footprints allowed)
		)
		(placement
			(enabled no)
			(sheetname "")
		)
		(fill yes
			(thermal_gap 0.5)
			(thermal_bridge_width 0.5)
			(island_removal_mode 0)
		)
		(polygon
			(pts
				(arc
					(start 126.533402 -217.064336)
					(mid 125.880622 -217.064336)
					(end 126.533402 -217.064336)
				)
			)
		)
	)
	(zone
		(layers "B.Cu" "In6.Cu" "In11.Cu" "In13.Cu" "In15.Cu")
		(hatch none 0.5)
		(connect_pads
			(clearance 0)
		)
		(min_thickness 0.25)
		(keepout
			(tracks not_allowed)
			(vias allowed)
			(pads allowed)
			(copperpour not_allowed)
			(footprints allowed)
		)
		(placement
			(enabled no)
			(sheetname "")
		)
		(fill yes
			(thermal_gap 0.5)
			(thermal_bridge_width 0.5)
			(island_removal_mode 0)
		)
		(polygon
			(pts
				(arc
					(start 32.203136 -235.566712)
					(mid 31.550356 -235.566712)
					(end 32.203136 -235.566712)
				)
			)
		)
	)
	(zone
		(layers "B.Cu" "In6.Cu" "In11.Cu" "In13.Cu" "In15.Cu")
		(hatch none 0.5)
		(connect_pads
			(clearance 0)
		)
		(min_thickness 0.25)
		(keepout
			(tracks not_allowed)
			(vias allowed)
			(pads allowed)
			(copperpour not_allowed)
			(footprints allowed)
		)
		(placement
			(enabled no)
			(sheetname "")
		)
		(fill yes
			(thermal_gap 0.5)
			(thermal_bridge_width 0.5)
			(island_removal_mode 0)
		)
		(polygon
			(pts
				(arc
					(start 188.209936 -310.366664)
					(mid 187.557156 -310.366664)
					(end 188.209936 -310.366664)
				)
			)
		)
	)
	(zone
		(layers "B.Cu" "In6.Cu" "In11.Cu" "In13.Cu" "In15.Cu")
		(hatch none 0.5)
		(connect_pads
			(clearance 0)
		)
		(min_thickness 0.25)
		(keepout
			(tracks not_allowed)
			(vias allowed)
			(pads allowed)
			(copperpour not_allowed)
			(footprints allowed)
		)
		(placement
			(enabled no)
			(sheetname "")
		)
		(fill yes
			(thermal_gap 0.5)
			(thermal_bridge_width 0.5)
			(island_removal_mode 0)
		)
		(polygon
			(pts
				(arc
					(start 284.243272 -259.366766)
					(mid 283.590492 -259.366766)
					(end 284.243272 -259.366766)
				)
			)
		)
	)
	(zone
		(layers "B.Cu" "In6.Cu" "In11.Cu" "In13.Cu" "In15.Cu")
		(hatch none 0.5)
		(connect_pads
			(clearance 0)
		)
		(min_thickness 0.25)
		(keepout
			(tracks not_allowed)
			(vias allowed)
			(pads allowed)
			(copperpour not_allowed)
			(footprints allowed)
		)
		(placement
			(enabled no)
			(sheetname "")
		)
		(fill yes
			(thermal_gap 0.5)
			(thermal_bridge_width 0.5)
			(island_removal_mode 0)
		)
		(polygon
			(pts
				(arc
					(start 421.062404 -305.266598)
					(mid 420.409624 -305.266598)
					(end 421.062404 -305.266598)
				)
			)
		)
	)
	(zone
		(layers "B.Cu" "In6.Cu" "In11.Cu" "In13.Cu" "In15.Cu")
		(hatch none 0.5)
		(connect_pads
			(clearance 0)
		)
		(min_thickness 0.25)
		(keepout
			(tracks not_allowed)
			(vias allowed)
			(pads allowed)
			(copperpour not_allowed)
			(footprints allowed)
		)
		(placement
			(enabled no)
			(sheetname "")
		)
		(fill yes
			(thermal_gap 0.5)
			(thermal_bridge_width 0.5)
			(island_removal_mode 0)
		)
		(polygon
			(pts
				(arc
					(start 284.243272 -293.366698)
					(mid 283.590492 -293.366698)
					(end 284.243272 -293.366698)
				)
			)
		)
	)
	(zone
		(layers "B.Cu" "In6.Cu" "In11.Cu" "In13.Cu" "In15.Cu")
		(hatch none 0.5)
		(connect_pads
			(clearance 0)
		)
		(min_thickness 0.25)
		(keepout
			(tracks not_allowed)
			(vias allowed)
			(pads allowed)
			(copperpour not_allowed)
			(footprints allowed)
		)
		(placement
			(enabled no)
			(sheetname "")
		)
		(fill yes
			(thermal_gap 0.5)
			(thermal_bridge_width 0.5)
			(island_removal_mode 0)
		)
		(polygon
			(pts
				(arc
					(start 91.760802 -230.086662)
					(mid 91.108022 -230.086662)
					(end 91.760802 -230.086662)
				)
			)
		)
	)
	(zone
		(layers "B.Cu" "In6.Cu" "In11.Cu" "In13.Cu" "In15.Cu")
		(hatch none 0.5)
		(connect_pads
			(clearance 0)
		)
		(min_thickness 0.25)
		(keepout
			(tracks not_allowed)
			(vias allowed)
			(pads allowed)
			(copperpour not_allowed)
			(footprints allowed)
		)
		(placement
			(enabled no)
			(sheetname "")
		)
		(fill yes
			(thermal_gap 0.5)
			(thermal_bridge_width 0.5)
			(island_removal_mode 0)
		)
		(polygon
			(pts
				(arc
					(start 341.58047 -238.225584)
					(mid 340.92769 -238.225584)
					(end 341.58047 -238.225584)
				)
			)
		)
	)
	(zone
		(layers "B.Cu" "In6.Cu" "In11.Cu" "In13.Cu" "In15.Cu")
		(hatch none 0.5)
		(connect_pads
			(clearance 0)
		)
		(min_thickness 0.25)
		(keepout
			(tracks not_allowed)
			(vias allowed)
			(pads allowed)
			(copperpour not_allowed)
			(footprints allowed)
		)
		(placement
			(enabled no)
			(sheetname "")
		)
		(fill yes
			(thermal_gap 0.5)
			(thermal_bridge_width 0.5)
			(island_removal_mode 0)
		)
		(polygon
			(pts
				(arc
					(start 92.340938 -258.80314)
					(mid 91.688158 -258.80314)
					(end 92.340938 -258.80314)
				)
			)
		)
	)
	(zone
		(layers "B.Cu" "In6.Cu" "In11.Cu" "In13.Cu" "In15.Cu")
		(hatch none 0.5)
		(connect_pads
			(clearance 0)
		)
		(min_thickness 0.25)
		(keepout
			(tracks not_allowed)
			(vias allowed)
			(pads allowed)
			(copperpour not_allowed)
			(footprints allowed)
		)
		(placement
			(enabled no)
			(sheetname "")
		)
		(fill yes
			(thermal_gap 0.5)
			(thermal_bridge_width 0.5)
			(island_removal_mode 0)
		)
		(polygon
			(pts
				(arc
					(start 125.233938 -288.103056)
					(mid 124.581158 -288.103056)
					(end 125.233938 -288.103056)
				)
			)
		)
	)
	(zone
		(layers "B.Cu" "In6.Cu" "In11.Cu" "In13.Cu" "In15.Cu")
		(hatch none 0.5)
		(connect_pads
			(clearance 0)
		)
		(min_thickness 0.25)
		(keepout
			(tracks not_allowed)
			(vias allowed)
			(pads allowed)
			(copperpour not_allowed)
			(footprints allowed)
		)
		(placement
			(enabled no)
			(sheetname "")
		)
		(fill yes
			(thermal_gap 0.5)
			(thermal_bridge_width 0.5)
			(island_removal_mode 0)
		)
		(polygon
			(pts
				(arc
					(start 241.015774 -54.710838)
					(mid 240.312194 -54.710838)
					(end 241.015774 -54.710838)
				)
			)
		)
	)
	(zone
		(layers "B.Cu" "In6.Cu" "In11.Cu" "In13.Cu" "In15.Cu")
		(hatch none 0.5)
		(connect_pads
			(clearance 0)
		)
		(min_thickness 0.25)
		(keepout
			(tracks not_allowed)
			(vias allowed)
			(pads allowed)
			(copperpour not_allowed)
			(footprints allowed)
		)
		(placement
			(enabled no)
			(sheetname "")
		)
		(fill yes
			(thermal_gap 0.5)
			(thermal_bridge_width 0.5)
			(island_removal_mode 0)
		)
		(polygon
			(pts
				(arc
					(start 379.752606 -276.708616)
					(mid 379.099826 -276.708616)
					(end 379.752606 -276.708616)
				)
			)
		)
	)
	(zone
		(layers "B.Cu" "In6.Cu" "In11.Cu" "In13.Cu" "In15.Cu")
		(hatch none 0.5)
		(connect_pads
			(clearance 0)
		)
		(min_thickness 0.25)
		(keepout
			(tracks not_allowed)
			(vias allowed)
			(pads allowed)
			(copperpour not_allowed)
			(footprints allowed)
		)
		(placement
			(enabled no)
			(sheetname "")
		)
		(fill yes
			(thermal_gap 0.5)
			(thermal_bridge_width 0.5)
			(island_removal_mode 0)
		)
		(polygon
			(pts
				(arc
					(start 130.872738 -275.08073)
					(mid 130.219958 -275.08073)
					(end 130.872738 -275.08073)
				)
			)
		)
	)
	(zone
		(layers "B.Cu" "In6.Cu" "In11.Cu" "In13.Cu" "In15.Cu")
		(hatch none 0.5)
		(connect_pads
			(clearance 0)
		)
		(min_thickness 0.25)
		(keepout
			(tracks not_allowed)
			(vias allowed)
			(pads allowed)
			(copperpour not_allowed)
			(footprints allowed)
		)
		(placement
			(enabled no)
			(sheetname "")
		)
		(fill yes
			(thermal_gap 0.5)
			(thermal_bridge_width 0.5)
			(island_removal_mode 0)
		)
		(polygon
			(pts
				(arc
					(start 132.172202 -243.108988)
					(mid 131.519422 -243.108988)
					(end 132.172202 -243.108988)
				)
			)
		)
	)
	(zone
		(layers "B.Cu" "In6.Cu" "In11.Cu" "In13.Cu" "In15.Cu")
		(hatch none 0.5)
		(connect_pads
			(clearance 0)
		)
		(min_thickness 0.25)
		(keepout
			(tracks not_allowed)
			(vias allowed)
			(pads allowed)
			(copperpour not_allowed)
			(footprints allowed)
		)
		(placement
			(enabled no)
			(sheetname "")
		)
		(fill yes
			(thermal_gap 0.5)
			(thermal_bridge_width 0.5)
			(island_removal_mode 0)
		)
		(polygon
			(pts
				(arc
					(start 328.085704 5.895594)
					(mid 327.382124 5.895594)
					(end 328.085704 5.895594)
				)
			)
		)
	)
	(zone
		(layers "B.Cu" "In6.Cu" "In11.Cu" "In13.Cu" "In15.Cu")
		(hatch none 0.5)
		(connect_pads
			(clearance 0)
		)
		(min_thickness 0.25)
		(keepout
			(tracks not_allowed)
			(vias allowed)
			(pads allowed)
			(copperpour not_allowed)
			(footprints allowed)
		)
		(placement
			(enabled no)
			(sheetname "")
		)
		(fill yes
			(thermal_gap 0.5)
			(thermal_bridge_width 0.5)
			(island_removal_mode 0)
		)
		(polygon
			(pts
				(arc
					(start 368.83467 -217.064336)
					(mid 368.18189 -217.064336)
					(end 368.83467 -217.064336)
				)
			)
		)
	)
	(zone
		(layers "B.Cu" "In6.Cu" "In11.Cu" "In13.Cu" "In15.Cu")
		(hatch none 0.5)
		(connect_pads
			(clearance 0)
		)
		(min_thickness 0.25)
		(keepout
			(tracks not_allowed)
			(vias allowed)
			(pads allowed)
			(copperpour not_allowed)
			(footprints allowed)
		)
		(placement
			(enabled no)
			(sheetname "")
		)
		(fill yes
			(thermal_gap 0.5)
			(thermal_bridge_width 0.5)
			(island_removal_mode 0)
		)
		(polygon
			(pts
				(arc
					(start 94.580202 -217.064336)
					(mid 93.927422 -217.064336)
					(end 94.580202 -217.064336)
				)
			)
		)
	)
	(zone
		(layers "B.Cu" "In6.Cu" "In11.Cu" "In13.Cu" "In15.Cu")
		(hatch none 0.5)
		(connect_pads
			(clearance 0)
		)
		(min_thickness 0.25)
		(keepout
			(tracks not_allowed)
			(vias allowed)
			(pads allowed)
			(copperpour not_allowed)
			(footprints allowed)
		)
		(placement
			(enabled no)
			(sheetname "")
		)
		(fill yes
			(thermal_gap 0.5)
			(thermal_bridge_width 0.5)
			(island_removal_mode 0)
		)
		(polygon
			(pts
				(arc
					(start 295.230804 -301.01667)
					(mid 294.578024 -301.01667)
					(end 295.230804 -301.01667)
				)
			)
		)
	)
	(zone
		(layers "B.Cu" "In6.Cu" "In11.Cu" "In13.Cu" "In15.Cu")
		(hatch none 0.5)
		(connect_pads
			(clearance 0)
		)
		(min_thickness 0.25)
		(keepout
			(tracks not_allowed)
			(vias allowed)
			(pads allowed)
			(copperpour not_allowed)
			(footprints allowed)
		)
		(placement
			(enabled no)
			(sheetname "")
		)
		(fill yes
			(thermal_gap 0.5)
			(thermal_bridge_width 0.5)
			(island_removal_mode 0)
		)
		(polygon
			(pts
				(arc
					(start 280.143204 -247.466612)
					(mid 279.490424 -247.466612)
					(end 280.143204 -247.466612)
				)
			)
		)
	)
	(zone
		(layers "B.Cu" "In6.Cu" "In11.Cu" "In13.Cu" "In15.Cu")
		(hatch none 0.5)
		(connect_pads
			(clearance 0)
		)
		(min_thickness 0.25)
		(keepout
			(tracks not_allowed)
			(vias allowed)
			(pads allowed)
			(copperpour not_allowed)
			(footprints allowed)
		)
		(placement
			(enabled no)
			(sheetname "")
		)
		(fill yes
			(thermal_gap 0.5)
			(thermal_bridge_width 0.5)
			(island_removal_mode 0)
		)
		(polygon
			(pts
				(arc
					(start 378.812806 -273.453098)
					(mid 378.160026 -273.453098)
					(end 378.812806 -273.453098)
				)
			)
		)
	)
	(zone
		(layers "B.Cu" "In6.Cu" "In11.Cu" "In13.Cu" "In15.Cu")
		(hatch none 0.5)
		(connect_pads
			(clearance 0)
		)
		(min_thickness 0.25)
		(keepout
			(tracks not_allowed)
			(vias allowed)
			(pads allowed)
			(copperpour not_allowed)
			(footprints allowed)
		)
		(placement
			(enabled no)
			(sheetname "")
		)
		(fill yes
			(thermal_gap 0.5)
			(thermal_bridge_width 0.5)
			(island_removal_mode 0)
		)
		(polygon
			(pts
				(arc
					(start 122.304556 -217.878406)
					(mid 121.651776 -217.878406)
					(end 122.304556 -217.878406)
				)
			)
		)
	)
	(zone
		(layers "B.Cu" "In6.Cu" "In11.Cu" "In13.Cu" "In15.Cu")
		(hatch none 0.5)
		(connect_pads
			(clearance 0)
		)
		(min_thickness 0.25)
		(keepout
			(tracks not_allowed)
			(vias allowed)
			(pads allowed)
			(copperpour not_allowed)
			(footprints allowed)
		)
		(placement
			(enabled no)
			(sheetname "")
		)
		(fill yes
			(thermal_gap 0.5)
			(thermal_bridge_width 0.5)
			(island_removal_mode 0)
		)
		(polygon
			(pts
				(arc
					(start 284.243272 -289.11677)
					(mid 283.590492 -289.11677)
					(end 284.243272 -289.11677)
				)
			)
		)
	)
	(zone
		(layers "B.Cu" "In6.Cu" "In11.Cu" "In13.Cu" "In15.Cu")
		(hatch none 0.5)
		(connect_pads
			(clearance 0)
		)
		(min_thickness 0.25)
		(keepout
			(tracks not_allowed)
			(vias allowed)
			(pads allowed)
			(copperpour not_allowed)
			(footprints allowed)
		)
		(placement
			(enabled no)
			(sheetname "")
		)
		(fill yes
			(thermal_gap 0.5)
			(thermal_bridge_width 0.5)
			(island_removal_mode 0)
		)
		(polygon
			(pts
				(arc
					(start 132.172202 -231.714548)
					(mid 131.519422 -231.714548)
					(end 132.172202 -231.714548)
				)
			)
		)
	)
	(zone
		(layers "B.Cu" "In6.Cu" "In11.Cu" "In13.Cu" "In15.Cu")
		(hatch none 0.5)
		(connect_pads
			(clearance 0)
		)
		(min_thickness 0.25)
		(keepout
			(tracks not_allowed)
			(vias allowed)
			(pads allowed)
			(copperpour not_allowed)
			(footprints allowed)
		)
		(placement
			(enabled no)
			(sheetname "")
		)
		(fill yes
			(thermal_gap 0.5)
			(thermal_bridge_width 0.5)
			(island_removal_mode 0)
		)
		(polygon
			(pts
				(arc
					(start 380.582424 -237.411514)
					(mid 379.929644 -237.411514)
					(end 380.582424 -237.411514)
				)
			)
		)
	)
	(zone
		(layers "B.Cu" "In6.Cu" "In11.Cu" "In13.Cu" "In15.Cu")
		(hatch none 0.5)
		(connect_pads
			(clearance 0)
		)
		(min_thickness 0.25)
		(keepout
			(tracks not_allowed)
			(vias allowed)
			(pads allowed)
			(copperpour not_allowed)
			(footprints allowed)
		)
		(placement
			(enabled no)
			(sheetname "")
		)
		(fill yes
			(thermal_gap 0.5)
			(thermal_bridge_width 0.5)
			(island_removal_mode 0)
		)
		(polygon
			(pts
				(arc
					(start 130.402584 -266.128246)
					(mid 129.749804 -266.128246)
					(end 130.402584 -266.128246)
				)
			)
		)
	)
	(zone
		(layers "B.Cu" "In6.Cu" "In11.Cu" "In13.Cu" "In15.Cu")
		(hatch none 0.5)
		(connect_pads
			(clearance 0)
		)
		(min_thickness 0.25)
		(keepout
			(tracks not_allowed)
			(vias allowed)
			(pads allowed)
			(copperpour not_allowed)
			(footprints allowed)
		)
		(placement
			(enabled no)
			(sheetname "")
		)
		(fill yes
			(thermal_gap 0.5)
			(thermal_bridge_width 0.5)
			(island_removal_mode 0)
		)
		(polygon
			(pts
				(arc
					(start 120.894602 -217.064336)
					(mid 120.241822 -217.064336)
					(end 120.894602 -217.064336)
				)
			)
		)
	)
	(zone
		(layers "B.Cu" "In6.Cu" "In11.Cu" "In13.Cu" "In15.Cu")
		(hatch none 0.5)
		(connect_pads
			(clearance 0)
		)
		(min_thickness 0.25)
		(keepout
			(tracks not_allowed)
			(vias allowed)
			(pads allowed)
			(copperpour not_allowed)
			(footprints allowed)
		)
		(placement
			(enabled no)
			(sheetname "")
		)
		(fill yes
			(thermal_gap 0.5)
			(thermal_bridge_width 0.5)
			(island_removal_mode 0)
		)
		(polygon
			(pts
				(arc
					(start 173.122336 -200.716642)
					(mid 172.469556 -200.716642)
					(end 173.122336 -200.716642)
				)
			)
		)
	)
	(zone
		(layers "B.Cu" "In6.Cu" "In11.Cu" "In13.Cu" "In15.Cu")
		(hatch none 0.5)
		(connect_pads
			(clearance 0)
		)
		(min_thickness 0.25)
		(keepout
			(tracks not_allowed)
			(vias allowed)
			(pads allowed)
			(copperpour not_allowed)
			(footprints allowed)
		)
		(placement
			(enabled no)
			(sheetname "")
		)
		(fill yes
			(thermal_gap 0.5)
			(thermal_bridge_width 0.5)
			(island_removal_mode 0)
		)
		(polygon
			(pts
				(arc
					(start 341.58047 -241.481102)
					(mid 340.92769 -241.481102)
					(end 341.58047 -241.481102)
				)
			)
		)
	)
	(zone
		(layers "B.Cu" "In6.Cu" "In11.Cu" "In13.Cu" "In15.Cu")
		(hatch none 0.5)
		(connect_pads
			(clearance 0)
		)
		(min_thickness 0.25)
		(keepout
			(tracks not_allowed)
			(vias allowed)
			(pads allowed)
			(copperpour not_allowed)
			(footprints allowed)
		)
		(placement
			(enabled no)
			(sheetname "")
		)
		(fill yes
			(thermal_gap 0.5)
			(thermal_bridge_width 0.5)
			(island_removal_mode 0)
		)
		(polygon
			(pts
				(arc
					(start 378.812806 -270.19758)
					(mid 378.160026 -270.19758)
					(end 378.812806 -270.19758)
				)
			)
		)
	)
	(zone
		(layers "B.Cu" "In6.Cu" "In11.Cu" "In13.Cu" "In15.Cu")
		(hatch none 0.5)
		(connect_pads
			(clearance 0)
		)
		(min_thickness 0.25)
		(keepout
			(tracks not_allowed)
			(vias allowed)
			(pads allowed)
			(copperpour not_allowed)
			(footprints allowed)
		)
		(placement
			(enabled no)
			(sheetname "")
		)
		(fill yes
			(thermal_gap 0.5)
			(thermal_bridge_width 0.5)
			(island_removal_mode 0)
		)
		(polygon
			(pts
				(arc
					(start 378.702824 -245.55069)
					(mid 378.050044 -245.55069)
					(end 378.702824 -245.55069)
				)
			)
		)
	)
	(zone
		(layers "B.Cu" "In6.Cu" "In11.Cu" "In13.Cu" "In15.Cu")
		(hatch none 0.5)
		(connect_pads
			(clearance 0)
		)
		(min_thickness 0.25)
		(keepout
			(tracks not_allowed)
			(vias allowed)
			(pads allowed)
			(copperpour not_allowed)
			(footprints allowed)
		)
		(placement
			(enabled no)
			(sheetname "")
		)
		(fill yes
			(thermal_gap 0.5)
			(thermal_bridge_width 0.5)
			(island_removal_mode 0)
		)
		(polygon
			(pts
				(arc
					(start 94.690184 -257.98907)
					(mid 94.037404 -257.98907)
					(end 94.690184 -257.98907)
				)
			)
		)
	)
	(zone
		(layers "B.Cu" "In6.Cu" "In11.Cu" "In13.Cu" "In15.Cu")
		(hatch none 0.5)
		(connect_pads
			(clearance 0)
		)
		(min_thickness 0.25)
		(keepout
			(tracks not_allowed)
			(vias allowed)
			(pads allowed)
			(copperpour not_allowed)
			(footprints allowed)
		)
		(placement
			(enabled no)
			(sheetname "")
		)
		(fill yes
			(thermal_gap 0.5)
			(thermal_bridge_width 0.5)
			(island_removal_mode 0)
		)
		(polygon
			(pts
				(arc
					(start 129.932684 -289.807142)
					(mid 129.279904 -289.807142)
					(end 129.932684 -289.807142)
				)
			)
		)
	)
	(zone
		(layers "B.Cu" "In6.Cu" "In11.Cu" "In13.Cu" "In15.Cu")
		(hatch none 0.5)
		(connect_pads
			(clearance 0)
		)
		(min_thickness 0.25)
		(keepout
			(tracks not_allowed)
			(vias allowed)
			(pads allowed)
			(copperpour not_allowed)
			(footprints allowed)
		)
		(placement
			(enabled no)
			(sheetname "")
		)
		(fill yes
			(thermal_gap 0.5)
			(thermal_bridge_width 0.5)
			(island_removal_mode 0)
		)
		(polygon
			(pts
				(arc
					(start 340.750652 -254.733552)
					(mid 340.097872 -254.733552)
					(end 340.750652 -254.733552)
				)
			)
		)
	)
	(zone
		(layers "B.Cu" "In6.Cu" "In11.Cu" "In13.Cu" "In15.Cu")
		(hatch none 0.5)
		(connect_pads
			(clearance 0)
		)
		(min_thickness 0.25)
		(keepout
			(tracks not_allowed)
			(vias allowed)
			(pads allowed)
			(copperpour not_allowed)
			(footprints allowed)
		)
		(placement
			(enabled no)
			(sheetname "")
		)
		(fill yes
			(thermal_gap 0.5)
			(thermal_bridge_width 0.5)
			(island_removal_mode 0)
		)
		(polygon
			(pts
				(arc
					(start 347.689424 -217.878406)
					(mid 347.036644 -217.878406)
					(end 347.689424 -217.878406)
				)
			)
		)
	)
	(zone
		(layers "B.Cu" "In6.Cu" "In11.Cu" "In13.Cu" "In15.Cu")
		(hatch none 0.5)
		(connect_pads
			(clearance 0)
		)
		(min_thickness 0.25)
		(keepout
			(tracks not_allowed)
			(vias allowed)
			(pads allowed)
			(copperpour not_allowed)
			(footprints allowed)
		)
		(placement
			(enabled no)
			(sheetname "")
		)
		(fill yes
			(thermal_gap 0.5)
			(thermal_bridge_width 0.5)
			(island_removal_mode 0)
		)
		(polygon
			(pts
				(arc
					(start 131.812538 -258.80314)
					(mid 131.159758 -258.80314)
					(end 131.812538 -258.80314)
				)
			)
		)
	)
	(zone
		(layers "B.Cu" "In6.Cu" "In11.Cu" "In13.Cu" "In15.Cu")
		(hatch none 0.5)
		(connect_pads
			(clearance 0)
		)
		(min_thickness 0.25)
		(keepout
			(tracks not_allowed)
			(vias allowed)
			(pads allowed)
			(copperpour not_allowed)
			(footprints allowed)
		)
		(placement
			(enabled no)
			(sheetname "")
		)
		(fill yes
			(thermal_gap 0.5)
			(thermal_bridge_width 0.5)
			(island_removal_mode 0)
		)
		(polygon
			(pts
				(arc
					(start 379.282706 -288.917126)
					(mid 378.629926 -288.917126)
					(end 379.282706 -288.917126)
				)
			)
		)
	)
	(zone
		(layers "B.Cu" "In6.Cu" "In11.Cu" "In13.Cu" "In15.Cu")
		(hatch none 0.5)
		(connect_pads
			(clearance 0)
		)
		(min_thickness 0.25)
		(keepout
			(tracks not_allowed)
			(vias allowed)
			(pads allowed)
			(copperpour not_allowed)
			(footprints allowed)
		)
		(placement
			(enabled no)
			(sheetname "")
		)
		(fill yes
			(thermal_gap 0.5)
			(thermal_bridge_width 0.5)
			(island_removal_mode 0)
		)
		(polygon
			(pts
				(arc
					(start 340.171024 -234.15625)
					(mid 339.518244 -234.15625)
					(end 340.171024 -234.15625)
				)
			)
		)
	)
	(zone
		(layers "B.Cu" "In6.Cu" "In11.Cu" "In13.Cu" "In15.Cu")
		(hatch none 0.5)
		(connect_pads
			(clearance 0)
		)
		(min_thickness 0.25)
		(keepout
			(tracks not_allowed)
			(vias allowed)
			(pads allowed)
			(copperpour not_allowed)
			(footprints allowed)
		)
		(placement
			(enabled no)
			(sheetname "")
		)
		(fill yes
			(thermal_gap 0.5)
			(thermal_bridge_width 0.5)
			(island_removal_mode 0)
		)
		(polygon
			(pts
				(arc
					(start 341.690452 -262.872474)
					(mid 341.037672 -262.872474)
					(end 341.690452 -262.872474)
				)
			)
		)
	)
	(zone
		(layers "B.Cu" "In6.Cu" "In11.Cu" "In13.Cu" "In15.Cu")
		(hatch none 0.5)
		(connect_pads
			(clearance 0)
		)
		(min_thickness 0.25)
		(keepout
			(tracks not_allowed)
			(vias allowed)
			(pads allowed)
			(copperpour not_allowed)
			(footprints allowed)
		)
		(placement
			(enabled no)
			(sheetname "")
		)
		(fill yes
			(thermal_gap 0.5)
			(thermal_bridge_width 0.5)
			(island_removal_mode 0)
		)
		(polygon
			(pts
				(arc
					(start 132.282184 -264.50036)
					(mid 131.629404 -264.50036)
					(end 132.282184 -264.50036)
				)
			)
		)
	)
	(zone
		(layers "B.Cu" "In6.Cu" "In11.Cu" "In13.Cu" "In15.Cu")
		(hatch none 0.5)
		(connect_pads
			(clearance 0)
		)
		(min_thickness 0.25)
		(keepout
			(tracks not_allowed)
			(vias allowed)
			(pads allowed)
			(copperpour not_allowed)
			(footprints allowed)
		)
		(placement
			(enabled no)
			(sheetname "")
		)
		(fill yes
			(thermal_gap 0.5)
			(thermal_bridge_width 0.5)
			(island_removal_mode 0)
		)
		(polygon
			(pts
				(arc
					(start 346.27947 -217.064336)
					(mid 345.62669 -217.064336)
					(end 346.27947 -217.064336)
				)
			)
		)
	)
	(zone
		(layers "B.Cu" "In6.Cu" "In11.Cu" "In13.Cu" "In15.Cu")
		(hatch none 0.5)
		(connect_pads
			(clearance 0)
		)
		(min_thickness 0.25)
		(keepout
			(tracks not_allowed)
			(vias allowed)
			(pads allowed)
			(copperpour not_allowed)
			(footprints allowed)
		)
		(placement
			(enabled no)
			(sheetname "")
		)
		(fill yes
			(thermal_gap 0.5)
			(thermal_bridge_width 0.5)
			(island_removal_mode 0)
		)
		(polygon
			(pts
				(arc
					(start 341.690452 -264.50036)
					(mid 341.037672 -264.50036)
					(end 341.690452 -264.50036)
				)
			)
		)
	)
	(zone
		(layers "B.Cu" "In6.Cu" "In11.Cu" "In13.Cu" "In15.Cu")
		(hatch none 0.5)
		(connect_pads
			(clearance 0)
		)
		(min_thickness 0.25)
		(keepout
			(tracks not_allowed)
			(vias allowed)
			(pads allowed)
			(copperpour not_allowed)
			(footprints allowed)
		)
		(placement
			(enabled no)
			(sheetname "")
		)
		(fill yes
			(thermal_gap 0.5)
			(thermal_bridge_width 0.5)
			(island_removal_mode 0)
		)
		(polygon
			(pts
				(arc
					(start 92.340938 -278.336502)
					(mid 91.688158 -278.336502)
					(end 92.340938 -278.336502)
				)
			)
		)
	)
	(zone
		(layers "B.Cu" "In6.Cu" "In11.Cu" "In13.Cu" "In15.Cu")
		(hatch none 0.5)
		(connect_pads
			(clearance 0)
		)
		(min_thickness 0.25)
		(keepout
			(tracks not_allowed)
			(vias allowed)
			(pads allowed)
			(copperpour not_allowed)
			(footprints allowed)
		)
		(placement
			(enabled no)
			(sheetname "")
		)
		(fill yes
			(thermal_gap 0.5)
			(thermal_bridge_width 0.5)
			(island_removal_mode 0)
		)
		(polygon
			(pts
				(arc
					(start 177.222404 -287.416748)
					(mid 176.569624 -287.416748)
					(end 177.222404 -287.416748)
				)
			)
		)
	)
	(zone
		(layers "B.Cu" "In6.Cu" "In11.Cu" "In13.Cu" "In15.Cu")
		(hatch none 0.5)
		(connect_pads
			(clearance 0)
		)
		(min_thickness 0.25)
		(keepout
			(tracks not_allowed)
			(vias allowed)
			(pads allowed)
			(copperpour not_allowed)
			(footprints allowed)
		)
		(placement
			(enabled no)
			(sheetname "")
		)
		(fill yes
			(thermal_gap 0.5)
			(thermal_bridge_width 0.5)
			(island_removal_mode 0)
		)
		(polygon
			(pts
				(arc
					(start 130.402584 -264.50036)
					(mid 129.749804 -264.50036)
					(end 130.402584 -264.50036)
				)
			)
		)
	)
	(zone
		(layers "B.Cu" "In6.Cu" "In11.Cu" "In13.Cu" "In15.Cu")
		(hatch none 0.5)
		(connect_pads
			(clearance 0)
		)
		(min_thickness 0.25)
		(keepout
			(tracks not_allowed)
			(vias allowed)
			(pads allowed)
			(copperpour not_allowed)
			(footprints allowed)
		)
		(placement
			(enabled no)
			(sheetname "")
		)
		(fill yes
			(thermal_gap 0.5)
			(thermal_bridge_width 0.5)
			(island_removal_mode 0)
		)
		(polygon
			(pts
				(arc
					(start 132.282438 -288.917126)
					(mid 131.629658 -288.917126)
					(end 132.282438 -288.917126)
				)
			)
		)
	)
	(zone
		(layers "B.Cu" "In6.Cu" "In11.Cu" "In13.Cu" "In15.Cu")
		(hatch none 0.5)
		(connect_pads
			(clearance 0)
		)
		(min_thickness 0.25)
		(keepout
			(tracks not_allowed)
			(vias allowed)
			(pads allowed)
			(copperpour not_allowed)
			(footprints allowed)
		)
		(placement
			(enabled no)
			(sheetname "")
		)
		(fill yes
			(thermal_gap 0.5)
			(thermal_bridge_width 0.5)
			(island_removal_mode 0)
		)
		(polygon
			(pts
				(arc
					(start 130.292602 -247.992138)
					(mid 129.639822 -247.992138)
					(end 130.292602 -247.992138)
				)
			)
		)
	)
	(zone
		(layers "B.Cu" "In6.Cu" "In11.Cu" "In13.Cu" "In15.Cu")
		(hatch none 0.5)
		(connect_pads
			(clearance 0)
		)
		(min_thickness 0.25)
		(keepout
			(tracks not_allowed)
			(vias allowed)
			(pads allowed)
			(copperpour not_allowed)
			(footprints allowed)
		)
		(placement
			(enabled no)
			(sheetname "")
		)
		(fill yes
			(thermal_gap 0.5)
			(thermal_bridge_width 0.5)
			(island_removal_mode 0)
		)
		(polygon
			(pts
				(arc
					(start 421.062404 -199.866758)
					(mid 420.409624 -199.866758)
					(end 421.062404 -199.866758)
				)
			)
		)
	)
	(zone
		(layers "B.Cu" "In6.Cu" "In11.Cu" "In13.Cu" "In15.Cu")
		(hatch none 0.5)
		(connect_pads
			(clearance 0)
		)
		(min_thickness 0.25)
		(keepout
			(tracks not_allowed)
			(vias allowed)
			(pads allowed)
			(copperpour not_allowed)
			(footprints allowed)
		)
		(placement
			(enabled no)
			(sheetname "")
		)
		(fill yes
			(thermal_gap 0.5)
			(thermal_bridge_width 0.5)
			(island_removal_mode 0)
		)
		(polygon
			(pts
				(arc
					(start 284.243272 -204.96657)
					(mid 283.590492 -204.96657)
					(end 284.243272 -204.96657)
				)
			)
		)
	)
	(zone
		(layers "B.Cu" "In6.Cu" "In11.Cu" "In13.Cu" "In15.Cu")
		(hatch none 0.5)
		(connect_pads
			(clearance 0)
		)
		(min_thickness 0.25)
		(keepout
			(tracks not_allowed)
			(vias allowed)
			(pads allowed)
			(copperpour not_allowed)
			(footprints allowed)
		)
		(placement
			(enabled no)
			(sheetname "")
		)
		(fill yes
			(thermal_gap 0.5)
			(thermal_bridge_width 0.5)
			(island_removal_mode 0)
		)
		(polygon
			(pts
				(arc
					(start 51.416204 -306.116736)
					(mid 50.763424 -306.116736)
					(end 51.416204 -306.116736)
				)
			)
		)
	)
	(zone
		(layers "B.Cu" "In6.Cu" "In11.Cu" "In13.Cu" "In15.Cu")
		(hatch none 0.5)
		(connect_pads
			(clearance 0)
		)
		(min_thickness 0.25)
		(keepout
			(tracks not_allowed)
			(vias allowed)
			(pads allowed)
			(copperpour not_allowed)
			(footprints allowed)
		)
		(placement
			(enabled no)
			(sheetname "")
		)
		(fill yes
			(thermal_gap 0.5)
			(thermal_bridge_width 0.5)
			(island_removal_mode 0)
		)
		(polygon
			(pts
				(arc
					(start 177.222404 -284.016704)
					(mid 176.569624 -284.016704)
					(end 177.222404 -284.016704)
				)
			)
		)
	)
	(zone
		(layers "B.Cu" "In6.Cu" "In11.Cu" "In13.Cu" "In15.Cu")
		(hatch none 0.5)
		(connect_pads
			(clearance 0)
		)
		(min_thickness 0.25)
		(keepout
			(tracks not_allowed)
			(vias allowed)
			(pads allowed)
			(copperpour not_allowed)
			(footprints allowed)
		)
		(placement
			(enabled no)
			(sheetname "")
		)
		(fill yes
			(thermal_gap 0.5)
			(thermal_bridge_width 0.5)
			(island_removal_mode 0)
		)
		(polygon
			(pts
				(arc
					(start 116.665756 -217.878406)
					(mid 116.012976 -217.878406)
					(end 116.665756 -217.878406)
				)
			)
		)
	)
	(zone
		(layers "B.Cu" "In6.Cu" "In11.Cu" "In13.Cu" "In15.Cu")
		(hatch none 0.5)
		(connect_pads
			(clearance 0)
		)
		(min_thickness 0.25)
		(keepout
			(tracks not_allowed)
			(vias allowed)
			(pads allowed)
			(copperpour not_allowed)
			(footprints allowed)
		)
		(placement
			(enabled no)
			(sheetname "")
		)
		(fill yes
			(thermal_gap 0.5)
			(thermal_bridge_width 0.5)
			(island_removal_mode 0)
		)
		(polygon
			(pts
				(arc
					(start 340.281006 -253.919736)
					(mid 339.628226 -253.919736)
					(end 340.281006 -253.919736)
				)
			)
		)
	)
	(zone
		(layers "B.Cu" "In6.Cu" "In11.Cu" "In13.Cu" "In15.Cu")
		(hatch none 0.5)
		(connect_pads
			(clearance 0)
		)
		(min_thickness 0.25)
		(keepout
			(tracks not_allowed)
			(vias allowed)
			(pads allowed)
			(copperpour not_allowed)
			(footprints allowed)
		)
		(placement
			(enabled no)
			(sheetname "")
		)
		(fill yes
			(thermal_gap 0.5)
			(thermal_bridge_width 0.5)
			(island_removal_mode 0)
		)
		(polygon
			(pts
				(arc
					(start 173.122336 -196.466714)
					(mid 172.469556 -196.466714)
					(end 173.122336 -196.466714)
				)
			)
		)
	)
	(zone
		(layers "B.Cu" "In6.Cu" "In11.Cu" "In13.Cu" "In15.Cu")
		(hatch none 0.5)
		(connect_pads
			(clearance 0)
		)
		(min_thickness 0.25)
		(keepout
			(tracks not_allowed)
			(vias allowed)
			(pads allowed)
			(copperpour not_allowed)
			(footprints allowed)
		)
		(placement
			(enabled no)
			(sheetname "")
		)
		(fill yes
			(thermal_gap 0.5)
			(thermal_bridge_width 0.5)
			(island_removal_mode 0)
		)
		(polygon
			(pts
				(arc
					(start 340.171024 -230.900478)
					(mid 339.518244 -230.900478)
					(end 340.171024 -230.900478)
				)
			)
		)
	)
	(zone
		(layers "B.Cu" "In6.Cu" "In11.Cu" "In13.Cu" "In15.Cu")
		(hatch none 0.5)
		(connect_pads
			(clearance 0)
		)
		(min_thickness 0.25)
		(keepout
			(tracks not_allowed)
			(vias allowed)
			(pads allowed)
			(copperpour not_allowed)
			(footprints allowed)
		)
		(placement
			(enabled no)
			(sheetname "")
		)
		(fill yes
			(thermal_gap 0.5)
			(thermal_bridge_width 0.5)
			(island_removal_mode 0)
		)
		(polygon
			(pts
				(arc
					(start 32.203136 -293.366698)
					(mid 31.550356 -293.366698)
					(end 32.203136 -293.366698)
				)
			)
		)
	)
	(zone
		(layers "B.Cu" "In6.Cu" "In11.Cu" "In13.Cu" "In15.Cu")
		(hatch none 0.5)
		(connect_pads
			(clearance 0)
		)
		(min_thickness 0.25)
		(keepout
			(tracks not_allowed)
			(vias allowed)
			(pads allowed)
			(copperpour not_allowed)
			(footprints allowed)
		)
		(placement
			(enabled no)
			(sheetname "")
		)
		(fill yes
			(thermal_gap 0.5)
			(thermal_bridge_width 0.5)
			(island_removal_mode 0)
		)
		(polygon
			(pts
				(arc
					(start 32.203136 -252.566678)
					(mid 31.550356 -252.566678)
					(end 32.203136 -252.566678)
				)
			)
		)
	)
	(zone
		(layers "B.Cu" "In6.Cu" "In11.Cu" "In13.Cu" "In15.Cu")
		(hatch none 0.5)
		(connect_pads
			(clearance 0)
		)
		(min_thickness 0.25)
		(keepout
			(tracks not_allowed)
			(vias allowed)
			(pads allowed)
			(copperpour not_allowed)
			(footprints allowed)
		)
		(placement
			(enabled no)
			(sheetname "")
		)
		(fill yes
			(thermal_gap 0.5)
			(thermal_bridge_width 0.5)
			(island_removal_mode 0)
		)
		(polygon
			(pts
				(arc
					(start 378.812806 -271.825212)
					(mid 378.160026 -271.825212)
					(end 378.812806 -271.825212)
				)
			)
		)
	)
	(zone
		(layers "B.Cu" "In6.Cu" "In11.Cu" "In13.Cu" "In15.Cu")
		(hatch none 0.5)
		(connect_pads
			(clearance 0)
		)
		(min_thickness 0.25)
		(keepout
			(tracks not_allowed)
			(vias allowed)
			(pads allowed)
			(copperpour not_allowed)
			(footprints allowed)
		)
		(placement
			(enabled no)
			(sheetname "")
		)
		(fill yes
			(thermal_gap 0.5)
			(thermal_bridge_width 0.5)
			(island_removal_mode 0)
		)
		(polygon
			(pts
				(arc
					(start 378.702824 -234.15625)
					(mid 378.050044 -234.15625)
					(end 378.702824 -234.15625)
				)
			)
		)
	)
	(zone
		(layers "B.Cu" "In6.Cu" "In11.Cu" "In13.Cu" "In15.Cu")
		(hatch none 0.5)
		(connect_pads
			(clearance 0)
		)
		(min_thickness 0.25)
		(keepout
			(tracks not_allowed)
			(vias allowed)
			(pads allowed)
			(copperpour not_allowed)
			(footprints allowed)
		)
		(placement
			(enabled no)
			(sheetname "")
		)
		(fill yes
			(thermal_gap 0.5)
			(thermal_bridge_width 0.5)
			(island_removal_mode 0)
		)
		(polygon
			(pts
				(arc
					(start 177.222404 -229.616762)
					(mid 176.569624 -229.616762)
					(end 177.222404 -229.616762)
				)
			)
		)
	)
	(zone
		(layers "B.Cu" "In6.Cu" "In11.Cu" "In13.Cu" "In15.Cu")
		(hatch none 0.5)
		(connect_pads
			(clearance 0)
		)
		(min_thickness 0.25)
		(keepout
			(tracks not_allowed)
			(vias allowed)
			(pads allowed)
			(copperpour not_allowed)
			(footprints allowed)
		)
		(placement
			(enabled no)
			(sheetname "")
		)
		(fill yes
			(thermal_gap 0.5)
			(thermal_bridge_width 0.5)
			(island_removal_mode 0)
		)
		(polygon
			(pts
				(arc
					(start 132.172202 -217.064336)
					(mid 131.519422 -217.064336)
					(end 132.172202 -217.064336)
				)
			)
		)
	)
	(zone
		(layers "B.Cu" "In6.Cu" "In11.Cu" "In13.Cu" "In15.Cu")
		(hatch none 0.5)
		(connect_pads
			(clearance 0)
		)
		(min_thickness 0.25)
		(keepout
			(tracks not_allowed)
			(vias allowed)
			(pads allowed)
			(copperpour not_allowed)
			(footprints allowed)
		)
		(placement
			(enabled no)
			(sheetname "")
		)
		(fill yes
			(thermal_gap 0.5)
			(thermal_bridge_width 0.5)
			(island_removal_mode 0)
		)
		(polygon
			(pts
				(arc
					(start 192.310004 -236.416596)
					(mid 191.657224 -236.416596)
					(end 192.310004 -236.416596)
				)
			)
		)
	)
	(zone
		(layers "B.Cu" "In6.Cu" "In11.Cu" "In13.Cu" "In15.Cu")
		(hatch none 0.5)
		(connect_pads
			(clearance 0)
		)
		(min_thickness 0.25)
		(keepout
			(tracks not_allowed)
			(vias allowed)
			(pads allowed)
			(copperpour not_allowed)
			(footprints allowed)
		)
		(placement
			(enabled no)
			(sheetname "")
		)
		(fill yes
			(thermal_gap 0.5)
			(thermal_bridge_width 0.5)
			(island_removal_mode 0)
		)
		(polygon
			(pts
				(arc
					(start 93.750384 -261.244842)
					(mid 93.097604 -261.244842)
					(end 93.750384 -261.244842)
				)
			)
		)
	)
	(zone
		(layers "B.Cu" "In6.Cu" "In11.Cu" "In13.Cu" "In15.Cu")
		(hatch none 0.5)
		(connect_pads
			(clearance 0)
		)
		(min_thickness 0.25)
		(keepout
			(tracks not_allowed)
			(vias allowed)
			(pads allowed)
			(copperpour not_allowed)
			(footprints allowed)
		)
		(placement
			(enabled no)
			(sheetname "")
		)
		(fill yes
			(thermal_gap 0.5)
			(thermal_bridge_width 0.5)
			(island_removal_mode 0)
		)
		(polygon
			(pts
				(arc
					(start 425.162472 -279.766776)
					(mid 424.509692 -279.766776)
					(end 425.162472 -279.766776)
				)
			)
		)
	)
	(zone
		(layers "B.Cu" "In6.Cu" "In11.Cu" "In13.Cu" "In15.Cu")
		(hatch none 0.5)
		(connect_pads
			(clearance 0)
		)
		(min_thickness 0.25)
		(keepout
			(tracks not_allowed)
			(vias allowed)
			(pads allowed)
			(copperpour not_allowed)
			(footprints allowed)
		)
		(placement
			(enabled no)
			(sheetname "")
		)
		(fill yes
			(thermal_gap 0.5)
			(thermal_bridge_width 0.5)
			(island_removal_mode 0)
		)
		(polygon
			(pts
				(arc
					(start 421.062404 -282.316682)
					(mid 420.409624 -282.316682)
					(end 421.062404 -282.316682)
				)
			)
		)
	)
	(zone
		(layers "B.Cu" "In6.Cu" "In11.Cu" "In13.Cu" "In15.Cu")
		(hatch none 0.5)
		(connect_pads
			(clearance 0)
		)
		(min_thickness 0.25)
		(keepout
			(tracks not_allowed)
			(vias allowed)
			(pads allowed)
			(copperpour not_allowed)
			(footprints allowed)
		)
		(placement
			(enabled no)
			(sheetname "")
		)
		(fill yes
			(thermal_gap 0.5)
			(thermal_bridge_width 0.5)
			(island_removal_mode 0)
		)
		(polygon
			(pts
				(arc
					(start 340.281006 -273.453098)
					(mid 339.628226 -273.453098)
					(end 340.281006 -273.453098)
				)
			)
		)
	)
	(zone
		(layers "B.Cu" "In6.Cu" "In11.Cu" "In13.Cu" "In15.Cu")
		(hatch none 0.5)
		(connect_pads
			(clearance 0)
		)
		(min_thickness 0.25)
		(keepout
			(tracks not_allowed)
			(vias allowed)
			(pads allowed)
			(copperpour not_allowed)
			(footprints allowed)
		)
		(placement
			(enabled no)
			(sheetname "")
		)
		(fill yes
			(thermal_gap 0.5)
			(thermal_bridge_width 0.5)
			(island_removal_mode 0)
		)
		(polygon
			(pts
				(arc
					(start 436.150004 -262.766556)
					(mid 435.497224 -262.766556)
					(end 436.150004 -262.766556)
				)
			)
		)
	)
	(zone
		(layers "B.Cu" "In6.Cu" "In11.Cu" "In13.Cu" "In15.Cu")
		(hatch none 0.5)
		(connect_pads
			(clearance 0)
		)
		(min_thickness 0.25)
		(keepout
			(tracks not_allowed)
			(vias allowed)
			(pads allowed)
			(copperpour not_allowed)
			(footprints allowed)
		)
		(placement
			(enabled no)
			(sheetname "")
		)
		(fill yes
			(thermal_gap 0.5)
			(thermal_bridge_width 0.5)
			(island_removal_mode 0)
		)
		(polygon
			(pts
				(arc
					(start 173.122336 -303.566576)
					(mid 172.469556 -303.566576)
					(end 173.122336 -303.566576)
				)
			)
		)
	)
	(zone
		(layers "B.Cu" "In6.Cu" "In11.Cu" "In13.Cu" "In15.Cu")
		(hatch none 0.5)
		(connect_pads
			(clearance 0)
		)
		(min_thickness 0.25)
		(keepout
			(tracks not_allowed)
			(vias allowed)
			(pads allowed)
			(copperpour not_allowed)
			(footprints allowed)
		)
		(placement
			(enabled no)
			(sheetname "")
		)
		(fill yes
			(thermal_gap 0.5)
			(thermal_bridge_width 0.5)
			(island_removal_mode 0)
		)
		(polygon
			(pts
				(arc
					(start 375.41327 -218.692222)
					(mid 374.76049 -218.692222)
					(end 375.41327 -218.692222)
				)
			)
		)
	)
	(zone
		(layers "B.Cu" "In6.Cu" "In11.Cu" "In13.Cu" "In15.Cu")
		(hatch none 0.5)
		(connect_pads
			(clearance 0)
		)
		(min_thickness 0.25)
		(keepout
			(tracks not_allowed)
			(vias allowed)
			(pads allowed)
			(copperpour not_allowed)
			(footprints allowed)
		)
		(placement
			(enabled no)
			(sheetname "")
		)
		(fill yes
			(thermal_gap 0.5)
			(thermal_bridge_width 0.5)
			(island_removal_mode 0)
		)
		(polygon
			(pts
				(arc
					(start 87.062056 -223.575626)
					(mid 86.409276 -223.575626)
					(end 87.062056 -223.575626)
				)
			)
		)
	)
	(zone
		(layers "B.Cu" "In6.Cu" "In11.Cu" "In13.Cu" "In15.Cu")
		(hatch none 0.5)
		(connect_pads
			(clearance 0)
		)
		(min_thickness 0.25)
		(keepout
			(tracks not_allowed)
			(vias allowed)
			(pads allowed)
			(copperpour not_allowed)
			(footprints allowed)
		)
		(placement
			(enabled no)
			(sheetname "")
		)
		(fill yes
			(thermal_gap 0.5)
			(thermal_bridge_width 0.5)
			(island_removal_mode 0)
		)
		(polygon
			(pts
				(arc
					(start 425.162472 -199.866758)
					(mid 424.509692 -199.866758)
					(end 425.162472 -199.866758)
				)
			)
		)
	)
	(zone
		(layers "B.Cu" "In6.Cu" "In11.Cu" "In13.Cu" "In15.Cu")
		(hatch none 0.5)
		(connect_pads
			(clearance 0)
		)
		(min_thickness 0.25)
		(keepout
			(tracks not_allowed)
			(vias allowed)
			(pads allowed)
			(copperpour not_allowed)
			(footprints allowed)
		)
		(placement
			(enabled no)
			(sheetname "")
		)
		(fill yes
			(thermal_gap 0.5)
			(thermal_bridge_width 0.5)
			(island_removal_mode 0)
		)
		(polygon
			(pts
				(arc
					(start 276.699472 -267.016738)
					(mid 276.046692 -267.016738)
					(end 276.699472 -267.016738)
				)
			)
		)
	)
	(zone
		(layers "B.Cu" "In6.Cu" "In11.Cu" "In13.Cu" "In15.Cu")
		(hatch none 0.5)
		(connect_pads
			(clearance 0)
		)
		(min_thickness 0.25)
		(keepout
			(tracks not_allowed)
			(vias allowed)
			(pads allowed)
			(copperpour not_allowed)
			(footprints allowed)
		)
		(placement
			(enabled no)
			(sheetname "")
		)
		(fill yes
			(thermal_gap 0.5)
			(thermal_bridge_width 0.5)
			(island_removal_mode 0)
		)
		(polygon
			(pts
				(arc
					(start 94.220538 -268.569694)
					(mid 93.567758 -268.569694)
					(end 94.220538 -268.569694)
				)
			)
		)
	)
	(zone
		(layers "B.Cu" "In6.Cu" "In11.Cu" "In13.Cu" "In15.Cu")
		(hatch none 0.5)
		(connect_pads
			(clearance 0)
		)
		(min_thickness 0.25)
		(keepout
			(tracks not_allowed)
			(vias allowed)
			(pads allowed)
			(copperpour not_allowed)
			(footprints allowed)
		)
		(placement
			(enabled no)
			(sheetname "")
		)
		(fill yes
			(thermal_gap 0.5)
			(thermal_bridge_width 0.5)
			(island_removal_mode 0)
		)
		(polygon
			(pts
				(arc
					(start 341.58047 -236.597952)
					(mid 340.92769 -236.597952)
					(end 341.58047 -236.597952)
				)
			)
		)
	)
	(zone
		(layers "B.Cu" "In6.Cu" "In11.Cu" "In13.Cu" "In15.Cu")
		(hatch none 0.5)
		(connect_pads
			(clearance 0)
		)
		(min_thickness 0.25)
		(keepout
			(tracks not_allowed)
			(vias allowed)
			(pads allowed)
			(copperpour not_allowed)
			(footprints allowed)
		)
		(placement
			(enabled no)
			(sheetname "")
		)
		(fill yes
			(thermal_gap 0.5)
			(thermal_bridge_width 0.5)
			(island_removal_mode 0)
		)
		(polygon
			(pts
				(arc
					(start 127.583184 -259.616956)
					(mid 126.930404 -259.616956)
					(end 127.583184 -259.616956)
				)
			)
		)
	)
	(zone
		(layers "B.Cu" "In6.Cu" "In11.Cu" "In13.Cu" "In15.Cu")
		(hatch none 0.5)
		(connect_pads
			(clearance 0)
		)
		(min_thickness 0.25)
		(keepout
			(tracks not_allowed)
			(vias allowed)
			(pads allowed)
			(copperpour not_allowed)
			(footprints allowed)
		)
		(placement
			(enabled no)
			(sheetname "")
		)
		(fill yes
			(thermal_gap 0.5)
			(thermal_bridge_width 0.5)
			(island_removal_mode 0)
		)
		(polygon
			(pts
				(arc
					(start 340.750652 -266.128246)
					(mid 340.097872 -266.128246)
					(end 340.750652 -266.128246)
				)
			)
		)
	)
	(zone
		(layers "B.Cu" "In6.Cu" "In11.Cu" "In13.Cu" "In15.Cu")
		(hatch none 0.5)
		(connect_pads
			(clearance 0)
		)
		(min_thickness 0.25)
		(keepout
			(tracks not_allowed)
			(vias allowed)
			(pads allowed)
			(copperpour not_allowed)
			(footprints allowed)
		)
		(placement
			(enabled no)
			(sheetname "")
		)
		(fill yes
			(thermal_gap 0.5)
			(thermal_bridge_width 0.5)
			(island_removal_mode 0)
		)
		(polygon
			(pts
				(arc
					(start 425.162472 -197.316598)
					(mid 424.509692 -197.316598)
					(end 425.162472 -197.316598)
				)
			)
		)
	)
	(zone
		(layers "B.Cu" "In6.Cu" "In11.Cu" "In13.Cu" "In15.Cu")
		(hatch none 0.5)
		(connect_pads
			(clearance 0)
		)
		(min_thickness 0.25)
		(keepout
			(tracks not_allowed)
			(vias allowed)
			(pads allowed)
			(copperpour not_allowed)
			(footprints allowed)
		)
		(placement
			(enabled no)
			(sheetname "")
		)
		(fill yes
			(thermal_gap 0.5)
			(thermal_bridge_width 0.5)
			(island_removal_mode 0)
		)
		(polygon
			(pts
				(arc
					(start 280.143204 -293.366698)
					(mid 279.490424 -293.366698)
					(end 280.143204 -293.366698)
				)
			)
		)
	)
	(zone
		(layers "B.Cu" "In6.Cu" "In11.Cu" "In13.Cu" "In15.Cu")
		(hatch none 0.5)
		(connect_pads
			(clearance 0)
		)
		(min_thickness 0.25)
		(keepout
			(tracks not_allowed)
			(vias allowed)
			(pads allowed)
			(copperpour not_allowed)
			(footprints allowed)
		)
		(placement
			(enabled no)
			(sheetname "")
		)
		(fill yes
			(thermal_gap 0.5)
			(thermal_bridge_width 0.5)
			(island_removal_mode 0)
		)
		(polygon
			(pts
				(arc
					(start 342.52027 -230.086662)
					(mid 341.86749 -230.086662)
					(end 342.52027 -230.086662)
				)
			)
		)
	)
	(zone
		(layers "B.Cu" "In6.Cu" "In11.Cu" "In13.Cu" "In15.Cu")
		(hatch none 0.5)
		(connect_pads
			(clearance 0)
		)
		(min_thickness 0.25)
		(keepout
			(tracks not_allowed)
			(vias allowed)
			(pads allowed)
			(copperpour not_allowed)
			(footprints allowed)
		)
		(placement
			(enabled no)
			(sheetname "")
		)
		(fill yes
			(thermal_gap 0.5)
			(thermal_bridge_width 0.5)
			(island_removal_mode 0)
		)
		(polygon
			(pts
				(arc
					(start 92.810584 -266.128246)
					(mid 92.157804 -266.128246)
					(end 92.810584 -266.128246)
				)
			)
		)
	)
	(zone
		(layers "B.Cu" "In6.Cu" "In11.Cu" "In13.Cu" "In15.Cu")
		(hatch none 0.5)
		(connect_pads
			(clearance 0)
		)
		(min_thickness 0.25)
		(keepout
			(tracks not_allowed)
			(vias allowed)
			(pads allowed)
			(copperpour not_allowed)
			(footprints allowed)
		)
		(placement
			(enabled no)
			(sheetname "")
		)
		(fill yes
			(thermal_gap 0.5)
			(thermal_bridge_width 0.5)
			(island_removal_mode 0)
		)
		(polygon
			(pts
				(arc
					(start 124.653802 -217.064336)
					(mid 124.001022 -217.064336)
					(end 124.653802 -217.064336)
				)
			)
		)
	)
	(zone
		(layers "B.Cu" "In6.Cu" "In11.Cu" "In13.Cu" "In15.Cu")
		(hatch none 0.5)
		(connect_pads
			(clearance 0)
		)
		(min_thickness 0.25)
		(keepout
			(tracks not_allowed)
			(vias allowed)
			(pads allowed)
			(copperpour not_allowed)
			(footprints allowed)
		)
		(placement
			(enabled no)
			(sheetname "")
		)
		(fill yes
			(thermal_gap 0.5)
			(thermal_bridge_width 0.5)
			(island_removal_mode 0)
		)
		(polygon
			(pts
				(arc
					(start 343.875868 -44.690792)
					(mid 343.223088 -44.690792)
					(end 343.875868 -44.690792)
				)
			)
		)
	)
	(zone
		(layers "B.Cu" "In6.Cu" "In11.Cu" "In13.Cu" "In15.Cu")
		(hatch none 0.5)
		(connect_pads
			(clearance 0)
		)
		(min_thickness 0.25)
		(keepout
			(tracks not_allowed)
			(vias allowed)
			(pads allowed)
			(copperpour not_allowed)
			(footprints allowed)
		)
		(placement
			(enabled no)
			(sheetname "")
		)
		(fill yes
			(thermal_gap 0.5)
			(thermal_bridge_width 0.5)
			(island_removal_mode 0)
		)
		(polygon
			(pts
				(arc
					(start 32.203136 -264.466578)
					(mid 31.550356 -264.466578)
					(end 32.203136 -264.466578)
				)
			)
		)
	)
	(zone
		(layers "B.Cu" "In6.Cu" "In11.Cu" "In13.Cu" "In15.Cu")
		(hatch none 0.5)
		(connect_pads
			(clearance 0)
		)
		(min_thickness 0.25)
		(keepout
			(tracks not_allowed)
			(vias allowed)
			(pads allowed)
			(copperpour not_allowed)
			(footprints allowed)
		)
		(placement
			(enabled no)
			(sheetname "")
		)
		(fill yes
			(thermal_gap 0.5)
			(thermal_bridge_width 0.5)
			(island_removal_mode 0)
		)
		(polygon
			(pts
				(arc
					(start 341.690452 -266.128246)
					(mid 341.037672 -266.128246)
					(end 341.690452 -266.128246)
				)
			)
		)
	)
	(zone
		(layers "B.Cu" "In6.Cu" "In11.Cu" "In13.Cu" "In15.Cu")
		(hatch none 0.5)
		(connect_pads
			(clearance 0)
		)
		(min_thickness 0.25)
		(keepout
			(tracks not_allowed)
			(vias allowed)
			(pads allowed)
			(copperpour not_allowed)
			(footprints allowed)
		)
		(placement
			(enabled no)
			(sheetname "")
		)
		(fill yes
			(thermal_gap 0.5)
			(thermal_bridge_width 0.5)
			(island_removal_mode 0)
		)
		(polygon
			(pts
				(arc
					(start 354.268024 -217.878406)
					(mid 353.615244 -217.878406)
					(end 354.268024 -217.878406)
				)
			)
		)
	)
	(zone
		(layers "B.Cu" "In6.Cu" "In11.Cu" "In13.Cu" "In15.Cu")
		(hatch none 0.5)
		(connect_pads
			(clearance 0)
		)
		(min_thickness 0.25)
		(keepout
			(tracks not_allowed)
			(vias allowed)
			(pads allowed)
			(copperpour not_allowed)
			(footprints allowed)
		)
		(placement
			(enabled no)
			(sheetname "")
		)
		(fill yes
			(thermal_gap 0.5)
			(thermal_bridge_width 0.5)
			(island_removal_mode 0)
		)
		(polygon
			(pts
				(arc
					(start 16.82877 -21.493988)
					(mid 16.12519 -21.493988)
					(end 16.82877 -21.493988)
				)
			)
		)
	)
	(zone
		(layers "B.Cu" "In6.Cu" "In11.Cu" "In13.Cu" "In15.Cu")
		(hatch none 0.5)
		(connect_pads
			(clearance 0)
		)
		(min_thickness 0.25)
		(keepout
			(tracks not_allowed)
			(vias allowed)
			(pads allowed)
			(copperpour not_allowed)
			(footprints allowed)
		)
		(placement
			(enabled no)
			(sheetname "")
		)
		(fill yes
			(thermal_gap 0.5)
			(thermal_bridge_width 0.5)
			(island_removal_mode 0)
		)
		(polygon
			(pts
				(arc
					(start 131.702556 -237.411514)
					(mid 131.049776 -237.411514)
					(end 131.702556 -237.411514)
				)
			)
		)
	)
	(zone
		(layers "B.Cu" "In6.Cu" "In11.Cu" "In13.Cu" "In15.Cu")
		(hatch none 0.5)
		(connect_pads
			(clearance 0)
		)
		(min_thickness 0.25)
		(keepout
			(tracks not_allowed)
			(vias allowed)
			(pads allowed)
			(copperpour not_allowed)
			(footprints allowed)
		)
		(placement
			(enabled no)
			(sheetname "")
		)
		(fill yes
			(thermal_gap 0.5)
			(thermal_bridge_width 0.5)
			(island_removal_mode 0)
		)
		(polygon
			(pts
				(arc
					(start 379.642624 -237.411514)
					(mid 378.989844 -237.411514)
					(end 379.642624 -237.411514)
				)
			)
		)
	)
	(zone
		(layers "B.Cu" "In6.Cu" "In11.Cu" "In13.Cu" "In15.Cu")
		(hatch none 0.5)
		(connect_pads
			(clearance 0)
		)
		(min_thickness 0.25)
		(keepout
			(tracks not_allowed)
			(vias allowed)
			(pads allowed)
			(copperpour not_allowed)
			(footprints allowed)
		)
		(placement
			(enabled no)
			(sheetname "")
		)
		(fill yes
			(thermal_gap 0.5)
			(thermal_bridge_width 0.5)
			(island_removal_mode 0)
		)
		(polygon
			(pts
				(arc
					(start 36.303204 -238.966756)
					(mid 35.650424 -238.966756)
					(end 36.303204 -238.966756)
				)
			)
		)
	)
	(zone
		(layers "B.Cu" "In6.Cu" "In11.Cu" "In13.Cu" "In15.Cu")
		(hatch none 0.5)
		(connect_pads
			(clearance 0)
		)
		(min_thickness 0.25)
		(keepout
			(tracks not_allowed)
			(vias allowed)
			(pads allowed)
			(copperpour not_allowed)
			(footprints allowed)
		)
		(placement
			(enabled no)
			(sheetname "")
		)
		(fill yes
			(thermal_gap 0.5)
			(thermal_bridge_width 0.5)
			(island_removal_mode 0)
		)
		(polygon
			(pts
				(arc
					(start 94.580202 -244.73662)
					(mid 93.927422 -244.73662)
					(end 94.580202 -244.73662)
				)
			)
		)
	)
	(zone
		(layers "B.Cu" "In6.Cu" "In11.Cu" "In13.Cu" "In15.Cu")
		(hatch none 0.5)
		(connect_pads
			(clearance 0)
		)
		(min_thickness 0.25)
		(keepout
			(tracks not_allowed)
			(vias allowed)
			(pads allowed)
			(copperpour not_allowed)
			(footprints allowed)
		)
		(placement
			(enabled no)
			(sheetname "")
		)
		(fill yes
			(thermal_gap 0.5)
			(thermal_bridge_width 0.5)
			(island_removal_mode 0)
		)
		(polygon
			(pts
				(arc
					(start 47.290736 -299.316648)
					(mid 46.637956 -299.316648)
					(end 47.290736 -299.316648)
				)
			)
		)
	)
	(zone
		(layers "B.Cu" "In6.Cu" "In11.Cu" "In13.Cu" "In15.Cu")
		(hatch none 0.5)
		(connect_pads
			(clearance 0)
		)
		(min_thickness 0.25)
		(keepout
			(tracks not_allowed)
			(vias allowed)
			(pads allowed)
			(copperpour not_allowed)
			(footprints allowed)
		)
		(placement
			(enabled no)
			(sheetname "")
		)
		(fill yes
			(thermal_gap 0.5)
			(thermal_bridge_width 0.5)
			(island_removal_mode 0)
		)
		(polygon
			(pts
				(arc
					(start 100.329238 -288.917126)
					(mid 99.676458 -288.917126)
					(end 100.329238 -288.917126)
				)
			)
		)
	)
	(zone
		(layers "B.Cu" "In6.Cu" "In11.Cu" "In13.Cu" "In15.Cu")
		(hatch none 0.5)
		(connect_pads
			(clearance 0)
		)
		(min_thickness 0.25)
		(keepout
			(tracks not_allowed)
			(vias allowed)
			(pads allowed)
			(copperpour not_allowed)
			(footprints allowed)
		)
		(placement
			(enabled no)
			(sheetname "")
		)
		(fill yes
			(thermal_gap 0.5)
			(thermal_bridge_width 0.5)
			(island_removal_mode 0)
		)
		(polygon
			(pts
				(arc
					(start 380.692406 -265.314176)
					(mid 380.039626 -265.314176)
					(end 380.692406 -265.314176)
				)
			)
		)
	)
	(zone
		(layers "B.Cu" "In6.Cu" "In11.Cu" "In13.Cu" "In15.Cu")
		(hatch none 0.5)
		(connect_pads
			(clearance 0)
		)
		(min_thickness 0.25)
		(keepout
			(tracks not_allowed)
			(vias allowed)
			(pads allowed)
			(copperpour not_allowed)
			(footprints allowed)
		)
		(placement
			(enabled no)
			(sheetname "")
		)
		(fill yes
			(thermal_gap 0.5)
			(thermal_bridge_width 0.5)
			(island_removal_mode 0)
		)
		(polygon
			(pts
				(arc
					(start 111.026956 -217.878406)
					(mid 110.374176 -217.878406)
					(end 111.026956 -217.878406)
				)
			)
		)
	)
	(zone
		(layers "B.Cu" "In6.Cu" "In11.Cu" "In13.Cu" "In15.Cu")
		(hatch none 0.5)
		(connect_pads
			(clearance 0)
		)
		(min_thickness 0.25)
		(keepout
			(tracks not_allowed)
			(vias allowed)
			(pads allowed)
			(copperpour not_allowed)
			(footprints allowed)
		)
		(placement
			(enabled no)
			(sheetname "")
		)
		(fill yes
			(thermal_gap 0.5)
			(thermal_bridge_width 0.5)
			(island_removal_mode 0)
		)
		(polygon
			(pts
				(arc
					(start 132.172202 -238.225584)
					(mid 131.519422 -238.225584)
					(end 132.172202 -238.225584)
				)
			)
		)
	)
	(zone
		(layers "B.Cu" "In6.Cu" "In11.Cu" "In13.Cu" "In15.Cu")
		(hatch none 0.5)
		(connect_pads
			(clearance 0)
		)
		(min_thickness 0.25)
		(keepout
			(tracks not_allowed)
			(vias allowed)
			(pads allowed)
			(copperpour not_allowed)
			(footprints allowed)
		)
		(placement
			(enabled no)
			(sheetname "")
		)
		(fill yes
			(thermal_gap 0.5)
			(thermal_bridge_width 0.5)
			(island_removal_mode 0)
		)
		(polygon
			(pts
				(arc
					(start 134.162038 -288.917126)
					(mid 133.509258 -288.917126)
					(end 134.162038 -288.917126)
				)
			)
		)
	)
	(zone
		(layers "B.Cu" "In6.Cu" "In11.Cu" "In13.Cu" "In15.Cu")
		(hatch none 0.5)
		(connect_pads
			(clearance 0)
		)
		(min_thickness 0.25)
		(keepout
			(tracks not_allowed)
			(vias allowed)
			(pads allowed)
			(copperpour not_allowed)
			(footprints allowed)
		)
		(placement
			(enabled no)
			(sheetname "")
		)
		(fill yes
			(thermal_gap 0.5)
			(thermal_bridge_width 0.5)
			(island_removal_mode 0)
		)
		(polygon
			(pts
				(arc
					(start 93.750384 -277.522432)
					(mid 93.097604 -277.522432)
					(end 93.750384 -277.522432)
				)
			)
		)
	)
	(zone
		(layers "B.Cu" "In6.Cu" "In11.Cu" "In13.Cu" "In15.Cu")
		(hatch none 0.5)
		(connect_pads
			(clearance 0)
		)
		(min_thickness 0.25)
		(keepout
			(tracks not_allowed)
			(vias allowed)
			(pads allowed)
			(copperpour not_allowed)
			(footprints allowed)
		)
		(placement
			(enabled no)
			(sheetname "")
		)
		(fill yes
			(thermal_gap 0.5)
			(thermal_bridge_width 0.5)
			(island_removal_mode 0)
		)
		(polygon
			(pts
				(arc
					(start 91.870784 -272.639282)
					(mid 91.218004 -272.639282)
					(end 91.870784 -272.639282)
				)
			)
		)
	)
	(zone
		(layers "B.Cu" "In6.Cu" "In11.Cu" "In13.Cu" "In15.Cu")
		(hatch none 0.5)
		(connect_pads
			(clearance 0)
		)
		(min_thickness 0.25)
		(keepout
			(tracks not_allowed)
			(vias allowed)
			(pads allowed)
			(copperpour not_allowed)
			(footprints allowed)
		)
		(placement
			(enabled no)
			(sheetname "")
		)
		(fill yes
			(thermal_gap 0.5)
			(thermal_bridge_width 0.5)
			(island_removal_mode 0)
		)
		(polygon
			(pts
				(arc
					(start 380.222252 -271.011396)
					(mid 379.569472 -271.011396)
					(end 380.222252 -271.011396)
				)
			)
		)
	)
	(zone
		(layers "B.Cu" "In6.Cu" "In11.Cu" "In13.Cu" "In15.Cu")
		(hatch none 0.5)
		(connect_pads
			(clearance 0)
		)
		(min_thickness 0.25)
		(keepout
			(tracks not_allowed)
			(vias allowed)
			(pads allowed)
			(copperpour not_allowed)
			(footprints allowed)
		)
		(placement
			(enabled no)
			(sheetname "")
		)
		(fill yes
			(thermal_gap 0.5)
			(thermal_bridge_width 0.5)
			(island_removal_mode 0)
		)
		(polygon
			(pts
				(arc
					(start 94.580202 -234.970066)
					(mid 93.927422 -234.970066)
					(end 94.580202 -234.970066)
				)
			)
		)
	)
	(zone
		(layers "B.Cu" "In6.Cu" "In11.Cu" "In13.Cu" "In15.Cu")
		(hatch none 0.5)
		(connect_pads
			(clearance 0)
		)
		(min_thickness 0.25)
		(keepout
			(tracks not_allowed)
			(vias allowed)
			(pads allowed)
			(copperpour not_allowed)
			(footprints allowed)
		)
		(placement
			(enabled no)
			(sheetname "")
		)
		(fill yes
			(thermal_gap 0.5)
			(thermal_bridge_width 0.5)
			(island_removal_mode 0)
		)
		(polygon
			(pts
				(arc
					(start 177.222404 -302.716692)
					(mid 176.569624 -302.716692)
					(end 177.222404 -302.716692)
				)
			)
		)
	)
	(zone
		(layers "B.Cu" "In6.Cu" "In11.Cu" "In13.Cu" "In15.Cu")
		(hatch none 0.5)
		(connect_pads
			(clearance 0)
		)
		(min_thickness 0.25)
		(keepout
			(tracks not_allowed)
			(vias allowed)
			(pads allowed)
			(copperpour not_allowed)
			(footprints allowed)
		)
		(placement
			(enabled no)
			(sheetname "")
		)
		(fill yes
			(thermal_gap 0.5)
			(thermal_bridge_width 0.5)
			(island_removal_mode 0)
		)
		(polygon
			(pts
				(arc
					(start 342.245188 -45.630846)
					(mid 341.592408 -45.630846)
					(end 342.245188 -45.630846)
				)
			)
		)
	)
	(zone
		(layers "B.Cu" "In6.Cu" "In11.Cu" "In13.Cu" "In15.Cu")
		(hatch none 0.5)
		(connect_pads
			(clearance 0)
		)
		(min_thickness 0.25)
		(keepout
			(tracks not_allowed)
			(vias allowed)
			(pads allowed)
			(copperpour not_allowed)
			(footprints allowed)
		)
		(placement
			(enabled no)
			(sheetname "")
		)
		(fill yes
			(thermal_gap 0.5)
			(thermal_bridge_width 0.5)
			(island_removal_mode 0)
		)
		(polygon
			(pts
				(arc
					(start 299.356272 -300.166786)
					(mid 298.703492 -300.166786)
					(end 299.356272 -300.166786)
				)
			)
		)
	)
	(zone
		(layers "B.Cu" "In6.Cu" "In11.Cu" "In13.Cu" "In15.Cu")
		(hatch none 0.5)
		(connect_pads
			(clearance 0)
		)
		(min_thickness 0.25)
		(keepout
			(tracks not_allowed)
			(vias allowed)
			(pads allowed)
			(copperpour not_allowed)
			(footprints allowed)
		)
		(placement
			(enabled no)
			(sheetname "")
		)
		(fill yes
			(thermal_gap 0.5)
			(thermal_bridge_width 0.5)
			(island_removal_mode 0)
		)
		(polygon
			(pts
				(arc
					(start 32.203136 -261.066788)
					(mid 31.550356 -261.066788)
					(end 32.203136 -261.066788)
				)
			)
		)
	)
	(zone
		(layers "B.Cu" "In6.Cu" "In11.Cu" "In13.Cu" "In15.Cu")
		(hatch none 0.5)
		(connect_pads
			(clearance 0)
		)
		(min_thickness 0.25)
		(keepout
			(tracks not_allowed)
			(vias allowed)
			(pads allowed)
			(copperpour not_allowed)
			(footprints allowed)
		)
		(placement
			(enabled no)
			(sheetname "")
		)
		(fill yes
			(thermal_gap 0.5)
			(thermal_bridge_width 0.5)
			(island_removal_mode 0)
		)
		(polygon
			(pts
				(arc
					(start 131.702556 -239.0394)
					(mid 131.049776 -239.0394)
					(end 131.702556 -239.0394)
				)
			)
		)
	)
	(zone
		(layers "B.Cu" "In6.Cu" "In11.Cu" "In13.Cu" "In15.Cu")
		(hatch none 0.5)
		(connect_pads
			(clearance 0)
		)
		(min_thickness 0.25)
		(keepout
			(tracks not_allowed)
			(vias allowed)
			(pads allowed)
			(copperpour not_allowed)
			(footprints allowed)
		)
		(placement
			(enabled no)
			(sheetname "")
		)
		(fill yes
			(thermal_gap 0.5)
			(thermal_bridge_width 0.5)
			(island_removal_mode 0)
		)
		(polygon
			(pts
				(arc
					(start 342.160606 -273.453098)
					(mid 341.507826 -273.453098)
					(end 342.160606 -273.453098)
				)
			)
		)
	)
	(zone
		(layers "B.Cu" "In6.Cu" "In11.Cu" "In13.Cu" "In15.Cu")
		(hatch none 0.5)
		(connect_pads
			(clearance 0)
		)
		(min_thickness 0.25)
		(keepout
			(tracks not_allowed)
			(vias allowed)
			(pads allowed)
			(copperpour not_allowed)
			(footprints allowed)
		)
		(placement
			(enabled no)
			(sheetname "")
		)
		(fill yes
			(thermal_gap 0.5)
			(thermal_bridge_width 0.5)
			(island_removal_mode 0)
		)
		(polygon
			(pts
				(arc
					(start 199.853804 -260.21665)
					(mid 199.201024 -260.21665)
					(end 199.853804 -260.21665)
				)
			)
		)
	)
	(zone
		(layers "B.Cu" "In6.Cu" "In11.Cu" "In13.Cu" "In15.Cu")
		(hatch none 0.5)
		(connect_pads
			(clearance 0)
		)
		(min_thickness 0.25)
		(keepout
			(tracks not_allowed)
			(vias allowed)
			(pads allowed)
			(copperpour not_allowed)
			(footprints allowed)
		)
		(placement
			(enabled no)
			(sheetname "")
		)
		(fill yes
			(thermal_gap 0.5)
			(thermal_bridge_width 0.5)
			(island_removal_mode 0)
		)
		(polygon
			(pts
				(arc
					(start 123.354338 -288.103056)
					(mid 122.701558 -288.103056)
					(end 123.354338 -288.103056)
				)
			)
		)
	)
	(zone
		(layers "B.Cu" "In6.Cu" "In11.Cu" "In13.Cu" "In15.Cu")
		(hatch none 0.5)
		(connect_pads
			(clearance 0)
		)
		(min_thickness 0.25)
		(keepout
			(tracks not_allowed)
			(vias allowed)
			(pads allowed)
			(copperpour not_allowed)
			(footprints allowed)
		)
		(placement
			(enabled no)
			(sheetname "")
		)
		(fill yes
			(thermal_gap 0.5)
			(thermal_bridge_width 0.5)
			(island_removal_mode 0)
		)
		(polygon
			(pts
				(arc
					(start 333.122524 -225.203258)
					(mid 332.469744 -225.203258)
					(end 333.122524 -225.203258)
				)
			)
		)
	)
	(zone
		(layers "B.Cu" "In6.Cu" "In11.Cu" "In13.Cu" "In15.Cu")
		(hatch none 0.5)
		(connect_pads
			(clearance 0)
		)
		(min_thickness 0.25)
		(keepout
			(tracks not_allowed)
			(vias allowed)
			(pads allowed)
			(copperpour not_allowed)
			(footprints allowed)
		)
		(placement
			(enabled no)
			(sheetname "")
		)
		(fill yes
			(thermal_gap 0.5)
			(thermal_bridge_width 0.5)
			(island_removal_mode 0)
		)
		(polygon
			(pts
				(arc
					(start 280.143204 -209.216752)
					(mid 279.490424 -209.216752)
					(end 280.143204 -209.216752)
				)
			)
		)
	)
	(zone
		(layers "B.Cu" "In6.Cu" "In11.Cu" "In13.Cu" "In15.Cu")
		(hatch none 0.5)
		(connect_pads
			(clearance 0)
		)
		(min_thickness 0.25)
		(keepout
			(tracks not_allowed)
			(vias allowed)
			(pads allowed)
			(copperpour not_allowed)
			(footprints allowed)
		)
		(placement
			(enabled no)
			(sheetname "")
		)
		(fill yes
			(thermal_gap 0.5)
			(thermal_bridge_width 0.5)
			(island_removal_mode 0)
		)
		(polygon
			(pts
				(arc
					(start 241.015774 -58.30189)
					(mid 240.312194 -58.30189)
					(end 241.015774 -58.30189)
				)
			)
		)
	)
	(zone
		(layers "B.Cu" "In6.Cu" "In11.Cu" "In13.Cu" "In15.Cu")
		(hatch none 0.5)
		(connect_pads
			(clearance 0)
		)
		(min_thickness 0.25)
		(keepout
			(tracks not_allowed)
			(vias allowed)
			(pads allowed)
			(copperpour not_allowed)
			(footprints allowed)
		)
		(placement
			(enabled no)
			(sheetname "")
		)
		(fill yes
			(thermal_gap 0.5)
			(thermal_bridge_width 0.5)
			(island_removal_mode 0)
		)
		(polygon
			(pts
				(arc
					(start 421.062404 -200.716642)
					(mid 420.409624 -200.716642)
					(end 421.062404 -200.716642)
				)
			)
		)
	)
	(zone
		(layers "B.Cu" "In6.Cu" "In11.Cu" "In13.Cu" "In15.Cu")
		(hatch none 0.5)
		(connect_pads
			(clearance 0)
		)
		(min_thickness 0.25)
		(keepout
			(tracks not_allowed)
			(vias allowed)
			(pads allowed)
			(copperpour not_allowed)
			(footprints allowed)
		)
		(placement
			(enabled no)
			(sheetname "")
		)
		(fill yes
			(thermal_gap 0.5)
			(thermal_bridge_width 0.5)
			(island_removal_mode 0)
		)
		(polygon
			(pts
				(arc
					(start 421.062404 -204.116686)
					(mid 420.409624 -204.116686)
					(end 421.062404 -204.116686)
				)
			)
		)
	)
	(zone
		(layers "B.Cu" "In6.Cu" "In11.Cu" "In13.Cu" "In15.Cu")
		(hatch none 0.5)
		(connect_pads
			(clearance 0)
		)
		(min_thickness 0.25)
		(keepout
			(tracks not_allowed)
			(vias allowed)
			(pads allowed)
			(copperpour not_allowed)
			(footprints allowed)
		)
		(placement
			(enabled no)
			(sheetname "")
		)
		(fill yes
			(thermal_gap 0.5)
			(thermal_bridge_width 0.5)
			(island_removal_mode 0)
		)
		(polygon
			(pts
				(arc
					(start 425.162472 -201.56678)
					(mid 424.509692 -201.56678)
					(end 425.162472 -201.56678)
				)
			)
		)
	)
	(zone
		(layers "B.Cu" "In6.Cu" "In11.Cu" "In13.Cu" "In15.Cu")
		(hatch none 0.5)
		(connect_pads
			(clearance 0)
		)
		(min_thickness 0.25)
		(keepout
			(tracks not_allowed)
			(vias allowed)
			(pads allowed)
			(copperpour not_allowed)
			(footprints allowed)
		)
		(placement
			(enabled no)
			(sheetname "")
		)
		(fill yes
			(thermal_gap 0.5)
			(thermal_bridge_width 0.5)
			(island_removal_mode 0)
		)
		(polygon
			(pts
				(arc
					(start 92.700602 -228.45903)
					(mid 92.047822 -228.45903)
					(end 92.700602 -228.45903)
				)
			)
		)
	)
	(zone
		(layers "B.Cu" "In6.Cu" "In11.Cu" "In13.Cu" "In15.Cu")
		(hatch none 0.5)
		(connect_pads
			(clearance 0)
		)
		(min_thickness 0.25)
		(keepout
			(tracks not_allowed)
			(vias allowed)
			(pads allowed)
			(copperpour not_allowed)
			(footprints allowed)
		)
		(placement
			(enabled no)
			(sheetname "")
		)
		(fill yes
			(thermal_gap 0.5)
			(thermal_bridge_width 0.5)
			(island_removal_mode 0)
		)
		(polygon
			(pts
				(arc
					(start 284.243272 -311.216802)
					(mid 283.590492 -311.216802)
					(end 284.243272 -311.216802)
				)
			)
		)
	)
	(zone
		(layers "B.Cu" "In6.Cu" "In11.Cu" "In13.Cu" "In15.Cu")
		(hatch none 0.5)
		(connect_pads
			(clearance 0)
		)
		(min_thickness 0.25)
		(keepout
			(tracks not_allowed)
			(vias allowed)
			(pads allowed)
			(copperpour not_allowed)
			(footprints allowed)
		)
		(placement
			(enabled no)
			(sheetname "")
		)
		(fill yes
			(thermal_gap 0.5)
			(thermal_bridge_width 0.5)
			(island_removal_mode 0)
		)
		(polygon
			(pts
				(arc
					(start 177.222404 -199.866758)
					(mid 176.569624 -199.866758)
					(end 177.222404 -199.866758)
				)
			)
		)
	)
	(zone
		(layers "B.Cu" "In6.Cu" "In11.Cu" "In13.Cu" "In15.Cu")
		(hatch none 0.5)
		(connect_pads
			(clearance 0)
		)
		(min_thickness 0.25)
		(keepout
			(tracks not_allowed)
			(vias allowed)
			(pads allowed)
			(copperpour not_allowed)
			(footprints allowed)
		)
		(placement
			(enabled no)
			(sheetname "")
		)
		(fill yes
			(thermal_gap 0.5)
			(thermal_bridge_width 0.5)
			(island_removal_mode 0)
		)
		(polygon
			(pts
				(arc
					(start 36.303204 -236.416596)
					(mid 35.650424 -236.416596)
					(end 36.303204 -236.416596)
				)
			)
		)
	)
	(zone
		(layers "B.Cu" "In6.Cu" "In11.Cu" "In13.Cu" "In15.Cu")
		(hatch none 0.5)
		(connect_pads
			(clearance 0)
		)
		(min_thickness 0.25)
		(keepout
			(tracks not_allowed)
			(vias allowed)
			(pads allowed)
			(copperpour not_allowed)
			(footprints allowed)
		)
		(placement
			(enabled no)
			(sheetname "")
		)
		(fill yes
			(thermal_gap 0.5)
			(thermal_bridge_width 0.5)
			(island_removal_mode 0)
		)
		(polygon
			(pts
				(arc
					(start 284.243272 -244.916706)
					(mid 283.590492 -244.916706)
					(end 284.243272 -244.916706)
				)
			)
		)
	)
	(zone
		(layers "B.Cu" "In6.Cu" "In11.Cu" "In13.Cu" "In15.Cu")
		(hatch none 0.5)
		(connect_pads
			(clearance 0)
		)
		(min_thickness 0.25)
		(keepout
			(tracks not_allowed)
			(vias allowed)
			(pads allowed)
			(copperpour not_allowed)
			(footprints allowed)
		)
		(placement
			(enabled no)
			(sheetname "")
		)
		(fill yes
			(thermal_gap 0.5)
			(thermal_bridge_width 0.5)
			(island_removal_mode 0)
		)
		(polygon
			(pts
				(arc
					(start 199.853804 -259.366766)
					(mid 199.201024 -259.366766)
					(end 199.853804 -259.366766)
				)
			)
		)
	)
	(zone
		(layers "B.Cu" "In6.Cu" "In11.Cu" "In13.Cu" "In15.Cu")
		(hatch none 0.5)
		(connect_pads
			(clearance 0)
		)
		(min_thickness 0.25)
		(keepout
			(tracks not_allowed)
			(vias allowed)
			(pads allowed)
			(copperpour not_allowed)
			(footprints allowed)
		)
		(placement
			(enabled no)
			(sheetname "")
		)
		(fill yes
			(thermal_gap 0.5)
			(thermal_bridge_width 0.5)
			(island_removal_mode 0)
		)
		(polygon
			(pts
				(arc
					(start 447.793872 -260.21665)
					(mid 447.141092 -260.21665)
					(end 447.793872 -260.21665)
				)
			)
		)
	)
	(zone
		(layers "B.Cu" "In6.Cu" "In11.Cu" "In13.Cu" "In15.Cu")
		(hatch none 0.5)
		(connect_pads
			(clearance 0)
		)
		(min_thickness 0.25)
		(keepout
			(tracks not_allowed)
			(vias allowed)
			(pads allowed)
			(copperpour not_allowed)
			(footprints allowed)
		)
		(placement
			(enabled no)
			(sheetname "")
		)
		(fill yes
			(thermal_gap 0.5)
			(thermal_bridge_width 0.5)
			(island_removal_mode 0)
		)
		(polygon
			(pts
				(arc
					(start 342.52027 -244.73662)
					(mid 341.86749 -244.73662)
					(end 342.52027 -244.73662)
				)
			)
		)
	)
	(zone
		(layers "B.Cu" "In6.Cu" "In11.Cu" "In13.Cu" "In15.Cu")
		(hatch none 0.5)
		(connect_pads
			(clearance 0)
		)
		(min_thickness 0.25)
		(keepout
			(tracks not_allowed)
			(vias allowed)
			(pads allowed)
			(copperpour not_allowed)
			(footprints allowed)
		)
		(placement
			(enabled no)
			(sheetname "")
		)
		(fill yes
			(thermal_gap 0.5)
			(thermal_bridge_width 0.5)
			(island_removal_mode 0)
		)
		(polygon
			(pts
				(arc
					(start 378.702824 -229.272846)
					(mid 378.050044 -229.272846)
					(end 378.702824 -229.272846)
				)
			)
		)
	)
	(zone
		(layers "B.Cu" "In6.Cu" "In11.Cu" "In13.Cu" "In15.Cu")
		(hatch none 0.5)
		(connect_pads
			(clearance 0)
		)
		(min_thickness 0.25)
		(keepout
			(tracks not_allowed)
			(vias allowed)
			(pads allowed)
			(copperpour not_allowed)
			(footprints allowed)
		)
		(placement
			(enabled no)
			(sheetname "")
		)
		(fill yes
			(thermal_gap 0.5)
			(thermal_bridge_width 0.5)
			(island_removal_mode 0)
		)
		(polygon
			(pts
				(arc
					(start 109.617002 -217.064336)
					(mid 108.964222 -217.064336)
					(end 109.617002 -217.064336)
				)
			)
		)
	)
	(zone
		(layers "B.Cu" "In6.Cu" "In11.Cu" "In13.Cu" "In15.Cu")
		(hatch none 0.5)
		(connect_pads
			(clearance 0)
		)
		(min_thickness 0.25)
		(keepout
			(tracks not_allowed)
			(vias allowed)
			(pads allowed)
			(copperpour not_allowed)
			(footprints allowed)
		)
		(placement
			(enabled no)
			(sheetname "")
		)
		(fill yes
			(thermal_gap 0.5)
			(thermal_bridge_width 0.5)
			(island_removal_mode 0)
		)
		(polygon
			(pts
				(arc
					(start 376.35307 -249.620024)
					(mid 375.70029 -249.620024)
					(end 376.35307 -249.620024)
				)
			)
		)
	)
	(zone
		(layers "B.Cu" "In6.Cu" "In11.Cu" "In13.Cu" "In15.Cu")
		(hatch none 0.5)
		(connect_pads
			(clearance 0)
		)
		(min_thickness 0.25)
		(keepout
			(tracks not_allowed)
			(vias allowed)
			(pads allowed)
			(copperpour not_allowed)
			(footprints allowed)
		)
		(placement
			(enabled no)
			(sheetname "")
		)
		(fill yes
			(thermal_gap 0.5)
			(thermal_bridge_width 0.5)
			(island_removal_mode 0)
		)
		(polygon
			(pts
				(arc
					(start 100.689156 -217.878406)
					(mid 100.036376 -217.878406)
					(end 100.689156 -217.878406)
				)
			)
		)
	)
	(zone
		(layers "B.Cu" "In6.Cu" "In11.Cu" "In13.Cu" "In15.Cu")
		(hatch none 0.5)
		(connect_pads
			(clearance 0)
		)
		(min_thickness 0.25)
		(keepout
			(tracks not_allowed)
			(vias allowed)
			(pads allowed)
			(copperpour not_allowed)
			(footprints allowed)
		)
		(placement
			(enabled no)
			(sheetname "")
		)
		(fill yes
			(thermal_gap 0.5)
			(thermal_bridge_width 0.5)
			(island_removal_mode 0)
		)
		(polygon
			(pts
				(arc
					(start 344.689684 -46.100492)
					(mid 344.036904 -46.100492)
					(end 344.689684 -46.100492)
				)
			)
		)
	)
	(zone
		(layers "B.Cu" "In6.Cu" "In11.Cu" "In13.Cu" "In15.Cu")
		(hatch none 0.5)
		(connect_pads
			(clearance 0)
		)
		(min_thickness 0.25)
		(keepout
			(tracks not_allowed)
			(vias allowed)
			(pads allowed)
			(copperpour not_allowed)
			(footprints allowed)
		)
		(placement
			(enabled no)
			(sheetname "")
		)
		(fill yes
			(thermal_gap 0.5)
			(thermal_bridge_width 0.5)
			(island_removal_mode 0)
		)
		(polygon
			(pts
				(arc
					(start 173.122336 -301.01667)
					(mid 172.469556 -301.01667)
					(end 173.122336 -301.01667)
				)
			)
		)
	)
	(zone
		(layers "B.Cu" "In6.Cu" "In11.Cu" "In13.Cu" "In15.Cu")
		(hatch none 0.5)
		(connect_pads
			(clearance 0)
		)
		(min_thickness 0.25)
		(keepout
			(tracks not_allowed)
			(vias allowed)
			(pads allowed)
			(copperpour not_allowed)
			(footprints allowed)
		)
		(placement
			(enabled no)
			(sheetname "")
		)
		(fill yes
			(thermal_gap 0.5)
			(thermal_bridge_width 0.5)
			(island_removal_mode 0)
		)
		(polygon
			(pts
				(arc
					(start 133.235446 -10.243312)
					(mid 132.531866 -10.243312)
					(end 133.235446 -10.243312)
				)
			)
		)
	)
	(zone
		(layers "B.Cu" "In6.Cu" "In11.Cu" "In13.Cu" "In15.Cu")
		(hatch none 0.5)
		(connect_pads
			(clearance 0)
		)
		(min_thickness 0.25)
		(keepout
			(tracks not_allowed)
			(vias allowed)
			(pads allowed)
			(copperpour not_allowed)
			(footprints allowed)
		)
		(placement
			(enabled no)
			(sheetname "")
		)
		(fill yes
			(thermal_gap 0.5)
			(thermal_bridge_width 0.5)
			(island_removal_mode 0)
		)
		(polygon
			(pts
				(arc
					(start 284.243272 -246.616728)
					(mid 283.590492 -246.616728)
					(end 284.243272 -246.616728)
				)
			)
		)
	)
	(zone
		(layers "B.Cu" "In6.Cu" "In11.Cu" "In13.Cu" "In15.Cu")
		(hatch none 0.5)
		(connect_pads
			(clearance 0)
		)
		(min_thickness 0.25)
		(keepout
			(tracks not_allowed)
			(vias allowed)
			(pads allowed)
			(copperpour not_allowed)
			(footprints allowed)
		)
		(placement
			(enabled no)
			(sheetname "")
		)
		(fill yes
			(thermal_gap 0.5)
			(thermal_bridge_width 0.5)
			(island_removal_mode 0)
		)
		(polygon
			(pts
				(arc
					(start 125.593602 -218.692222)
					(mid 124.940822 -218.692222)
					(end 125.593602 -218.692222)
				)
			)
		)
	)
	(zone
		(layers "B.Cu" "In6.Cu" "In11.Cu" "In13.Cu" "In15.Cu")
		(hatch none 0.5)
		(connect_pads
			(clearance 0)
		)
		(min_thickness 0.25)
		(keepout
			(tracks not_allowed)
			(vias allowed)
			(pads allowed)
			(copperpour not_allowed)
			(footprints allowed)
		)
		(placement
			(enabled no)
			(sheetname "")
		)
		(fill yes
			(thermal_gap 0.5)
			(thermal_bridge_width 0.5)
			(island_removal_mode 0)
		)
		(polygon
			(pts
				(arc
					(start 132.752338 -275.08073)
					(mid 132.099558 -275.08073)
					(end 132.752338 -275.08073)
				)
			)
		)
	)
	(zone
		(layers "B.Cu" "In6.Cu" "In11.Cu" "In13.Cu" "In15.Cu")
		(hatch none 0.5)
		(connect_pads
			(clearance 0)
		)
		(min_thickness 0.25)
		(keepout
			(tracks not_allowed)
			(vias allowed)
			(pads allowed)
			(copperpour not_allowed)
			(footprints allowed)
		)
		(placement
			(enabled no)
			(sheetname "")
		)
		(fill yes
			(thermal_gap 0.5)
			(thermal_bridge_width 0.5)
			(island_removal_mode 0)
		)
		(polygon
			(pts
				(arc
					(start 284.243272 -210.916774)
					(mid 283.590492 -210.916774)
					(end 284.243272 -210.916774)
				)
			)
		)
	)
	(zone
		(layers "B.Cu" "In6.Cu" "In11.Cu" "In13.Cu" "In15.Cu")
		(hatch none 0.5)
		(connect_pads
			(clearance 0)
		)
		(min_thickness 0.25)
		(keepout
			(tracks not_allowed)
			(vias allowed)
			(pads allowed)
			(copperpour not_allowed)
			(footprints allowed)
		)
		(placement
			(enabled no)
			(sheetname "")
		)
		(fill yes
			(thermal_gap 0.5)
			(thermal_bridge_width 0.5)
			(island_removal_mode 0)
		)
		(polygon
			(pts
				(arc
					(start 51.416204 -279.766776)
					(mid 50.763424 -279.766776)
					(end 51.416204 -279.766776)
				)
			)
		)
	)
	(zone
		(layers "B.Cu" "In6.Cu" "In11.Cu" "In13.Cu" "In15.Cu")
		(hatch none 0.5)
		(connect_pads
			(clearance 0)
		)
		(min_thickness 0.25)
		(keepout
			(tracks not_allowed)
			(vias allowed)
			(pads allowed)
			(copperpour not_allowed)
			(footprints allowed)
		)
		(placement
			(enabled no)
			(sheetname "")
		)
		(fill yes
			(thermal_gap 0.5)
			(thermal_bridge_width 0.5)
			(island_removal_mode 0)
		)
		(polygon
			(pts
				(arc
					(start 376.463052 -259.616956)
					(mid 375.810272 -259.616956)
					(end 376.463052 -259.616956)
				)
			)
		)
	)
	(zone
		(layers "B.Cu" "In6.Cu" "In11.Cu" "In13.Cu" "In15.Cu")
		(hatch none 0.5)
		(connect_pads
			(clearance 0)
		)
		(min_thickness 0.25)
		(keepout
			(tracks not_allowed)
			(vias allowed)
			(pads allowed)
			(copperpour not_allowed)
			(footprints allowed)
		)
		(placement
			(enabled no)
			(sheetname "")
		)
		(fill yes
			(thermal_gap 0.5)
			(thermal_bridge_width 0.5)
			(island_removal_mode 0)
		)
		(polygon
			(pts
				(arc
					(start 340.171024 -245.55069)
					(mid 339.518244 -245.55069)
					(end 340.171024 -245.55069)
				)
			)
		)
	)
	(zone
		(layers "B.Cu" "In6.Cu" "In11.Cu" "In13.Cu" "In15.Cu")
		(hatch none 0.5)
		(connect_pads
			(clearance 0)
		)
		(min_thickness 0.25)
		(keepout
			(tracks not_allowed)
			(vias allowed)
			(pads allowed)
			(copperpour not_allowed)
			(footprints allowed)
		)
		(placement
			(enabled no)
			(sheetname "")
		)
		(fill yes
			(thermal_gap 0.5)
			(thermal_bridge_width 0.5)
			(island_removal_mode 0)
		)
		(polygon
			(pts
				(arc
					(start 119.954802 -218.692222)
					(mid 119.302022 -218.692222)
					(end 119.954802 -218.692222)
				)
			)
		)
	)
	(zone
		(layers "B.Cu" "In6.Cu" "In11.Cu" "In13.Cu" "In15.Cu")
		(hatch none 0.5)
		(connect_pads
			(clearance 0)
		)
		(min_thickness 0.25)
		(keepout
			(tracks not_allowed)
			(vias allowed)
			(pads allowed)
			(copperpour not_allowed)
			(footprints allowed)
		)
		(placement
			(enabled no)
			(sheetname "")
		)
		(fill yes
			(thermal_gap 0.5)
			(thermal_bridge_width 0.5)
			(island_removal_mode 0)
		)
		(polygon
			(pts
				(arc
					(start 280.143204 -312.066686)
					(mid 279.490424 -312.066686)
					(end 280.143204 -312.066686)
				)
			)
		)
	)
	(zone
		(layers "B.Cu" "In6.Cu" "In11.Cu" "In13.Cu" "In15.Cu")
		(hatch none 0.5)
		(connect_pads
			(clearance 0)
		)
		(min_thickness 0.25)
		(keepout
			(tracks not_allowed)
			(vias allowed)
			(pads allowed)
			(copperpour not_allowed)
			(footprints allowed)
		)
		(placement
			(enabled no)
			(sheetname "")
		)
		(fill yes
			(thermal_gap 0.5)
			(thermal_bridge_width 0.5)
			(island_removal_mode 0)
		)
		(polygon
			(pts
				(arc
					(start 47.290736 -280.61666)
					(mid 46.637956 -280.61666)
					(end 47.290736 -280.61666)
				)
			)
		)
	)
	(zone
		(layers "B.Cu" "In6.Cu" "In11.Cu" "In13.Cu" "In15.Cu")
		(hatch none 0.5)
		(connect_pads
			(clearance 0)
		)
		(min_thickness 0.25)
		(keepout
			(tracks not_allowed)
			(vias allowed)
			(pads allowed)
			(copperpour not_allowed)
			(footprints allowed)
		)
		(placement
			(enabled no)
			(sheetname "")
		)
		(fill yes
			(thermal_gap 0.5)
			(thermal_bridge_width 0.5)
			(island_removal_mode 0)
		)
		(polygon
			(pts
				(arc
					(start 118.075202 -218.692222)
					(mid 117.422422 -218.692222)
					(end 118.075202 -218.692222)
				)
			)
		)
	)
	(zone
		(layers "B.Cu" "In6.Cu" "In11.Cu" "In13.Cu" "In15.Cu")
		(hatch none 0.5)
		(connect_pads
			(clearance 0)
		)
		(min_thickness 0.25)
		(keepout
			(tracks not_allowed)
			(vias allowed)
			(pads allowed)
			(copperpour not_allowed)
			(footprints allowed)
		)
		(placement
			(enabled no)
			(sheetname "")
		)
		(fill yes
			(thermal_gap 0.5)
			(thermal_bridge_width 0.5)
			(island_removal_mode 0)
		)
		(polygon
			(pts
				(arc
					(start 421.062404 -302.716692)
					(mid 420.409624 -302.716692)
					(end 421.062404 -302.716692)
				)
			)
		)
	)
	(zone
		(layers "B.Cu" "In6.Cu" "In11.Cu" "In13.Cu" "In15.Cu")
		(hatch none 0.5)
		(connect_pads
			(clearance 0)
		)
		(min_thickness 0.25)
		(keepout
			(tracks not_allowed)
			(vias allowed)
			(pads allowed)
			(copperpour not_allowed)
			(footprints allowed)
		)
		(placement
			(enabled no)
			(sheetname "")
		)
		(fill yes
			(thermal_gap 0.5)
			(thermal_bridge_width 0.5)
			(island_removal_mode 0)
		)
		(polygon
			(pts
				(arc
					(start 299.330872 -199.01662)
					(mid 298.678092 -199.01662)
					(end 299.330872 -199.01662)
				)
			)
		)
	)
	(zone
		(layers "B.Cu" "In6.Cu" "In11.Cu" "In13.Cu" "In15.Cu")
		(hatch none 0.5)
		(connect_pads
			(clearance 0)
		)
		(min_thickness 0.25)
		(keepout
			(tracks not_allowed)
			(vias allowed)
			(pads allowed)
			(copperpour not_allowed)
			(footprints allowed)
		)
		(placement
			(enabled no)
			(sheetname "")
		)
		(fill yes
			(thermal_gap 0.5)
			(thermal_bridge_width 0.5)
			(island_removal_mode 0)
		)
		(polygon
			(pts
				(arc
					(start 131.812538 -263.686544)
					(mid 131.159758 -263.686544)
					(end 131.812538 -263.686544)
				)
			)
		)
	)
	(zone
		(layers "B.Cu" "In6.Cu" "In11.Cu" "In13.Cu" "In15.Cu")
		(hatch none 0.5)
		(connect_pads
			(clearance 0)
		)
		(min_thickness 0.25)
		(keepout
			(tracks not_allowed)
			(vias allowed)
			(pads allowed)
			(copperpour not_allowed)
			(footprints allowed)
		)
		(placement
			(enabled no)
			(sheetname "")
		)
		(fill yes
			(thermal_gap 0.5)
			(thermal_bridge_width 0.5)
			(island_removal_mode 0)
		)
		(polygon
			(pts
				(arc
					(start 379.752606 -258.80314)
					(mid 379.099826 -258.80314)
					(end 379.752606 -258.80314)
				)
			)
		)
	)
	(zone
		(layers "B.Cu" "In6.Cu" "In11.Cu" "In13.Cu" "In15.Cu")
		(hatch none 0.5)
		(connect_pads
			(clearance 0)
		)
		(min_thickness 0.25)
		(keepout
			(tracks not_allowed)
			(vias allowed)
			(pads allowed)
			(copperpour not_allowed)
			(footprints allowed)
		)
		(placement
			(enabled no)
			(sheetname "")
		)
		(fill yes
			(thermal_gap 0.5)
			(thermal_bridge_width 0.5)
			(island_removal_mode 0)
		)
		(polygon
			(pts
				(arc
					(start 104.558338 -288.103056)
					(mid 103.905558 -288.103056)
					(end 104.558338 -288.103056)
				)
			)
		)
	)
	(zone
		(layers "B.Cu" "In6.Cu" "In11.Cu" "In13.Cu" "In15.Cu")
		(hatch none 0.5)
		(connect_pads
			(clearance 0)
		)
		(min_thickness 0.25)
		(keepout
			(tracks not_allowed)
			(vias allowed)
			(pads allowed)
			(copperpour not_allowed)
			(footprints allowed)
		)
		(placement
			(enabled no)
			(sheetname "")
		)
		(fill yes
			(thermal_gap 0.5)
			(thermal_bridge_width 0.5)
			(island_removal_mode 0)
		)
		(polygon
			(pts
				(arc
					(start 130.762756 -227.64496)
					(mid 130.109976 -227.64496)
					(end 130.762756 -227.64496)
				)
			)
		)
	)
	(zone
		(layers "B.Cu" "In6.Cu" "In11.Cu" "In13.Cu" "In15.Cu")
		(hatch none 0.5)
		(connect_pads
			(clearance 0)
		)
		(min_thickness 0.25)
		(keepout
			(tracks not_allowed)
			(vias allowed)
			(pads allowed)
			(copperpour not_allowed)
			(footprints allowed)
		)
		(placement
			(enabled no)
			(sheetname "")
		)
		(fill yes
			(thermal_gap 0.5)
			(thermal_bridge_width 0.5)
			(island_removal_mode 0)
		)
		(polygon
			(pts
				(arc
					(start 342.050624 -230.900478)
					(mid 341.397844 -230.900478)
					(end 342.050624 -230.900478)
				)
			)
		)
	)
	(zone
		(layers "B.Cu" "In6.Cu" "In11.Cu" "In13.Cu" "In15.Cu")
		(hatch none 0.5)
		(connect_pads
			(clearance 0)
		)
		(min_thickness 0.25)
		(keepout
			(tracks not_allowed)
			(vias allowed)
			(pads allowed)
			(copperpour not_allowed)
			(footprints allowed)
		)
		(placement
			(enabled no)
			(sheetname "")
		)
		(fill yes
			(thermal_gap 0.5)
			(thermal_bridge_width 0.5)
			(island_removal_mode 0)
		)
		(polygon
			(pts
				(arc
					(start 130.872738 -288.103056)
					(mid 130.219958 -288.103056)
					(end 130.872738 -288.103056)
				)
			)
		)
	)
	(zone
		(layers "B.Cu" "In6.Cu" "In11.Cu" "In13.Cu" "In15.Cu")
		(hatch none 0.5)
		(connect_pads
			(clearance 0)
		)
		(min_thickness 0.25)
		(keepout
			(tracks not_allowed)
			(vias allowed)
			(pads allowed)
			(copperpour not_allowed)
			(footprints allowed)
		)
		(placement
			(enabled no)
			(sheetname "")
		)
		(fill yes
			(thermal_gap 0.5)
			(thermal_bridge_width 0.5)
			(island_removal_mode 0)
		)
		(polygon
			(pts
				(arc
					(start 374.943624 -217.878406)
					(mid 374.290844 -217.878406)
					(end 374.943624 -217.878406)
				)
			)
		)
	)
	(zone
		(layers "B.Cu" "In6.Cu" "In11.Cu" "In13.Cu" "In15.Cu")
		(hatch none 0.5)
		(connect_pads
			(clearance 0)
		)
		(min_thickness 0.25)
		(keepout
			(tracks not_allowed)
			(vias allowed)
			(pads allowed)
			(copperpour not_allowed)
			(footprints allowed)
		)
		(placement
			(enabled no)
			(sheetname "")
		)
		(fill yes
			(thermal_gap 0.5)
			(thermal_bridge_width 0.5)
			(island_removal_mode 0)
		)
		(polygon
			(pts
				(arc
					(start 132.642356 -227.64496)
					(mid 131.989576 -227.64496)
					(end 132.642356 -227.64496)
				)
			)
		)
	)
	(zone
		(layers "B.Cu" "In6.Cu" "In11.Cu" "In13.Cu" "In15.Cu")
		(hatch none 0.5)
		(connect_pads
			(clearance 0)
		)
		(min_thickness 0.25)
		(keepout
			(tracks not_allowed)
			(vias allowed)
			(pads allowed)
			(copperpour not_allowed)
			(footprints allowed)
		)
		(placement
			(enabled no)
			(sheetname "")
		)
		(fill yes
			(thermal_gap 0.5)
			(thermal_bridge_width 0.5)
			(island_removal_mode 0)
		)
		(polygon
			(pts
				(arc
					(start 130.872738 -263.686544)
					(mid 130.219958 -263.686544)
					(end 130.872738 -263.686544)
				)
			)
		)
	)
	(zone
		(layers "B.Cu" "In6.Cu" "In11.Cu" "In13.Cu" "In15.Cu")
		(hatch none 0.5)
		(connect_pads
			(clearance 0)
		)
		(min_thickness 0.25)
		(keepout
			(tracks not_allowed)
			(vias allowed)
			(pads allowed)
			(copperpour not_allowed)
			(footprints allowed)
		)
		(placement
			(enabled no)
			(sheetname "")
		)
		(fill yes
			(thermal_gap 0.5)
			(thermal_bridge_width 0.5)
			(island_removal_mode 0)
		)
		(polygon
			(pts
				(arc
					(start 51.416204 -302.716946)
					(mid 50.763424 -302.716946)
					(end 51.416204 -302.716946)
				)
			)
		)
	)
	(zone
		(layers "B.Cu" "In6.Cu" "In11.Cu" "In13.Cu" "In15.Cu")
		(hatch none 0.5)
		(connect_pads
			(clearance 0)
		)
		(min_thickness 0.25)
		(keepout
			(tracks not_allowed)
			(vias allowed)
			(pads allowed)
			(copperpour not_allowed)
			(footprints allowed)
		)
		(placement
			(enabled no)
			(sheetname "")
		)
		(fill yes
			(thermal_gap 0.5)
			(thermal_bridge_width 0.5)
			(island_removal_mode 0)
		)
		(polygon
			(pts
				(arc
					(start 32.203136 -239.81664)
					(mid 31.550356 -239.81664)
					(end 32.203136 -239.81664)
				)
			)
		)
	)
	(zone
		(layers "B.Cu" "In6.Cu" "In11.Cu" "In13.Cu" "In15.Cu")
		(hatch none 0.5)
		(connect_pads
			(clearance 0)
		)
		(min_thickness 0.25)
		(keepout
			(tracks not_allowed)
			(vias allowed)
			(pads allowed)
			(copperpour not_allowed)
			(footprints allowed)
		)
		(placement
			(enabled no)
			(sheetname "")
		)
		(fill yes
			(thermal_gap 0.5)
			(thermal_bridge_width 0.5)
			(island_removal_mode 0)
		)
		(polygon
			(pts
				(arc
					(start 425.162472 -302.716692)
					(mid 424.509692 -302.716692)
					(end 425.162472 -302.716692)
				)
			)
		)
	)
	(zone
		(layers "B.Cu" "In6.Cu" "In11.Cu" "In13.Cu" "In15.Cu")
		(hatch none 0.5)
		(connect_pads
			(clearance 0)
		)
		(min_thickness 0.25)
		(keepout
			(tracks not_allowed)
			(vias allowed)
			(pads allowed)
			(copperpour not_allowed)
			(footprints allowed)
		)
		(placement
			(enabled no)
			(sheetname "")
		)
		(fill yes
			(thermal_gap 0.5)
			(thermal_bridge_width 0.5)
			(island_removal_mode 0)
		)
		(polygon
			(pts
				(arc
					(start 345.919806 -255.547622)
					(mid 345.267026 -255.547622)
					(end 345.919806 -255.547622)
				)
			)
		)
	)
	(zone
		(layers "B.Cu" "In6.Cu" "In11.Cu" "In13.Cu" "In15.Cu")
		(hatch none 0.5)
		(connect_pads
			(clearance 0)
		)
		(min_thickness 0.25)
		(keepout
			(tracks not_allowed)
			(vias allowed)
			(pads allowed)
			(copperpour not_allowed)
			(footprints allowed)
		)
		(placement
			(enabled no)
			(sheetname "")
		)
		(fill yes
			(thermal_gap 0.5)
			(thermal_bridge_width 0.5)
			(island_removal_mode 0)
		)
		(polygon
			(pts
				(arc
					(start 99.389438 -288.917126)
					(mid 98.736658 -288.917126)
					(end 99.389438 -288.917126)
				)
			)
		)
	)
	(zone
		(layers "B.Cu" "In6.Cu" "In11.Cu" "In13.Cu" "In15.Cu")
		(hatch none 0.5)
		(connect_pads
			(clearance 0)
		)
		(min_thickness 0.25)
		(keepout
			(tracks not_allowed)
			(vias allowed)
			(pads allowed)
			(copperpour not_allowed)
			(footprints allowed)
		)
		(placement
			(enabled no)
			(sheetname "")
		)
		(fill yes
			(thermal_gap 0.5)
			(thermal_bridge_width 0.5)
			(island_removal_mode 0)
		)
		(polygon
			(pts
				(arc
					(start 341.690452 -261.244842)
					(mid 341.037672 -261.244842)
					(end 341.690452 -261.244842)
				)
			)
		)
	)
	(zone
		(layers "B.Cu" "In6.Cu" "In11.Cu" "In13.Cu" "In15.Cu")
		(hatch none 0.5)
		(connect_pads
			(clearance 0)
		)
		(min_thickness 0.25)
		(keepout
			(tracks not_allowed)
			(vias allowed)
			(pads allowed)
			(copperpour not_allowed)
			(footprints allowed)
		)
		(placement
			(enabled no)
			(sheetname "")
		)
		(fill yes
			(thermal_gap 0.5)
			(thermal_bridge_width 0.5)
			(island_removal_mode 0)
		)
		(polygon
			(pts
				(arc
					(start 119.015002 -217.064336)
					(mid 118.362222 -217.064336)
					(end 119.015002 -217.064336)
				)
			)
		)
	)
	(zone
		(layers "B.Cu" "In6.Cu" "In11.Cu" "In13.Cu" "In15.Cu")
		(hatch none 0.5)
		(connect_pads
			(clearance 0)
		)
		(min_thickness 0.25)
		(keepout
			(tracks not_allowed)
			(vias allowed)
			(pads allowed)
			(copperpour not_allowed)
			(footprints allowed)
		)
		(placement
			(enabled no)
			(sheetname "")
		)
		(fill yes
			(thermal_gap 0.5)
			(thermal_bridge_width 0.5)
			(island_removal_mode 0)
		)
		(polygon
			(pts
				(arc
					(start 340.64067 -239.853216)
					(mid 339.98789 -239.853216)
					(end 340.64067 -239.853216)
				)
			)
		)
	)
	(zone
		(layers "B.Cu" "In6.Cu" "In11.Cu" "In13.Cu" "In15.Cu")
		(hatch none 0.5)
		(connect_pads
			(clearance 0)
		)
		(min_thickness 0.25)
		(keepout
			(tracks not_allowed)
			(vias allowed)
			(pads allowed)
			(copperpour not_allowed)
			(footprints allowed)
		)
		(placement
			(enabled no)
			(sheetname "")
		)
		(fill yes
			(thermal_gap 0.5)
			(thermal_bridge_width 0.5)
			(island_removal_mode 0)
		)
		(polygon
			(pts
				(arc
					(start 36.303204 -263.616694)
					(mid 35.650424 -263.616694)
					(end 36.303204 -263.616694)
				)
			)
		)
	)
	(zone
		(layers "B.Cu" "In6.Cu" "In11.Cu" "In13.Cu" "In15.Cu")
		(hatch none 0.5)
		(connect_pads
			(clearance 0)
		)
		(min_thickness 0.25)
		(keepout
			(tracks not_allowed)
			(vias allowed)
			(pads allowed)
			(copperpour not_allowed)
			(footprints allowed)
		)
		(placement
			(enabled no)
			(sheetname "")
		)
		(fill yes
			(thermal_gap 0.5)
			(thermal_bridge_width 0.5)
			(island_removal_mode 0)
		)
		(polygon
			(pts
				(arc
					(start 177.222404 -298.466764)
					(mid 176.569624 -298.466764)
					(end 177.222404 -298.466764)
				)
			)
		)
	)
	(zone
		(layers "B.Cu" "In6.Cu" "In11.Cu" "In13.Cu" "In15.Cu")
		(hatch none 0.5)
		(connect_pads
			(clearance 0)
		)
		(min_thickness 0.25)
		(keepout
			(tracks not_allowed)
			(vias allowed)
			(pads allowed)
			(copperpour not_allowed)
			(footprints allowed)
		)
		(placement
			(enabled no)
			(sheetname "")
		)
		(fill yes
			(thermal_gap 0.5)
			(thermal_bridge_width 0.5)
			(island_removal_mode 0)
		)
		(polygon
			(pts
				(arc
					(start 425.162472 -301.866554)
					(mid 424.509692 -301.866554)
					(end 425.162472 -301.866554)
				)
			)
		)
	)
	(zone
		(layers "B.Cu" "In6.Cu" "In11.Cu" "In13.Cu" "In15.Cu")
		(hatch none 0.5)
		(connect_pads
			(clearance 0)
		)
		(min_thickness 0.25)
		(keepout
			(tracks not_allowed)
			(vias allowed)
			(pads allowed)
			(copperpour not_allowed)
			(footprints allowed)
		)
		(placement
			(enabled no)
			(sheetname "")
		)
		(fill yes
			(thermal_gap 0.5)
			(thermal_bridge_width 0.5)
			(island_removal_mode 0)
		)
		(polygon
			(pts
				(arc
					(start 92.810838 -288.917126)
					(mid 92.158058 -288.917126)
					(end 92.810838 -288.917126)
				)
			)
		)
	)
	(zone
		(layers "B.Cu" "In6.Cu" "In11.Cu" "In13.Cu" "In15.Cu")
		(hatch none 0.5)
		(connect_pads
			(clearance 0)
		)
		(min_thickness 0.25)
		(keepout
			(tracks not_allowed)
			(vias allowed)
			(pads allowed)
			(copperpour not_allowed)
			(footprints allowed)
		)
		(placement
			(enabled no)
			(sheetname "")
		)
		(fill yes
			(thermal_gap 0.5)
			(thermal_bridge_width 0.5)
			(island_removal_mode 0)
		)
		(polygon
			(pts
				(arc
					(start 132.172202 -236.597952)
					(mid 131.519422 -236.597952)
					(end 132.172202 -236.597952)
				)
			)
		)
	)
	(zone
		(layers "B.Cu" "In6.Cu" "In11.Cu" "In13.Cu" "In15.Cu")
		(hatch none 0.5)
		(connect_pads
			(clearance 0)
		)
		(min_thickness 0.25)
		(keepout
			(tracks not_allowed)
			(vias allowed)
			(pads allowed)
			(copperpour not_allowed)
			(footprints allowed)
		)
		(placement
			(enabled no)
			(sheetname "")
		)
		(fill yes
			(thermal_gap 0.5)
			(thermal_bridge_width 0.5)
			(island_removal_mode 0)
		)
		(polygon
			(pts
				(arc
					(start 47.290736 -303.566576)
					(mid 46.637956 -303.566576)
					(end 47.290736 -303.566576)
				)
			)
		)
	)
	(zone
		(layers "B.Cu" "In6.Cu" "In11.Cu" "In13.Cu" "In15.Cu")
		(hatch none 0.5)
		(connect_pads
			(clearance 0)
		)
		(min_thickness 0.25)
		(keepout
			(tracks not_allowed)
			(vias allowed)
			(pads allowed)
			(copperpour not_allowed)
			(footprints allowed)
		)
		(placement
			(enabled no)
			(sheetname "")
		)
		(fill yes
			(thermal_gap 0.5)
			(thermal_bridge_width 0.5)
			(island_removal_mode 0)
		)
		(polygon
			(pts
				(arc
					(start 284.243272 -315.46673)
					(mid 283.590492 -315.46673)
					(end 284.243272 -315.46673)
				)
			)
		)
	)
	(zone
		(layers "B.Cu" "In6.Cu" "In11.Cu" "In13.Cu" "In15.Cu")
		(hatch none 0.5)
		(connect_pads
			(clearance 0)
		)
		(min_thickness 0.25)
		(keepout
			(tracks not_allowed)
			(vias allowed)
			(pads allowed)
			(copperpour not_allowed)
			(footprints allowed)
		)
		(placement
			(enabled no)
			(sheetname "")
		)
		(fill yes
			(thermal_gap 0.5)
			(thermal_bridge_width 0.5)
			(island_removal_mode 0)
		)
		(polygon
			(pts
				(arc
					(start 93.280738 -288.103056)
					(mid 92.627958 -288.103056)
					(end 93.280738 -288.103056)
				)
			)
		)
	)
	(zone
		(layers "B.Cu" "In6.Cu" "In11.Cu" "In13.Cu" "In15.Cu")
		(hatch none 0.5)
		(connect_pads
			(clearance 0)
		)
		(min_thickness 0.25)
		(keepout
			(tracks not_allowed)
			(vias allowed)
			(pads allowed)
			(copperpour not_allowed)
			(footprints allowed)
		)
		(placement
			(enabled no)
			(sheetname "")
		)
		(fill yes
			(thermal_gap 0.5)
			(thermal_bridge_width 0.5)
			(island_removal_mode 0)
		)
		(polygon
			(pts
				(arc
					(start 132.172202 -241.481102)
					(mid 131.519422 -241.481102)
					(end 132.172202 -241.481102)
				)
			)
		)
	)
	(zone
		(layers "B.Cu" "In6.Cu" "In11.Cu" "In13.Cu" "In15.Cu")
		(hatch none 0.5)
		(connect_pads
			(clearance 0)
		)
		(min_thickness 0.25)
		(keepout
			(tracks not_allowed)
			(vias allowed)
			(pads allowed)
			(copperpour not_allowed)
			(footprints allowed)
		)
		(placement
			(enabled no)
			(sheetname "")
		)
		(fill yes
			(thermal_gap 0.5)
			(thermal_bridge_width 0.5)
			(island_removal_mode 0)
		)
		(polygon
			(pts
				(arc
					(start 295.230804 -284.016704)
					(mid 294.578024 -284.016704)
					(end 295.230804 -284.016704)
				)
			)
		)
	)
	(zone
		(layers "B.Cu" "In6.Cu" "In11.Cu" "In13.Cu" "In15.Cu")
		(hatch none 0.5)
		(connect_pads
			(clearance 0)
		)
		(min_thickness 0.25)
		(keepout
			(tracks not_allowed)
			(vias allowed)
			(pads allowed)
			(copperpour not_allowed)
			(footprints allowed)
		)
		(placement
			(enabled no)
			(sheetname "")
		)
		(fill yes
			(thermal_gap 0.5)
			(thermal_bridge_width 0.5)
			(island_removal_mode 0)
		)
		(polygon
			(pts
				(arc
					(start 47.290736 -301.01667)
					(mid 46.637956 -301.01667)
					(end 47.290736 -301.01667)
				)
			)
		)
	)
	(zone
		(layers "B.Cu" "In6.Cu" "In11.Cu" "In13.Cu" "In15.Cu")
		(hatch none 0.5)
		(connect_pads
			(clearance 0)
		)
		(min_thickness 0.25)
		(keepout
			(tracks not_allowed)
			(vias allowed)
			(pads allowed)
			(copperpour not_allowed)
			(footprints allowed)
		)
		(placement
			(enabled no)
			(sheetname "")
		)
		(fill yes
			(thermal_gap 0.5)
			(thermal_bridge_width 0.5)
			(island_removal_mode 0)
		)
		(polygon
			(pts
				(arc
					(start 94.220538 -262.058658)
					(mid 93.567758 -262.058658)
					(end 94.220538 -262.058658)
				)
			)
		)
	)
	(zone
		(layers "B.Cu" "In6.Cu" "In11.Cu" "In13.Cu" "In15.Cu")
		(hatch none 0.5)
		(connect_pads
			(clearance 0)
		)
		(min_thickness 0.25)
		(keepout
			(tracks not_allowed)
			(vias allowed)
			(pads allowed)
			(copperpour not_allowed)
			(footprints allowed)
		)
		(placement
			(enabled no)
			(sheetname "")
		)
		(fill yes
			(thermal_gap 0.5)
			(thermal_bridge_width 0.5)
			(island_removal_mode 0)
		)
		(polygon
			(pts
				(arc
					(start 378.342652 -264.50036)
					(mid 377.689872 -264.50036)
					(end 378.342652 -264.50036)
				)
			)
		)
	)
	(zone
		(layers "B.Cu" "In6.Cu" "In11.Cu" "In13.Cu" "In15.Cu")
		(hatch none 0.5)
		(connect_pads
			(clearance 0)
		)
		(min_thickness 0.25)
		(keepout
			(tracks not_allowed)
			(vias allowed)
			(pads allowed)
			(copperpour not_allowed)
			(footprints allowed)
		)
		(placement
			(enabled no)
			(sheetname "")
		)
		(fill yes
			(thermal_gap 0.5)
			(thermal_bridge_width 0.5)
			(island_removal_mode 0)
		)
		(polygon
			(pts
				(arc
					(start 421.062404 -230.466646)
					(mid 420.409624 -230.466646)
					(end 421.062404 -230.466646)
				)
			)
		)
	)
	(zone
		(layers "B.Cu" "In6.Cu" "In11.Cu" "In13.Cu" "In15.Cu")
		(hatch none 0.5)
		(connect_pads
			(clearance 0)
		)
		(min_thickness 0.25)
		(keepout
			(tracks not_allowed)
			(vias allowed)
			(pads allowed)
			(copperpour not_allowed)
			(footprints allowed)
		)
		(placement
			(enabled no)
			(sheetname "")
		)
		(fill yes
			(thermal_gap 0.5)
			(thermal_bridge_width 0.5)
			(island_removal_mode 0)
		)
		(polygon
			(pts
				(arc
					(start 443.693804 -267.866622)
					(mid 443.041024 -267.866622)
					(end 443.693804 -267.866622)
				)
			)
		)
	)
	(zone
		(layers "B.Cu" "In6.Cu" "In11.Cu" "In13.Cu" "In15.Cu")
		(hatch none 0.5)
		(connect_pads
			(clearance 0)
		)
		(min_thickness 0.25)
		(keepout
			(tracks not_allowed)
			(vias allowed)
			(pads allowed)
			(copperpour not_allowed)
			(footprints allowed)
		)
		(placement
			(enabled no)
			(sheetname "")
		)
		(fill yes
			(thermal_gap 0.5)
			(thermal_bridge_width 0.5)
			(island_removal_mode 0)
		)
		(polygon
			(pts
				(arc
					(start 436.150004 -293.366698)
					(mid 435.497224 -293.366698)
					(end 436.150004 -293.366698)
				)
			)
		)
	)
	(zone
		(layers "B.Cu" "In6.Cu" "In11.Cu" "In13.Cu" "In15.Cu")
		(hatch none 0.5)
		(connect_pads
			(clearance 0)
		)
		(min_thickness 0.25)
		(keepout
			(tracks not_allowed)
			(vias allowed)
			(pads allowed)
			(copperpour not_allowed)
			(footprints allowed)
		)
		(placement
			(enabled no)
			(sheetname "")
		)
		(fill yes
			(thermal_gap 0.5)
			(thermal_bridge_width 0.5)
			(island_removal_mode 0)
		)
		(polygon
			(pts
				(arc
					(start 93.750384 -262.872474)
					(mid 93.097604 -262.872474)
					(end 93.750384 -262.872474)
				)
			)
		)
	)
	(zone
		(layers "B.Cu" "In6.Cu" "In11.Cu" "In13.Cu" "In15.Cu")
		(hatch none 0.5)
		(connect_pads
			(clearance 0)
		)
		(min_thickness 0.25)
		(keepout
			(tracks not_allowed)
			(vias allowed)
			(pads allowed)
			(copperpour not_allowed)
			(footprints allowed)
		)
		(placement
			(enabled no)
			(sheetname "")
		)
		(fill yes
			(thermal_gap 0.5)
			(thermal_bridge_width 0.5)
			(island_removal_mode 0)
		)
		(polygon
			(pts
				(arc
					(start 128.993138 -258.80314)
					(mid 128.340358 -258.80314)
					(end 128.993138 -258.80314)
				)
			)
		)
	)
	(zone
		(layers "B.Cu" "In6.Cu" "In11.Cu" "In13.Cu" "In15.Cu")
		(hatch none 0.5)
		(connect_pads
			(clearance 0)
		)
		(min_thickness 0.25)
		(keepout
			(tracks not_allowed)
			(vias allowed)
			(pads allowed)
			(copperpour not_allowed)
			(footprints allowed)
		)
		(placement
			(enabled no)
			(sheetname "")
		)
		(fill yes
			(thermal_gap 0.5)
			(thermal_bridge_width 0.5)
			(island_removal_mode 0)
		)
		(polygon
			(pts
				(arc
					(start 133.112002 -226.831144)
					(mid 132.459222 -226.831144)
					(end 133.112002 -226.831144)
				)
			)
		)
	)
	(zone
		(layers "B.Cu" "In6.Cu" "In11.Cu" "In13.Cu" "In15.Cu")
		(hatch none 0.5)
		(connect_pads
			(clearance 0)
		)
		(min_thickness 0.25)
		(keepout
			(tracks not_allowed)
			(vias allowed)
			(pads allowed)
			(copperpour not_allowed)
			(footprints allowed)
		)
		(placement
			(enabled no)
			(sheetname "")
		)
		(fill yes
			(thermal_gap 0.5)
			(thermal_bridge_width 0.5)
			(island_removal_mode 0)
		)
		(polygon
			(pts
				(arc
					(start 351.088706 -288.917126)
					(mid 350.435926 -288.917126)
					(end 351.088706 -288.917126)
				)
			)
		)
	)
	(zone
		(layers "B.Cu" "In6.Cu" "In11.Cu" "In13.Cu" "In15.Cu")
		(hatch none 0.5)
		(connect_pads
			(clearance 0)
		)
		(min_thickness 0.25)
		(keepout
			(tracks not_allowed)
			(vias allowed)
			(pads allowed)
			(copperpour not_allowed)
			(footprints allowed)
		)
		(placement
			(enabled no)
			(sheetname "")
		)
		(fill yes
			(thermal_gap 0.5)
			(thermal_bridge_width 0.5)
			(island_removal_mode 0)
		)
		(polygon
			(pts
				(arc
					(start 347.329506 -288.917126)
					(mid 346.676726 -288.917126)
					(end 347.329506 -288.917126)
				)
			)
		)
	)
	(zone
		(layers "B.Cu" "In6.Cu" "In11.Cu" "In13.Cu" "In15.Cu")
		(hatch none 0.5)
		(connect_pads
			(clearance 0)
		)
		(min_thickness 0.25)
		(keepout
			(tracks not_allowed)
			(vias allowed)
			(pads allowed)
			(copperpour not_allowed)
			(footprints allowed)
		)
		(placement
			(enabled no)
			(sheetname "")
		)
		(fill yes
			(thermal_gap 0.5)
			(thermal_bridge_width 0.5)
			(island_removal_mode 0)
		)
		(polygon
			(pts
				(arc
					(start 177.222404 -199.01662)
					(mid 176.569624 -199.01662)
					(end 177.222404 -199.01662)
				)
			)
		)
	)
	(zone
		(layers "B.Cu" "In6.Cu" "In11.Cu" "In13.Cu" "In15.Cu")
		(hatch none 0.5)
		(connect_pads
			(clearance 0)
		)
		(min_thickness 0.25)
		(keepout
			(tracks not_allowed)
			(vias allowed)
			(pads allowed)
			(copperpour not_allowed)
			(footprints allowed)
		)
		(placement
			(enabled no)
			(sheetname "")
		)
		(fill yes
			(thermal_gap 0.5)
			(thermal_bridge_width 0.5)
			(island_removal_mode 0)
		)
		(polygon
			(pts
				(arc
					(start 130.402584 -271.011396)
					(mid 129.749804 -271.011396)
					(end 130.402584 -271.011396)
				)
			)
		)
	)
	(zone
		(layers "B.Cu" "In6.Cu" "In11.Cu" "In13.Cu" "In15.Cu")
		(hatch none 0.5)
		(connect_pads
			(clearance 0)
		)
		(min_thickness 0.25)
		(keepout
			(tracks not_allowed)
			(vias allowed)
			(pads allowed)
			(copperpour not_allowed)
			(footprints allowed)
		)
		(placement
			(enabled no)
			(sheetname "")
		)
		(fill yes
			(thermal_gap 0.5)
			(thermal_bridge_width 0.5)
			(island_removal_mode 0)
		)
		(polygon
			(pts
				(arc
					(start 51.416204 -300.166786)
					(mid 50.763424 -300.166786)
					(end 51.416204 -300.166786)
				)
			)
		)
	)
	(zone
		(layers "B.Cu" "In6.Cu" "In11.Cu" "In13.Cu" "In15.Cu")
		(hatch none 0.5)
		(connect_pads
			(clearance 0)
		)
		(min_thickness 0.25)
		(keepout
			(tracks not_allowed)
			(vias allowed)
			(pads allowed)
			(copperpour not_allowed)
			(footprints allowed)
		)
		(placement
			(enabled no)
			(sheetname "")
		)
		(fill yes
			(thermal_gap 0.5)
			(thermal_bridge_width 0.5)
			(island_removal_mode 0)
		)
		(polygon
			(pts
				(arc
					(start 374.47347 -249.620024)
					(mid 373.82069 -249.620024)
					(end 374.47347 -249.620024)
				)
			)
		)
	)
	(zone
		(layers "B.Cu" "In6.Cu" "In11.Cu" "In13.Cu" "In15.Cu")
		(hatch none 0.5)
		(connect_pads
			(clearance 0)
		)
		(min_thickness 0.25)
		(keepout
			(tracks not_allowed)
			(vias allowed)
			(pads allowed)
			(copperpour not_allowed)
			(footprints allowed)
		)
		(placement
			(enabled no)
			(sheetname "")
		)
		(fill yes
			(thermal_gap 0.5)
			(thermal_bridge_width 0.5)
			(island_removal_mode 0)
		)
		(polygon
			(pts
				(arc
					(start 378.812806 -275.08073)
					(mid 378.160026 -275.08073)
					(end 378.812806 -275.08073)
				)
			)
		)
	)
	(zone
		(layers "B.Cu" "In6.Cu" "In11.Cu" "In13.Cu" "In15.Cu")
		(hatch none 0.5)
		(connect_pads
			(clearance 0)
		)
		(min_thickness 0.25)
		(keepout
			(tracks not_allowed)
			(vias allowed)
			(pads allowed)
			(copperpour not_allowed)
			(footprints allowed)
		)
		(placement
			(enabled no)
			(sheetname "")
		)
		(fill yes
			(thermal_gap 0.5)
			(thermal_bridge_width 0.5)
			(island_removal_mode 0)
		)
		(polygon
			(pts
				(arc
					(start 93.640402 -228.45903)
					(mid 92.987622 -228.45903)
					(end 93.640402 -228.45903)
				)
			)
		)
	)
	(zone
		(layers "B.Cu" "In6.Cu" "In11.Cu" "In13.Cu" "In15.Cu")
		(hatch none 0.5)
		(connect_pads
			(clearance 0)
		)
		(min_thickness 0.25)
		(keepout
			(tracks not_allowed)
			(vias allowed)
			(pads allowed)
			(copperpour not_allowed)
			(footprints allowed)
		)
		(placement
			(enabled no)
			(sheetname "")
		)
		(fill yes
			(thermal_gap 0.5)
			(thermal_bridge_width 0.5)
			(island_removal_mode 0)
		)
		(polygon
			(pts
				(arc
					(start 342.160606 -271.825212)
					(mid 341.507826 -271.825212)
					(end 342.160606 -271.825212)
				)
			)
		)
	)
	(zone
		(layers "B.Cu" "In6.Cu" "In11.Cu" "In13.Cu" "In15.Cu")
		(hatch none 0.5)
		(connect_pads
			(clearance 0)
		)
		(min_thickness 0.25)
		(keepout
			(tracks not_allowed)
			(vias allowed)
			(pads allowed)
			(copperpour not_allowed)
			(footprints allowed)
		)
		(placement
			(enabled no)
			(sheetname "")
		)
		(fill yes
			(thermal_gap 0.5)
			(thermal_bridge_width 0.5)
			(island_removal_mode 0)
		)
		(polygon
			(pts
				(arc
					(start 366.95507 -217.064336)
					(mid 366.30229 -217.064336)
					(end 366.95507 -217.064336)
				)
			)
		)
	)
	(zone
		(layers "B.Cu" "In6.Cu" "In11.Cu" "In13.Cu" "In15.Cu")
		(hatch none 0.5)
		(connect_pads
			(clearance 0)
		)
		(min_thickness 0.25)
		(keepout
			(tracks not_allowed)
			(vias allowed)
			(pads allowed)
			(copperpour not_allowed)
			(footprints allowed)
		)
		(placement
			(enabled no)
			(sheetname "")
		)
		(fill yes
			(thermal_gap 0.5)
			(thermal_bridge_width 0.5)
			(island_removal_mode 0)
		)
		(polygon
			(pts
				(arc
					(start 192.310004 -238.966756)
					(mid 191.657224 -238.966756)
					(end 192.310004 -238.966756)
				)
			)
		)
	)
	(zone
		(layers "B.Cu" "In6.Cu" "In11.Cu" "In13.Cu" "In15.Cu")
		(hatch none 0.5)
		(connect_pads
			(clearance 0)
		)
		(min_thickness 0.25)
		(keepout
			(tracks not_allowed)
			(vias allowed)
			(pads allowed)
			(copperpour not_allowed)
			(footprints allowed)
		)
		(placement
			(enabled no)
			(sheetname "")
		)
		(fill yes
			(thermal_gap 0.5)
			(thermal_bridge_width 0.5)
			(island_removal_mode 0)
		)
		(polygon
			(pts
				(arc
					(start 32.203136 -245.76659)
					(mid 31.550356 -245.76659)
					(end 32.203136 -245.76659)
				)
			)
		)
	)
	(zone
		(layers "B.Cu" "In6.Cu" "In11.Cu" "In13.Cu" "In15.Cu")
		(hatch none 0.5)
		(connect_pads
			(clearance 0)
		)
		(min_thickness 0.25)
		(keepout
			(tracks not_allowed)
			(vias allowed)
			(pads allowed)
			(copperpour not_allowed)
			(footprints allowed)
		)
		(placement
			(enabled no)
			(sheetname "")
		)
		(fill yes
			(thermal_gap 0.5)
			(thermal_bridge_width 0.5)
			(island_removal_mode 0)
		)
		(polygon
			(pts
				(arc
					(start 357.55707 -217.064336)
					(mid 356.90429 -217.064336)
					(end 357.55707 -217.064336)
				)
			)
		)
	)
	(zone
		(layers "B.Cu" "In6.Cu" "In11.Cu" "In13.Cu" "In15.Cu")
		(hatch none 0.5)
		(connect_pads
			(clearance 0)
		)
		(min_thickness 0.25)
		(keepout
			(tracks not_allowed)
			(vias allowed)
			(pads allowed)
			(copperpour not_allowed)
			(footprints allowed)
		)
		(placement
			(enabled no)
			(sheetname "")
		)
		(fill yes
			(thermal_gap 0.5)
			(thermal_bridge_width 0.5)
			(island_removal_mode 0)
		)
		(polygon
			(pts
				(arc
					(start 342.050624 -235.783882)
					(mid 341.397844 -235.783882)
					(end 342.050624 -235.783882)
				)
			)
		)
	)
	(zone
		(layers "B.Cu" "In6.Cu" "In11.Cu" "In13.Cu" "In15.Cu")
		(hatch none 0.5)
		(connect_pads
			(clearance 0)
		)
		(min_thickness 0.25)
		(keepout
			(tracks not_allowed)
			(vias allowed)
			(pads allowed)
			(copperpour not_allowed)
			(footprints allowed)
		)
		(placement
			(enabled no)
			(sheetname "")
		)
		(fill yes
			(thermal_gap 0.5)
			(thermal_bridge_width 0.5)
			(island_removal_mode 0)
		)
		(polygon
			(pts
				(arc
					(start 342.160352 -289.807142)
					(mid 341.507572 -289.807142)
					(end 342.160352 -289.807142)
				)
			)
		)
	)
	(zone
		(layers "B.Cu" "In6.Cu" "In11.Cu" "In13.Cu" "In15.Cu")
		(hatch none 0.5)
		(connect_pads
			(clearance 0)
		)
		(min_thickness 0.25)
		(keepout
			(tracks not_allowed)
			(vias allowed)
			(pads allowed)
			(copperpour not_allowed)
			(footprints allowed)
		)
		(placement
			(enabled no)
			(sheetname "")
		)
		(fill yes
			(thermal_gap 0.5)
			(thermal_bridge_width 0.5)
			(island_removal_mode 0)
		)
		(polygon
			(pts
				(arc
					(start 131.702556 -240.667286)
					(mid 131.049776 -240.667286)
					(end 131.702556 -240.667286)
				)
			)
		)
	)
	(zone
		(layers "B.Cu" "In6.Cu" "In11.Cu" "In13.Cu" "In15.Cu")
		(hatch none 0.5)
		(connect_pads
			(clearance 0)
		)
		(min_thickness 0.25)
		(keepout
			(tracks not_allowed)
			(vias allowed)
			(pads allowed)
			(copperpour not_allowed)
			(footprints allowed)
		)
		(placement
			(enabled no)
			(sheetname "")
		)
		(fill yes
			(thermal_gap 0.5)
			(thermal_bridge_width 0.5)
			(island_removal_mode 0)
		)
		(polygon
			(pts
				(arc
					(start 36.303204 -237.266734)
					(mid 35.650424 -237.266734)
					(end 36.303204 -237.266734)
				)
			)
		)
	)
	(zone
		(layers "B.Cu" "In6.Cu" "In11.Cu" "In13.Cu" "In15.Cu")
		(hatch none 0.5)
		(connect_pads
			(clearance 0)
		)
		(min_thickness 0.25)
		(keepout
			(tracks not_allowed)
			(vias allowed)
			(pads allowed)
			(copperpour not_allowed)
			(footprints allowed)
		)
		(placement
			(enabled no)
			(sheetname "")
		)
		(fill yes
			(thermal_gap 0.5)
			(thermal_bridge_width 0.5)
			(island_removal_mode 0)
		)
		(polygon
			(pts
				(arc
					(start 127.113538 -258.80314)
					(mid 126.460758 -258.80314)
					(end 127.113538 -258.80314)
				)
			)
		)
	)
	(zone
		(layers "B.Cu" "In6.Cu" "In11.Cu" "In13.Cu" "In15.Cu")
		(hatch none 0.5)
		(connect_pads
			(clearance 0)
		)
		(min_thickness 0.25)
		(keepout
			(tracks not_allowed)
			(vias allowed)
			(pads allowed)
			(copperpour not_allowed)
			(footprints allowed)
		)
		(placement
			(enabled no)
			(sheetname "")
		)
		(fill yes
			(thermal_gap 0.5)
			(thermal_bridge_width 0.5)
			(island_removal_mode 0)
		)
		(polygon
			(pts
				(arc
					(start 91.871038 -288.917126)
					(mid 91.218258 -288.917126)
					(end 91.871038 -288.917126)
				)
			)
		)
	)
	(zone
		(layers "B.Cu" "In6.Cu" "In11.Cu" "In13.Cu" "In15.Cu")
		(hatch none 0.5)
		(connect_pads
			(clearance 0)
		)
		(min_thickness 0.25)
		(keepout
			(tracks not_allowed)
			(vias allowed)
			(pads allowed)
			(copperpour not_allowed)
			(footprints allowed)
		)
		(placement
			(enabled no)
			(sheetname "")
		)
		(fill yes
			(thermal_gap 0.5)
			(thermal_bridge_width 0.5)
			(island_removal_mode 0)
		)
		(polygon
			(pts
				(arc
					(start 340.171024 -229.272846)
					(mid 339.518244 -229.272846)
					(end 340.171024 -229.272846)
				)
			)
		)
	)
	(zone
		(layers "B.Cu" "In6.Cu" "In11.Cu" "In13.Cu" "In15.Cu")
		(hatch none 0.5)
		(connect_pads
			(clearance 0)
		)
		(min_thickness 0.25)
		(keepout
			(tracks not_allowed)
			(vias allowed)
			(pads allowed)
			(copperpour not_allowed)
			(footprints allowed)
		)
		(placement
			(enabled no)
			(sheetname "")
		)
		(fill yes
			(thermal_gap 0.5)
			(thermal_bridge_width 0.5)
			(island_removal_mode 0)
		)
		(polygon
			(pts
				(arc
					(start 376.35307 -217.064336)
					(mid 375.70029 -217.064336)
					(end 376.35307 -217.064336)
				)
			)
		)
	)
	(zone
		(layers "B.Cu" "In6.Cu" "In11.Cu" "In13.Cu" "In15.Cu")
		(hatch none 0.5)
		(connect_pads
			(clearance 0)
		)
		(min_thickness 0.25)
		(keepout
			(tracks not_allowed)
			(vias allowed)
			(pads allowed)
			(copperpour not_allowed)
			(footprints allowed)
		)
		(placement
			(enabled no)
			(sheetname "")
		)
		(fill yes
			(thermal_gap 0.5)
			(thermal_bridge_width 0.5)
			(island_removal_mode 0)
		)
		(polygon
			(pts
				(arc
					(start 192.310004 -240.666778)
					(mid 191.657224 -240.666778)
					(end 192.310004 -240.666778)
				)
			)
		)
	)
	(zone
		(layers "B.Cu" "In6.Cu" "In11.Cu" "In13.Cu" "In15.Cu")
		(hatch none 0.5)
		(connect_pads
			(clearance 0)
		)
		(min_thickness 0.25)
		(keepout
			(tracks not_allowed)
			(vias allowed)
			(pads allowed)
			(copperpour not_allowed)
			(footprints allowed)
		)
		(placement
			(enabled no)
			(sheetname "")
		)
		(fill yes
			(thermal_gap 0.5)
			(thermal_bridge_width 0.5)
			(island_removal_mode 0)
		)
		(polygon
			(pts
				(arc
					(start 192.310004 -233.016806)
					(mid 191.657224 -233.016806)
					(end 192.310004 -233.016806)
				)
			)
		)
	)
	(zone
		(layers "B.Cu" "In6.Cu" "In11.Cu" "In13.Cu" "In15.Cu")
		(hatch none 0.5)
		(connect_pads
			(clearance 0)
		)
		(min_thickness 0.25)
		(keepout
			(tracks not_allowed)
			(vias allowed)
			(pads allowed)
			(copperpour not_allowed)
			(footprints allowed)
		)
		(placement
			(enabled no)
			(sheetname "")
		)
		(fill yes
			(thermal_gap 0.5)
			(thermal_bridge_width 0.5)
			(island_removal_mode 0)
		)
		(polygon
			(pts
				(arc
					(start 177.222404 -195.616576)
					(mid 176.569624 -195.616576)
					(end 177.222404 -195.616576)
				)
			)
		)
	)
	(zone
		(layers "B.Cu" "In6.Cu" "In11.Cu" "In13.Cu" "In15.Cu")
		(hatch none 0.5)
		(connect_pads
			(clearance 0)
		)
		(min_thickness 0.25)
		(keepout
			(tracks not_allowed)
			(vias allowed)
			(pads allowed)
			(copperpour not_allowed)
			(footprints allowed)
		)
		(placement
			(enabled no)
			(sheetname "")
		)
		(fill yes
			(thermal_gap 0.5)
			(thermal_bridge_width 0.5)
			(island_removal_mode 0)
		)
		(polygon
			(pts
				(arc
					(start 342.160606 -253.919736)
					(mid 341.507826 -253.919736)
					(end 342.160606 -253.919736)
				)
			)
		)
	)
	(zone
		(layers "B.Cu" "In6.Cu" "In11.Cu" "In13.Cu" "In15.Cu")
		(hatch none 0.5)
		(connect_pads
			(clearance 0)
		)
		(min_thickness 0.25)
		(keepout
			(tracks not_allowed)
			(vias allowed)
			(pads allowed)
			(copperpour not_allowed)
			(footprints allowed)
		)
		(placement
			(enabled no)
			(sheetname "")
		)
		(fill yes
			(thermal_gap 0.5)
			(thermal_bridge_width 0.5)
			(island_removal_mode 0)
		)
		(polygon
			(pts
				(arc
					(start 98.449638 -288.917126)
					(mid 97.796858 -288.917126)
					(end 98.449638 -288.917126)
				)
			)
		)
	)
	(zone
		(layers "B.Cu" "In6.Cu" "In11.Cu" "In13.Cu" "In15.Cu")
		(hatch none 0.5)
		(connect_pads
			(clearance 0)
		)
		(min_thickness 0.25)
		(keepout
			(tracks not_allowed)
			(vias allowed)
			(pads allowed)
			(copperpour not_allowed)
			(footprints allowed)
		)
		(placement
			(enabled no)
			(sheetname "")
		)
		(fill yes
			(thermal_gap 0.5)
			(thermal_bridge_width 0.5)
			(island_removal_mode 0)
		)
		(polygon
			(pts
				(arc
					(start 32.203136 -267.866622)
					(mid 31.550356 -267.866622)
					(end 32.203136 -267.866622)
				)
			)
		)
	)
	(zone
		(layers "B.Cu" "In6.Cu" "In11.Cu" "In13.Cu" "In15.Cu")
		(hatch none 0.5)
		(connect_pads
			(clearance 0)
		)
		(min_thickness 0.25)
		(keepout
			(tracks not_allowed)
			(vias allowed)
			(pads allowed)
			(copperpour not_allowed)
			(footprints allowed)
		)
		(placement
			(enabled no)
			(sheetname "")
		)
		(fill yes
			(thermal_gap 0.5)
			(thermal_bridge_width 0.5)
			(island_removal_mode 0)
		)
		(polygon
			(pts
				(arc
					(start 93.750384 -279.150318)
					(mid 93.097604 -279.150318)
					(end 93.750384 -279.150318)
				)
			)
		)
	)
	(zone
		(layers "B.Cu" "In6.Cu" "In11.Cu" "In13.Cu" "In15.Cu")
		(hatch none 0.5)
		(connect_pads
			(clearance 0)
		)
		(min_thickness 0.25)
		(keepout
			(tracks not_allowed)
			(vias allowed)
			(pads allowed)
			(copperpour not_allowed)
			(footprints allowed)
		)
		(placement
			(enabled no)
			(sheetname "")
		)
		(fill yes
			(thermal_gap 0.5)
			(thermal_bridge_width 0.5)
			(island_removal_mode 0)
		)
		(polygon
			(pts
				(arc
					(start 32.203136 -211.766658)
					(mid 31.550356 -211.766658)
					(end 32.203136 -211.766658)
				)
			)
		)
	)
	(zone
		(layers "B.Cu" "In6.Cu" "In11.Cu" "In13.Cu" "In15.Cu")
		(hatch none 0.5)
		(connect_pads
			(clearance 0)
		)
		(min_thickness 0.25)
		(keepout
			(tracks not_allowed)
			(vias allowed)
			(pads allowed)
			(copperpour not_allowed)
			(footprints allowed)
		)
		(placement
			(enabled no)
			(sheetname "")
		)
		(fill yes
			(thermal_gap 0.5)
			(thermal_bridge_width 0.5)
			(island_removal_mode 0)
		)
		(polygon
			(pts
				(arc
					(start 440.173872 -263.616694)
					(mid 439.521092 -263.616694)
					(end 440.173872 -263.616694)
				)
			)
		)
	)
	(zone
		(layers "B.Cu" "In6.Cu" "In11.Cu" "In13.Cu" "In15.Cu")
		(hatch none 0.5)
		(connect_pads
			(clearance 0)
		)
		(min_thickness 0.25)
		(keepout
			(tracks not_allowed)
			(vias allowed)
			(pads allowed)
			(copperpour not_allowed)
			(footprints allowed)
		)
		(placement
			(enabled no)
			(sheetname "")
		)
		(fill yes
			(thermal_gap 0.5)
			(thermal_bridge_width 0.5)
			(island_removal_mode 0)
		)
		(polygon
			(pts
				(arc
					(start 377.763024 -237.411514)
					(mid 377.110244 -237.411514)
					(end 377.763024 -237.411514)
				)
			)
		)
	)
	(zone
		(layers "B.Cu" "In6.Cu" "In11.Cu" "In13.Cu" "In15.Cu")
		(hatch none 0.5)
		(connect_pads
			(clearance 0)
		)
		(min_thickness 0.25)
		(keepout
			(tracks not_allowed)
			(vias allowed)
			(pads allowed)
			(copperpour not_allowed)
			(footprints allowed)
		)
		(placement
			(enabled no)
			(sheetname "")
		)
		(fill yes
			(thermal_gap 0.5)
			(thermal_bridge_width 0.5)
			(island_removal_mode 0)
		)
		(polygon
			(pts
				(arc
					(start 339.810852 -272.639282)
					(mid 339.158072 -272.639282)
					(end 339.810852 -272.639282)
				)
			)
		)
	)
	(zone
		(layers "B.Cu" "In6.Cu" "In11.Cu" "In13.Cu" "In15.Cu")
		(hatch none 0.5)
		(connect_pads
			(clearance 0)
		)
		(min_thickness 0.25)
		(keepout
			(tracks not_allowed)
			(vias allowed)
			(pads allowed)
			(copperpour not_allowed)
			(footprints allowed)
		)
		(placement
			(enabled no)
			(sheetname "")
		)
		(fill yes
			(thermal_gap 0.5)
			(thermal_bridge_width 0.5)
			(island_removal_mode 0)
		)
		(polygon
			(pts
				(arc
					(start 129.932938 -270.19758)
					(mid 129.280158 -270.19758)
					(end 129.932938 -270.19758)
				)
			)
		)
	)
	(zone
		(layers "B.Cu" "In6.Cu" "In11.Cu" "In13.Cu" "In15.Cu")
		(hatch none 0.5)
		(connect_pads
			(clearance 0)
		)
		(min_thickness 0.25)
		(keepout
			(tracks not_allowed)
			(vias allowed)
			(pads allowed)
			(copperpour not_allowed)
			(footprints allowed)
		)
		(placement
			(enabled no)
			(sheetname "")
		)
		(fill yes
			(thermal_gap 0.5)
			(thermal_bridge_width 0.5)
			(island_removal_mode 0)
		)
		(polygon
			(pts
				(arc
					(start 342.630252 -267.755878)
					(mid 341.977472 -267.755878)
					(end 342.630252 -267.755878)
				)
			)
		)
	)
	(zone
		(layers "B.Cu" "In6.Cu" "In11.Cu" "In13.Cu" "In15.Cu")
		(hatch none 0.5)
		(connect_pads
			(clearance 0)
		)
		(min_thickness 0.25)
		(keepout
			(tracks not_allowed)
			(vias allowed)
			(pads allowed)
			(copperpour not_allowed)
			(footprints allowed)
		)
		(placement
			(enabled no)
			(sheetname "")
		)
		(fill yes
			(thermal_gap 0.5)
			(thermal_bridge_width 0.5)
			(island_removal_mode 0)
		)
		(polygon
			(pts
				(arc
					(start 132.172202 -228.45903)
					(mid 131.519422 -228.45903)
					(end 132.172202 -228.45903)
				)
			)
		)
	)
	(zone
		(layers "B.Cu" "In6.Cu" "In11.Cu" "In13.Cu" "In15.Cu")
		(hatch none 0.5)
		(connect_pads
			(clearance 0)
		)
		(min_thickness 0.25)
		(keepout
			(tracks not_allowed)
			(vias allowed)
			(pads allowed)
			(copperpour not_allowed)
			(footprints allowed)
		)
		(placement
			(enabled no)
			(sheetname "")
		)
		(fill yes
			(thermal_gap 0.5)
			(thermal_bridge_width 0.5)
			(island_removal_mode 0)
		)
		(polygon
			(pts
				(arc
					(start 342.630252 -272.639282)
					(mid 341.977472 -272.639282)
					(end 342.630252 -272.639282)
				)
			)
		)
	)
	(zone
		(layers "B.Cu" "In6.Cu" "In11.Cu" "In13.Cu" "In15.Cu")
		(hatch none 0.5)
		(connect_pads
			(clearance 0)
		)
		(min_thickness 0.25)
		(keepout
			(tracks not_allowed)
			(vias allowed)
			(pads allowed)
			(copperpour not_allowed)
			(footprints allowed)
		)
		(placement
			(enabled no)
			(sheetname "")
		)
		(fill yes
			(thermal_gap 0.5)
			(thermal_bridge_width 0.5)
			(island_removal_mode 0)
		)
		(polygon
			(pts
				(arc
					(start 381.99187 -217.064336)
					(mid 381.33909 -217.064336)
					(end 381.99187 -217.064336)
				)
			)
		)
	)
	(zone
		(layers "B.Cu" "In6.Cu" "In11.Cu" "In13.Cu" "In15.Cu")
		(hatch none 0.5)
		(connect_pads
			(clearance 0)
		)
		(min_thickness 0.25)
		(keepout
			(tracks not_allowed)
			(vias allowed)
			(pads allowed)
			(copperpour not_allowed)
			(footprints allowed)
		)
		(placement
			(enabled no)
			(sheetname "")
		)
		(fill yes
			(thermal_gap 0.5)
			(thermal_bridge_width 0.5)
			(island_removal_mode 0)
		)
		(polygon
			(pts
				(arc
					(start 36.303204 -251.716794)
					(mid 35.650424 -251.716794)
					(end 36.303204 -251.716794)
				)
			)
		)
	)
	(zone
		(layers "B.Cu" "In6.Cu" "In11.Cu" "In13.Cu" "In15.Cu")
		(hatch none 0.5)
		(connect_pads
			(clearance 0)
		)
		(min_thickness 0.25)
		(keepout
			(tracks not_allowed)
			(vias allowed)
			(pads allowed)
			(copperpour not_allowed)
			(footprints allowed)
		)
		(placement
			(enabled no)
			(sheetname "")
		)
		(fill yes
			(thermal_gap 0.5)
			(thermal_bridge_width 0.5)
			(island_removal_mode 0)
		)
		(polygon
			(pts
				(arc
					(start 342.050624 -239.0394)
					(mid 341.397844 -239.0394)
					(end 342.050624 -239.0394)
				)
			)
		)
	)
	(zone
		(layers "B.Cu" "In6.Cu" "In11.Cu" "In13.Cu" "In15.Cu")
		(hatch none 0.5)
		(connect_pads
			(clearance 0)
		)
		(min_thickness 0.25)
		(keepout
			(tracks not_allowed)
			(vias allowed)
			(pads allowed)
			(copperpour not_allowed)
			(footprints allowed)
		)
		(placement
			(enabled no)
			(sheetname "")
		)
		(fill yes
			(thermal_gap 0.5)
			(thermal_bridge_width 0.5)
			(island_removal_mode 0)
		)
		(polygon
			(pts
				(arc
					(start 280.143204 -297.616626)
					(mid 279.490424 -297.616626)
					(end 280.143204 -297.616626)
				)
			)
		)
	)
	(zone
		(layers "B.Cu" "In6.Cu" "In11.Cu" "In13.Cu" "In15.Cu")
		(hatch none 0.5)
		(connect_pads
			(clearance 0)
		)
		(min_thickness 0.25)
		(keepout
			(tracks not_allowed)
			(vias allowed)
			(pads allowed)
			(copperpour not_allowed)
			(footprints allowed)
		)
		(placement
			(enabled no)
			(sheetname "")
		)
		(fill yes
			(thermal_gap 0.5)
			(thermal_bridge_width 0.5)
			(island_removal_mode 0)
		)
		(polygon
			(pts
				(arc
					(start 47.290736 -302.716692)
					(mid 46.637956 -302.716692)
					(end 47.290736 -302.716692)
				)
			)
		)
	)
	(zone
		(layers "B.Cu" "In6.Cu" "In11.Cu" "In13.Cu" "In15.Cu")
		(hatch none 0.5)
		(connect_pads
			(clearance 0)
		)
		(min_thickness 0.25)
		(keepout
			(tracks not_allowed)
			(vias allowed)
			(pads allowed)
			(copperpour not_allowed)
			(footprints allowed)
		)
		(placement
			(enabled no)
			(sheetname "")
		)
		(fill yes
			(thermal_gap 0.5)
			(thermal_bridge_width 0.5)
			(island_removal_mode 0)
		)
		(polygon
			(pts
				(arc
					(start 378.342652 -275.8948)
					(mid 377.689872 -275.8948)
					(end 378.342652 -275.8948)
				)
			)
		)
	)
	(zone
		(layers "B.Cu" "In6.Cu" "In11.Cu" "In13.Cu" "In15.Cu")
		(hatch none 0.5)
		(connect_pads
			(clearance 0)
		)
		(min_thickness 0.25)
		(keepout
			(tracks not_allowed)
			(vias allowed)
			(pads allowed)
			(copperpour not_allowed)
			(footprints allowed)
		)
		(placement
			(enabled no)
			(sheetname "")
		)
		(fill yes
			(thermal_gap 0.5)
			(thermal_bridge_width 0.5)
			(island_removal_mode 0)
		)
		(polygon
			(pts
				(arc
					(start 436.150004 -207.51673)
					(mid 435.497224 -207.51673)
					(end 436.150004 -207.51673)
				)
			)
		)
	)
	(zone
		(layers "B.Cu" "In6.Cu" "In11.Cu" "In13.Cu" "In15.Cu")
		(hatch none 0.5)
		(connect_pads
			(clearance 0)
		)
		(min_thickness 0.25)
		(keepout
			(tracks not_allowed)
			(vias allowed)
			(pads allowed)
			(copperpour not_allowed)
			(footprints allowed)
		)
		(placement
			(enabled no)
			(sheetname "")
		)
		(fill yes
			(thermal_gap 0.5)
			(thermal_bridge_width 0.5)
			(island_removal_mode 0)
		)
		(polygon
			(pts
				(arc
					(start 299.330872 -195.616576)
					(mid 298.678092 -195.616576)
					(end 299.330872 -195.616576)
				)
			)
		)
	)
	(zone
		(layers "B.Cu" "In6.Cu" "In11.Cu" "In13.Cu" "In15.Cu")
		(hatch none 0.5)
		(connect_pads
			(clearance 0)
		)
		(min_thickness 0.25)
		(keepout
			(tracks not_allowed)
			(vias allowed)
			(pads allowed)
			(copperpour not_allowed)
			(footprints allowed)
		)
		(placement
			(enabled no)
			(sheetname "")
		)
		(fill yes
			(thermal_gap 0.5)
			(thermal_bridge_width 0.5)
			(island_removal_mode 0)
		)
		(polygon
			(pts
				(arc
					(start 340.281006 -266.941808)
					(mid 339.628226 -266.941808)
					(end 340.281006 -266.941808)
				)
			)
		)
	)
	(zone
		(layers "B.Cu" "In6.Cu" "In11.Cu" "In13.Cu" "In15.Cu")
		(hatch none 0.5)
		(connect_pads
			(clearance 0)
		)
		(min_thickness 0.25)
		(keepout
			(tracks not_allowed)
			(vias allowed)
			(pads allowed)
			(copperpour not_allowed)
			(footprints allowed)
		)
		(placement
			(enabled no)
			(sheetname "")
		)
		(fill yes
			(thermal_gap 0.5)
			(thermal_bridge_width 0.5)
			(island_removal_mode 0)
		)
		(polygon
			(pts
				(arc
					(start 173.122336 -284.866588)
					(mid 172.469556 -284.866588)
					(end 173.122336 -284.866588)
				)
			)
		)
	)
	(zone
		(layers "B.Cu" "In6.Cu" "In11.Cu" "In13.Cu" "In15.Cu")
		(hatch none 0.5)
		(connect_pads
			(clearance 0)
		)
		(min_thickness 0.25)
		(keepout
			(tracks not_allowed)
			(vias allowed)
			(pads allowed)
			(copperpour not_allowed)
			(footprints allowed)
		)
		(placement
			(enabled no)
			(sheetname "")
		)
		(fill yes
			(thermal_gap 0.5)
			(thermal_bridge_width 0.5)
			(island_removal_mode 0)
		)
		(polygon
			(pts
				(arc
					(start 354.73767 -218.692222)
					(mid 354.08489 -218.692222)
					(end 354.73767 -218.692222)
				)
			)
		)
	)
	(zone
		(layers "B.Cu" "In6.Cu" "In11.Cu" "In13.Cu" "In15.Cu")
		(hatch none 0.5)
		(connect_pads
			(clearance 0)
		)
		(min_thickness 0.25)
		(keepout
			(tracks not_allowed)
			(vias allowed)
			(pads allowed)
			(copperpour not_allowed)
			(footprints allowed)
		)
		(placement
			(enabled no)
			(sheetname "")
		)
		(fill yes
			(thermal_gap 0.5)
			(thermal_bridge_width 0.5)
			(island_removal_mode 0)
		)
		(polygon
			(pts
				(arc
					(start 364.13567 -218.692222)
					(mid 363.48289 -218.692222)
					(end 364.13567 -218.692222)
				)
			)
		)
	)
	(zone
		(layers "B.Cu" "In6.Cu" "In11.Cu" "In13.Cu" "In15.Cu")
		(hatch none 0.5)
		(connect_pads
			(clearance 0)
		)
		(min_thickness 0.25)
		(keepout
			(tracks not_allowed)
			(vias allowed)
			(pads allowed)
			(copperpour not_allowed)
			(footprints allowed)
		)
		(placement
			(enabled no)
			(sheetname "")
		)
		(fill yes
			(thermal_gap 0.5)
			(thermal_bridge_width 0.5)
			(island_removal_mode 0)
		)
		(polygon
			(pts
				(arc
					(start 358.497124 -218.692222)
					(mid 357.844344 -218.692222)
					(end 358.497124 -218.692222)
				)
			)
		)
	)
	(zone
		(layers "B.Cu" "In6.Cu" "In11.Cu" "In13.Cu" "In15.Cu")
		(hatch none 0.5)
		(connect_pads
			(clearance 0)
		)
		(min_thickness 0.25)
		(keepout
			(tracks not_allowed)
			(vias allowed)
			(pads allowed)
			(copperpour not_allowed)
			(footprints allowed)
		)
		(placement
			(enabled no)
			(sheetname "")
		)
		(fill yes
			(thermal_gap 0.5)
			(thermal_bridge_width 0.5)
			(island_removal_mode 0)
		)
		(polygon
			(pts
				(arc
					(start 436.150004 -289.966654)
					(mid 435.497224 -289.966654)
					(end 436.150004 -289.966654)
				)
			)
		)
	)
	(zone
		(layers "B.Cu" "In6.Cu" "In11.Cu" "In13.Cu" "In15.Cu")
		(hatch none 0.5)
		(connect_pads
			(clearance 0)
		)
		(min_thickness 0.25)
		(keepout
			(tracks not_allowed)
			(vias allowed)
			(pads allowed)
			(copperpour not_allowed)
			(footprints allowed)
		)
		(placement
			(enabled no)
			(sheetname "")
		)
		(fill yes
			(thermal_gap 0.5)
			(thermal_bridge_width 0.5)
			(island_removal_mode 0)
		)
		(polygon
			(pts
				(arc
					(start 188.209936 -289.966654)
					(mid 187.557156 -289.966654)
					(end 188.209936 -289.966654)
				)
			)
		)
	)
	(zone
		(layers "B.Cu" "In6.Cu" "In11.Cu" "In13.Cu" "In15.Cu")
		(hatch none 0.5)
		(connect_pads
			(clearance 0)
		)
		(min_thickness 0.25)
		(keepout
			(tracks not_allowed)
			(vias allowed)
			(pads allowed)
			(copperpour not_allowed)
			(footprints allowed)
		)
		(placement
			(enabled no)
			(sheetname "")
		)
		(fill yes
			(thermal_gap 0.5)
			(thermal_bridge_width 0.5)
			(island_removal_mode 0)
		)
		(polygon
			(pts
				(arc
					(start 299.356272 -283.16682)
					(mid 298.703492 -283.16682)
					(end 299.356272 -283.16682)
				)
			)
		)
	)
	(zone
		(layers "B.Cu" "In6.Cu" "In11.Cu" "In13.Cu" "In15.Cu")
		(hatch none 0.5)
		(connect_pads
			(clearance 0)
		)
		(min_thickness 0.25)
		(keepout
			(tracks not_allowed)
			(vias allowed)
			(pads allowed)
			(copperpour not_allowed)
			(footprints allowed)
		)
		(placement
			(enabled no)
			(sheetname "")
		)
		(fill yes
			(thermal_gap 0.5)
			(thermal_bridge_width 0.5)
			(island_removal_mode 0)
		)
		(polygon
			(pts
				(arc
					(start 436.150004 -209.216752)
					(mid 435.497224 -209.216752)
					(end 436.150004 -209.216752)
				)
			)
		)
	)
	(zone
		(layers "B.Cu" "In6.Cu" "In11.Cu" "In13.Cu" "In15.Cu")
		(hatch none 0.5)
		(connect_pads
			(clearance 0)
		)
		(min_thickness 0.25)
		(keepout
			(tracks not_allowed)
			(vias allowed)
			(pads allowed)
			(copperpour not_allowed)
			(footprints allowed)
		)
		(placement
			(enabled no)
			(sheetname "")
		)
		(fill yes
			(thermal_gap 0.5)
			(thermal_bridge_width 0.5)
			(island_removal_mode 0)
		)
		(polygon
			(pts
				(arc
					(start 94.690184 -254.733552)
					(mid 94.037404 -254.733552)
					(end 94.690184 -254.733552)
				)
			)
		)
	)
	(zone
		(layers "B.Cu" "In6.Cu" "In11.Cu" "In13.Cu" "In15.Cu")
		(hatch none 0.5)
		(connect_pads
			(clearance 0)
		)
		(min_thickness 0.25)
		(keepout
			(tracks not_allowed)
			(vias allowed)
			(pads allowed)
			(copperpour not_allowed)
			(footprints allowed)
		)
		(placement
			(enabled no)
			(sheetname "")
		)
		(fill yes
			(thermal_gap 0.5)
			(thermal_bridge_width 0.5)
			(island_removal_mode 0)
		)
		(polygon
			(pts
				(arc
					(start 339.810852 -267.755878)
					(mid 339.158072 -267.755878)
					(end 339.810852 -267.755878)
				)
			)
		)
	)
	(zone
		(layers "B.Cu" "In6.Cu" "In11.Cu" "In13.Cu" "In15.Cu")
		(hatch none 0.5)
		(connect_pads
			(clearance 0)
		)
		(min_thickness 0.25)
		(keepout
			(tracks not_allowed)
			(vias allowed)
			(pads allowed)
			(copperpour not_allowed)
			(footprints allowed)
		)
		(placement
			(enabled no)
			(sheetname "")
		)
		(fill yes
			(thermal_gap 0.5)
			(thermal_bridge_width 0.5)
			(island_removal_mode 0)
		)
		(polygon
			(pts
				(arc
					(start 32.203136 -209.216752)
					(mid 31.550356 -209.216752)
					(end 32.203136 -209.216752)
				)
			)
		)
	)
	(zone
		(layers "B.Cu" "In6.Cu" "In11.Cu" "In13.Cu" "In15.Cu")
		(hatch none 0.5)
		(connect_pads
			(clearance 0)
		)
		(min_thickness 0.25)
		(keepout
			(tracks not_allowed)
			(vias allowed)
			(pads allowed)
			(copperpour not_allowed)
			(footprints allowed)
		)
		(placement
			(enabled no)
			(sheetname "")
		)
		(fill yes
			(thermal_gap 0.5)
			(thermal_bridge_width 0.5)
			(island_removal_mode 0)
		)
		(polygon
			(pts
				(arc
					(start 103.978202 -217.064336)
					(mid 103.325422 -217.064336)
					(end 103.978202 -217.064336)
				)
			)
		)
	)
	(zone
		(layers "B.Cu" "In6.Cu" "In11.Cu" "In13.Cu" "In15.Cu")
		(hatch none 0.5)
		(connect_pads
			(clearance 0)
		)
		(min_thickness 0.25)
		(keepout
			(tracks not_allowed)
			(vias allowed)
			(pads allowed)
			(copperpour not_allowed)
			(footprints allowed)
		)
		(placement
			(enabled no)
			(sheetname "")
		)
		(fill yes
			(thermal_gap 0.5)
			(thermal_bridge_width 0.5)
			(island_removal_mode 0)
		)
		(polygon
			(pts
				(arc
					(start 131.812284 -289.807142)
					(mid 131.159504 -289.807142)
					(end 131.812284 -289.807142)
				)
			)
		)
	)
	(zone
		(layers "B.Cu" "In6.Cu" "In11.Cu" "In13.Cu" "In15.Cu")
		(hatch none 0.5)
		(connect_pads
			(clearance 0)
		)
		(min_thickness 0.25)
		(keepout
			(tracks not_allowed)
			(vias allowed)
			(pads allowed)
			(copperpour not_allowed)
			(footprints allowed)
		)
		(placement
			(enabled no)
			(sheetname "")
		)
		(fill yes
			(thermal_gap 0.5)
			(thermal_bridge_width 0.5)
			(island_removal_mode 0)
		)
		(polygon
			(pts
				(arc
					(start 130.762756 -229.272846)
					(mid 130.109976 -229.272846)
					(end 130.762756 -229.272846)
				)
			)
		)
	)
	(zone
		(layers "B.Cu" "In6.Cu" "In11.Cu" "In13.Cu" "In15.Cu")
		(hatch none 0.5)
		(connect_pads
			(clearance 0)
		)
		(min_thickness 0.25)
		(keepout
			(tracks not_allowed)
			(vias allowed)
			(pads allowed)
			(copperpour not_allowed)
			(footprints allowed)
		)
		(placement
			(enabled no)
			(sheetname "")
		)
		(fill yes
			(thermal_gap 0.5)
			(thermal_bridge_width 0.5)
			(island_removal_mode 0)
		)
		(polygon
			(pts
				(arc
					(start 132.752338 -265.314176)
					(mid 132.099558 -265.314176)
					(end 132.752338 -265.314176)
				)
			)
		)
	)
	(zone
		(layers "B.Cu" "In6.Cu" "In11.Cu" "In13.Cu" "In15.Cu")
		(hatch none 0.5)
		(connect_pads
			(clearance 0)
		)
		(min_thickness 0.25)
		(keepout
			(tracks not_allowed)
			(vias allowed)
			(pads allowed)
			(copperpour not_allowed)
			(footprints allowed)
		)
		(placement
			(enabled no)
			(sheetname "")
		)
		(fill yes
			(thermal_gap 0.5)
			(thermal_bridge_width 0.5)
			(island_removal_mode 0)
		)
		(polygon
			(pts
				(arc
					(start 280.143204 -289.966654)
					(mid 279.490424 -289.966654)
					(end 280.143204 -289.966654)
				)
			)
		)
	)
	(zone
		(layers "B.Cu" "In6.Cu" "In11.Cu" "In13.Cu" "In15.Cu")
		(hatch none 0.5)
		(connect_pads
			(clearance 0)
		)
		(min_thickness 0.25)
		(keepout
			(tracks not_allowed)
			(vias allowed)
			(pads allowed)
			(copperpour not_allowed)
			(footprints allowed)
		)
		(placement
			(enabled no)
			(sheetname "")
		)
		(fill yes
			(thermal_gap 0.5)
			(thermal_bridge_width 0.5)
			(island_removal_mode 0)
		)
		(polygon
			(pts
				(arc
					(start 188.209936 -312.91657)
					(mid 187.557156 -312.91657)
					(end 188.209936 -312.91657)
				)
			)
		)
	)
	(zone
		(layers "B.Cu" "In6.Cu" "In11.Cu" "In13.Cu" "In15.Cu")
		(hatch none 0.5)
		(connect_pads
			(clearance 0)
		)
		(min_thickness 0.25)
		(keepout
			(tracks not_allowed)
			(vias allowed)
			(pads allowed)
			(copperpour not_allowed)
			(footprints allowed)
		)
		(placement
			(enabled no)
			(sheetname "")
		)
		(fill yes
			(thermal_gap 0.5)
			(thermal_bridge_width 0.5)
			(island_removal_mode 0)
		)
		(polygon
			(pts
				(arc
					(start 199.853804 -267.016738)
					(mid 199.201024 -267.016738)
					(end 199.853804 -267.016738)
				)
			)
		)
	)
	(zone
		(layers "B.Cu" "In6.Cu" "In11.Cu" "In13.Cu" "In15.Cu")
		(hatch none 0.5)
		(connect_pads
			(clearance 0)
		)
		(min_thickness 0.25)
		(keepout
			(tracks not_allowed)
			(vias allowed)
			(pads allowed)
			(copperpour not_allowed)
			(footprints allowed)
		)
		(placement
			(enabled no)
			(sheetname "")
		)
		(fill yes
			(thermal_gap 0.5)
			(thermal_bridge_width 0.5)
			(island_removal_mode 0)
		)
		(polygon
			(pts
				(arc
					(start 370.71427 -217.064336)
					(mid 370.06149 -217.064336)
					(end 370.71427 -217.064336)
				)
			)
		)
	)
	(zone
		(layers "B.Cu" "In6.Cu" "In11.Cu" "In13.Cu" "In15.Cu")
		(hatch none 0.5)
		(connect_pads
			(clearance 0)
		)
		(min_thickness 0.25)
		(keepout
			(tracks not_allowed)
			(vias allowed)
			(pads allowed)
			(copperpour not_allowed)
			(footprints allowed)
		)
		(placement
			(enabled no)
			(sheetname "")
		)
		(fill yes
			(thermal_gap 0.5)
			(thermal_bridge_width 0.5)
			(island_removal_mode 0)
		)
		(polygon
			(pts
				(arc
					(start 284.243272 -295.06672)
					(mid 283.590492 -295.06672)
					(end 284.243272 -295.06672)
				)
			)
		)
	)
	(zone
		(layers "B.Cu" "In6.Cu" "In11.Cu" "In13.Cu" "In15.Cu")
		(hatch none 0.5)
		(connect_pads
			(clearance 0)
		)
		(min_thickness 0.25)
		(keepout
			(tracks not_allowed)
			(vias allowed)
			(pads allowed)
			(copperpour not_allowed)
			(footprints allowed)
		)
		(placement
			(enabled no)
			(sheetname "")
		)
		(fill yes
			(thermal_gap 0.5)
			(thermal_bridge_width 0.5)
			(island_removal_mode 0)
		)
		(polygon
			(pts
				(arc
					(start 94.220538 -271.825212)
					(mid 93.567758 -271.825212)
					(end 94.220538 -271.825212)
				)
			)
		)
	)
	(zone
		(layers "B.Cu" "In6.Cu" "In11.Cu" "In13.Cu" "In15.Cu")
		(hatch none 0.5)
		(connect_pads
			(clearance 0)
		)
		(min_thickness 0.25)
		(keepout
			(tracks not_allowed)
			(vias allowed)
			(pads allowed)
			(copperpour not_allowed)
			(footprints allowed)
		)
		(placement
			(enabled no)
			(sheetname "")
		)
		(fill yes
			(thermal_gap 0.5)
			(thermal_bridge_width 0.5)
			(island_removal_mode 0)
		)
		(polygon
			(pts
				(arc
					(start 102.678738 -288.103056)
					(mid 102.025958 -288.103056)
					(end 102.678738 -288.103056)
				)
			)
		)
	)
	(zone
		(layers "B.Cu" "In6.Cu" "In11.Cu" "In13.Cu" "In15.Cu")
		(hatch none 0.5)
		(connect_pads
			(clearance 0)
		)
		(min_thickness 0.25)
		(keepout
			(tracks not_allowed)
			(vias allowed)
			(pads allowed)
			(copperpour not_allowed)
			(footprints allowed)
		)
		(placement
			(enabled no)
			(sheetname "")
		)
		(fill yes
			(thermal_gap 0.5)
			(thermal_bridge_width 0.5)
			(island_removal_mode 0)
		)
		(polygon
			(pts
				(arc
					(start 51.390804 -197.316598)
					(mid 50.738024 -197.316598)
					(end 51.390804 -197.316598)
				)
			)
		)
	)
	(zone
		(layers "B.Cu" "In6.Cu" "In11.Cu" "In13.Cu" "In15.Cu")
		(hatch none 0.5)
		(connect_pads
			(clearance 0)
		)
		(min_thickness 0.25)
		(keepout
			(tracks not_allowed)
			(vias allowed)
			(pads allowed)
			(copperpour not_allowed)
			(footprints allowed)
		)
		(placement
			(enabled no)
			(sheetname "")
		)
		(fill yes
			(thermal_gap 0.5)
			(thermal_bridge_width 0.5)
			(island_removal_mode 0)
		)
		(polygon
			(pts
				(arc
					(start 284.243272 -296.766742)
					(mid 283.590492 -296.766742)
					(end 284.243272 -296.766742)
				)
			)
		)
	)
	(zone
		(layers "B.Cu" "In6.Cu" "In11.Cu" "In13.Cu" "In15.Cu")
		(hatch none 0.5)
		(connect_pads
			(clearance 0)
		)
		(min_thickness 0.25)
		(keepout
			(tracks not_allowed)
			(vias allowed)
			(pads allowed)
			(copperpour not_allowed)
			(footprints allowed)
		)
		(placement
			(enabled no)
			(sheetname "")
		)
		(fill yes
			(thermal_gap 0.5)
			(thermal_bridge_width 0.5)
			(island_removal_mode 0)
		)
		(polygon
			(pts
				(arc
					(start 380.692406 -260.430772)
					(mid 380.039626 -260.430772)
					(end 380.692406 -260.430772)
				)
			)
		)
	)
	(zone
		(layers "B.Cu" "In6.Cu" "In11.Cu" "In13.Cu" "In15.Cu")
		(hatch none 0.5)
		(connect_pads
			(clearance 0)
		)
		(min_thickness 0.25)
		(keepout
			(tracks not_allowed)
			(vias allowed)
			(pads allowed)
			(copperpour not_allowed)
			(footprints allowed)
		)
		(placement
			(enabled no)
			(sheetname "")
		)
		(fill yes
			(thermal_gap 0.5)
			(thermal_bridge_width 0.5)
			(island_removal_mode 0)
		)
		(polygon
			(pts
				(arc
					(start 32.203136 -295.916604)
					(mid 31.550356 -295.916604)
					(end 32.203136 -295.916604)
				)
			)
		)
	)
	(zone
		(layers "B.Cu" "In6.Cu" "In11.Cu" "In13.Cu" "In15.Cu")
		(hatch none 0.5)
		(connect_pads
			(clearance 0)
		)
		(min_thickness 0.25)
		(keepout
			(tracks not_allowed)
			(vias allowed)
			(pads allowed)
			(copperpour not_allowed)
			(footprints allowed)
		)
		(placement
			(enabled no)
			(sheetname "")
		)
		(fill yes
			(thermal_gap 0.5)
			(thermal_bridge_width 0.5)
			(island_removal_mode 0)
		)
		(polygon
			(pts
				(arc
					(start 192.310004 -204.96657)
					(mid 191.657224 -204.96657)
					(end 192.310004 -204.96657)
				)
			)
		)
	)
	(zone
		(layers "B.Cu" "In6.Cu" "In11.Cu" "In13.Cu" "In15.Cu")
		(hatch none 0.5)
		(connect_pads
			(clearance 0)
		)
		(min_thickness 0.25)
		(keepout
			(tracks not_allowed)
			(vias allowed)
			(pads allowed)
			(copperpour not_allowed)
			(footprints allowed)
		)
		(placement
			(enabled no)
			(sheetname "")
		)
		(fill yes
			(thermal_gap 0.5)
			(thermal_bridge_width 0.5)
			(island_removal_mode 0)
		)
		(polygon
			(pts
				(arc
					(start 92.230956 -240.667286)
					(mid 91.578176 -240.667286)
					(end 92.230956 -240.667286)
				)
			)
		)
	)
	(zone
		(layers "B.Cu" "In6.Cu" "In11.Cu" "In13.Cu" "In15.Cu")
		(hatch none 0.5)
		(connect_pads
			(clearance 0)
		)
		(min_thickness 0.25)
		(keepout
			(tracks not_allowed)
			(vias allowed)
			(pads allowed)
			(copperpour not_allowed)
			(footprints allowed)
		)
		(placement
			(enabled no)
			(sheetname "")
		)
		(fill yes
			(thermal_gap 0.5)
			(thermal_bridge_width 0.5)
			(island_removal_mode 0)
		)
		(polygon
			(pts
				(arc
					(start 177.222404 -201.56678)
					(mid 176.569624 -201.56678)
					(end 177.222404 -201.56678)
				)
			)
		)
	)
	(zone
		(layers "B.Cu" "In6.Cu" "In11.Cu" "In13.Cu" "In15.Cu")
		(hatch none 0.5)
		(connect_pads
			(clearance 0)
		)
		(min_thickness 0.25)
		(keepout
			(tracks not_allowed)
			(vias allowed)
			(pads allowed)
			(copperpour not_allowed)
			(footprints allowed)
		)
		(placement
			(enabled no)
			(sheetname "")
		)
		(fill yes
			(thermal_gap 0.5)
			(thermal_bridge_width 0.5)
			(island_removal_mode 0)
		)
		(polygon
			(pts
				(arc
					(start 103.148638 -288.917126)
					(mid 102.495858 -288.917126)
					(end 103.148638 -288.917126)
				)
			)
		)
	)
	(zone
		(layers "B.Cu" "In6.Cu" "In11.Cu" "In13.Cu" "In15.Cu")
		(hatch none 0.5)
		(connect_pads
			(clearance 0)
		)
		(min_thickness 0.25)
		(keepout
			(tracks not_allowed)
			(vias allowed)
			(pads allowed)
			(copperpour not_allowed)
			(footprints allowed)
		)
		(placement
			(enabled no)
			(sheetname "")
		)
		(fill yes
			(thermal_gap 0.5)
			(thermal_bridge_width 0.5)
			(island_removal_mode 0)
		)
		(polygon
			(pts
				(arc
					(start 108.207556 -217.878406)
					(mid 107.554776 -217.878406)
					(end 108.207556 -217.878406)
				)
			)
		)
	)
	(zone
		(layers "B.Cu" "In6.Cu" "In11.Cu" "In13.Cu" "In15.Cu")
		(hatch none 0.5)
		(connect_pads
			(clearance 0)
		)
		(min_thickness 0.25)
		(keepout
			(tracks not_allowed)
			(vias allowed)
			(pads allowed)
			(copperpour not_allowed)
			(footprints allowed)
		)
		(placement
			(enabled no)
			(sheetname "")
		)
		(fill yes
			(thermal_gap 0.5)
			(thermal_bridge_width 0.5)
			(island_removal_mode 0)
		)
		(polygon
			(pts
				(arc
					(start 130.872738 -266.941808)
					(mid 130.219958 -266.941808)
					(end 130.872738 -266.941808)
				)
			)
		)
	)
	(zone
		(layers "B.Cu" "In6.Cu" "In11.Cu" "In13.Cu" "In15.Cu")
		(hatch none 0.5)
		(connect_pads
			(clearance 0)
		)
		(min_thickness 0.25)
		(keepout
			(tracks not_allowed)
			(vias allowed)
			(pads allowed)
			(copperpour not_allowed)
			(footprints allowed)
		)
		(placement
			(enabled no)
			(sheetname "")
		)
		(fill yes
			(thermal_gap 0.5)
			(thermal_bridge_width 0.5)
			(island_removal_mode 0)
		)
		(polygon
			(pts
				(arc
					(start 173.122336 -232.166668)
					(mid 172.469556 -232.166668)
					(end 173.122336 -232.166668)
				)
			)
		)
	)
	(zone
		(layers "B.Cu" "In6.Cu" "In11.Cu" "In13.Cu" "In15.Cu")
		(hatch none 0.5)
		(connect_pads
			(clearance 0)
		)
		(min_thickness 0.25)
		(keepout
			(tracks not_allowed)
			(vias allowed)
			(pads allowed)
			(copperpour not_allowed)
			(footprints allowed)
		)
		(placement
			(enabled no)
			(sheetname "")
		)
		(fill yes
			(thermal_gap 0.5)
			(thermal_bridge_width 0.5)
			(island_removal_mode 0)
		)
		(polygon
			(pts
				(arc
					(start 99.749356 -217.878406)
					(mid 99.096576 -217.878406)
					(end 99.749356 -217.878406)
				)
			)
		)
	)
	(zone
		(layers "B.Cu" "In6.Cu" "In11.Cu" "In13.Cu" "In15.Cu")
		(hatch none 0.5)
		(connect_pads
			(clearance 0)
		)
		(min_thickness 0.25)
		(keepout
			(tracks not_allowed)
			(vias allowed)
			(pads allowed)
			(copperpour not_allowed)
			(footprints allowed)
		)
		(placement
			(enabled no)
			(sheetname "")
		)
		(fill yes
			(thermal_gap 0.5)
			(thermal_bridge_width 0.5)
			(island_removal_mode 0)
		)
		(polygon
			(pts
				(arc
					(start 440.250072 -248.31675)
					(mid 439.597292 -248.31675)
					(end 440.250072 -248.31675)
				)
			)
		)
	)
	(zone
		(layers "B.Cu" "In6.Cu" "In11.Cu" "In13.Cu" "In15.Cu")
		(hatch none 0.5)
		(connect_pads
			(clearance 0)
		)
		(min_thickness 0.25)
		(keepout
			(tracks not_allowed)
			(vias allowed)
			(pads allowed)
			(copperpour not_allowed)
			(footprints allowed)
		)
		(placement
			(enabled no)
			(sheetname "")
		)
		(fill yes
			(thermal_gap 0.5)
			(thermal_bridge_width 0.5)
			(island_removal_mode 0)
		)
		(polygon
			(pts
				(arc
					(start 340.750652 -269.38351)
					(mid 340.097872 -269.38351)
					(end 340.750652 -269.38351)
				)
			)
		)
	)
	(zone
		(layers "B.Cu" "In6.Cu" "In11.Cu" "In13.Cu" "In15.Cu")
		(hatch none 0.5)
		(connect_pads
			(clearance 0)
		)
		(min_thickness 0.25)
		(keepout
			(tracks not_allowed)
			(vias allowed)
			(pads allowed)
			(copperpour not_allowed)
			(footprints allowed)
		)
		(placement
			(enabled no)
			(sheetname "")
		)
		(fill yes
			(thermal_gap 0.5)
			(thermal_bridge_width 0.5)
			(island_removal_mode 0)
		)
		(polygon
			(pts
				(arc
					(start 92.230956 -234.15625)
					(mid 91.578176 -234.15625)
					(end 92.230956 -234.15625)
				)
			)
		)
	)
	(zone
		(layers "B.Cu" "In6.Cu" "In11.Cu" "In13.Cu" "In15.Cu")
		(hatch none 0.5)
		(connect_pads
			(clearance 0)
		)
		(min_thickness 0.25)
		(keepout
			(tracks not_allowed)
			(vias allowed)
			(pads allowed)
			(copperpour not_allowed)
			(footprints allowed)
		)
		(placement
			(enabled no)
			(sheetname "")
		)
		(fill yes
			(thermal_gap 0.5)
			(thermal_bridge_width 0.5)
			(island_removal_mode 0)
		)
		(polygon
			(pts
				(arc
					(start 284.243272 -209.216752)
					(mid 283.590492 -209.216752)
					(end 284.243272 -209.216752)
				)
			)
		)
	)
	(zone
		(layers "B.Cu" "In6.Cu" "In11.Cu" "In13.Cu" "In15.Cu")
		(hatch none 0.5)
		(connect_pads
			(clearance 0)
		)
		(min_thickness 0.25)
		(keepout
			(tracks not_allowed)
			(vias allowed)
			(pads allowed)
			(copperpour not_allowed)
			(footprints allowed)
		)
		(placement
			(enabled no)
			(sheetname "")
		)
		(fill yes
			(thermal_gap 0.5)
			(thermal_bridge_width 0.5)
			(island_removal_mode 0)
		)
		(polygon
			(pts
				(arc
					(start 130.292602 -231.714548)
					(mid 129.639822 -231.714548)
					(end 130.292602 -231.714548)
				)
			)
		)
	)
	(zone
		(layers "B.Cu" "In6.Cu" "In11.Cu" "In13.Cu" "In15.Cu")
		(hatch none 0.5)
		(connect_pads
			(clearance 0)
		)
		(min_thickness 0.25)
		(keepout
			(tracks not_allowed)
			(vias allowed)
			(pads allowed)
			(copperpour not_allowed)
			(footprints allowed)
		)
		(placement
			(enabled no)
			(sheetname "")
		)
		(fill yes
			(thermal_gap 0.5)
			(thermal_bridge_width 0.5)
			(island_removal_mode 0)
		)
		(polygon
			(pts
				(arc
					(start 36.303204 -292.516814)
					(mid 35.650424 -292.516814)
					(end 36.303204 -292.516814)
				)
			)
		)
	)
	(zone
		(layers "B.Cu" "In6.Cu" "In11.Cu" "In13.Cu" "In15.Cu")
		(hatch none 0.5)
		(connect_pads
			(clearance 0)
		)
		(min_thickness 0.25)
		(keepout
			(tracks not_allowed)
			(vias allowed)
			(pads allowed)
			(copperpour not_allowed)
			(footprints allowed)
		)
		(placement
			(enabled no)
			(sheetname "")
		)
		(fill yes
			(thermal_gap 0.5)
			(thermal_bridge_width 0.5)
			(island_removal_mode 0)
		)
		(polygon
			(pts
				(arc
					(start 92.700602 -239.853216)
					(mid 92.047822 -239.853216)
					(end 92.700602 -239.853216)
				)
			)
		)
	)
	(zone
		(layers "B.Cu" "In6.Cu" "In11.Cu" "In13.Cu" "In15.Cu")
		(hatch none 0.5)
		(connect_pads
			(clearance 0)
		)
		(min_thickness 0.25)
		(keepout
			(tracks not_allowed)
			(vias allowed)
			(pads allowed)
			(copperpour not_allowed)
			(footprints allowed)
		)
		(placement
			(enabled no)
			(sheetname "")
		)
		(fill yes
			(thermal_gap 0.5)
			(thermal_bridge_width 0.5)
			(island_removal_mode 0)
		)
		(polygon
			(pts
				(arc
					(start 131.812538 -265.314176)
					(mid 131.159758 -265.314176)
					(end 131.812538 -265.314176)
				)
			)
		)
	)
	(zone
		(layers "B.Cu" "In6.Cu" "In11.Cu" "In13.Cu" "In15.Cu")
		(hatch none 0.5)
		(connect_pads
			(clearance 0)
		)
		(min_thickness 0.25)
		(keepout
			(tracks not_allowed)
			(vias allowed)
			(pads allowed)
			(copperpour not_allowed)
			(footprints allowed)
		)
		(placement
			(enabled no)
			(sheetname "")
		)
		(fill yes
			(thermal_gap 0.5)
			(thermal_bridge_width 0.5)
			(island_removal_mode 0)
		)
		(polygon
			(pts
				(arc
					(start 130.762756 -235.783882)
					(mid 130.109976 -235.783882)
					(end 130.762756 -235.783882)
				)
			)
		)
	)
	(zone
		(layers "B.Cu" "In6.Cu" "In11.Cu" "In13.Cu" "In15.Cu")
		(hatch none 0.5)
		(connect_pads
			(clearance 0)
		)
		(min_thickness 0.25)
		(keepout
			(tracks not_allowed)
			(vias allowed)
			(pads allowed)
			(copperpour not_allowed)
			(footprints allowed)
		)
		(placement
			(enabled no)
			(sheetname "")
		)
		(fill yes
			(thermal_gap 0.5)
			(thermal_bridge_width 0.5)
			(island_removal_mode 0)
		)
		(polygon
			(pts
				(arc
					(start 338.76107 -217.064336)
					(mid 338.10829 -217.064336)
					(end 338.76107 -217.064336)
				)
			)
		)
	)
	(zone
		(layers "B.Cu" "In6.Cu" "In11.Cu" "In13.Cu" "In15.Cu")
		(hatch none 0.5)
		(connect_pads
			(clearance 0)
		)
		(min_thickness 0.25)
		(keepout
			(tracks not_allowed)
			(vias allowed)
			(pads allowed)
			(copperpour not_allowed)
			(footprints allowed)
		)
		(placement
			(enabled no)
			(sheetname "")
		)
		(fill yes
			(thermal_gap 0.5)
			(thermal_bridge_width 0.5)
			(island_removal_mode 0)
		)
		(polygon
			(pts
				(arc
					(start 121.364756 -217.878406)
					(mid 120.711976 -217.878406)
					(end 121.364756 -217.878406)
				)
			)
		)
	)
	(zone
		(layers "B.Cu" "In6.Cu" "In11.Cu" "In13.Cu" "In15.Cu")
		(hatch none 0.5)
		(connect_pads
			(clearance 0)
		)
		(min_thickness 0.25)
		(keepout
			(tracks not_allowed)
			(vias allowed)
			(pads allowed)
			(copperpour not_allowed)
			(footprints allowed)
		)
		(placement
			(enabled no)
			(sheetname "")
		)
		(fill yes
			(thermal_gap 0.5)
			(thermal_bridge_width 0.5)
			(island_removal_mode 0)
		)
		(polygon
			(pts
				(arc
					(start 113.376202 -217.064336)
					(mid 112.723422 -217.064336)
					(end 113.376202 -217.064336)
				)
			)
		)
	)
	(zone
		(layers "B.Cu" "In6.Cu" "In11.Cu" "In13.Cu" "In15.Cu")
		(hatch none 0.5)
		(connect_pads
			(clearance 0)
		)
		(min_thickness 0.25)
		(keepout
			(tracks not_allowed)
			(vias allowed)
			(pads allowed)
			(copperpour not_allowed)
			(footprints allowed)
		)
		(placement
			(enabled no)
			(sheetname "")
		)
		(fill yes
			(thermal_gap 0.5)
			(thermal_bridge_width 0.5)
			(island_removal_mode 0)
		)
		(polygon
			(pts
				(arc
					(start 356.61727 -218.692222)
					(mid 355.96449 -218.692222)
					(end 356.61727 -218.692222)
				)
			)
		)
	)
	(zone
		(layers "B.Cu" "In6.Cu" "In11.Cu" "In13.Cu" "In15.Cu")
		(hatch none 0.5)
		(connect_pads
			(clearance 0)
		)
		(min_thickness 0.25)
		(keepout
			(tracks not_allowed)
			(vias allowed)
			(pads allowed)
			(copperpour not_allowed)
			(footprints allowed)
		)
		(placement
			(enabled no)
			(sheetname "")
		)
		(fill yes
			(thermal_gap 0.5)
			(thermal_bridge_width 0.5)
			(island_removal_mode 0)
		)
		(polygon
			(pts
				(arc
					(start 51.390804 -227.066602)
					(mid 50.738024 -227.066602)
					(end 51.390804 -227.066602)
				)
			)
		)
	)
	(zone
		(layers "B.Cu" "In6.Cu" "In11.Cu" "In13.Cu" "In15.Cu")
		(hatch none 0.5)
		(connect_pads
			(clearance 0)
		)
		(min_thickness 0.25)
		(keepout
			(tracks not_allowed)
			(vias allowed)
			(pads allowed)
			(copperpour not_allowed)
			(footprints allowed)
		)
		(placement
			(enabled no)
			(sheetname "")
		)
		(fill yes
			(thermal_gap 0.5)
			(thermal_bridge_width 0.5)
			(island_removal_mode 0)
		)
		(polygon
			(pts
				(arc
					(start 127.113538 -257.175254)
					(mid 126.460758 -257.175254)
					(end 127.113538 -257.175254)
				)
			)
		)
	)
	(zone
		(layers "B.Cu" "In6.Cu" "In11.Cu" "In13.Cu" "In15.Cu")
		(hatch none 0.5)
		(connect_pads
			(clearance 0)
		)
		(min_thickness 0.25)
		(keepout
			(tracks not_allowed)
			(vias allowed)
			(pads allowed)
			(copperpour not_allowed)
			(footprints allowed)
		)
		(placement
			(enabled no)
			(sheetname "")
		)
		(fill yes
			(thermal_gap 0.5)
			(thermal_bridge_width 0.5)
			(island_removal_mode 0)
		)
		(polygon
			(pts
				(arc
					(start 126.173484 -289.807142)
					(mid 125.520704 -289.807142)
					(end 126.173484 -289.807142)
				)
			)
		)
	)
	(zone
		(layers "B.Cu" "In6.Cu" "In11.Cu" "In13.Cu" "In15.Cu")
		(hatch none 0.5)
		(connect_pads
			(clearance 0)
		)
		(min_thickness 0.25)
		(keepout
			(tracks not_allowed)
			(vias allowed)
			(pads allowed)
			(copperpour not_allowed)
			(footprints allowed)
		)
		(placement
			(enabled no)
			(sheetname "")
		)
		(fill yes
			(thermal_gap 0.5)
			(thermal_bridge_width 0.5)
			(island_removal_mode 0)
		)
		(polygon
			(pts
				(arc
					(start 121.834402 -218.692222)
					(mid 121.181622 -218.692222)
					(end 121.834402 -218.692222)
				)
			)
		)
	)
	(zone
		(layers "B.Cu" "In6.Cu" "In11.Cu" "In13.Cu" "In15.Cu")
		(hatch none 0.5)
		(connect_pads
			(clearance 0)
		)
		(min_thickness 0.25)
		(keepout
			(tracks not_allowed)
			(vias allowed)
			(pads allowed)
			(copperpour not_allowed)
			(footprints allowed)
		)
		(placement
			(enabled no)
			(sheetname "")
		)
		(fill yes
			(thermal_gap 0.5)
			(thermal_bridge_width 0.5)
			(island_removal_mode 0)
		)
		(polygon
			(pts
				(arc
					(start 380.582424 -227.64496)
					(mid 379.929644 -227.64496)
					(end 380.582424 -227.64496)
				)
			)
		)
	)
	(zone
		(layers "B.Cu" "In6.Cu" "In11.Cu" "In13.Cu" "In15.Cu")
		(hatch none 0.5)
		(connect_pads
			(clearance 0)
		)
		(min_thickness 0.25)
		(keepout
			(tracks not_allowed)
			(vias allowed)
			(pads allowed)
			(copperpour not_allowed)
			(footprints allowed)
		)
		(placement
			(enabled no)
			(sheetname "")
		)
		(fill yes
			(thermal_gap 0.5)
			(thermal_bridge_width 0.5)
			(island_removal_mode 0)
		)
		(polygon
			(pts
				(arc
					(start 375.053606 -288.103056)
					(mid 374.400826 -288.103056)
					(end 375.053606 -288.103056)
				)
			)
		)
	)
	(zone
		(layers "B.Cu" "In6.Cu" "In11.Cu" "In13.Cu" "In15.Cu")
		(hatch none 0.5)
		(connect_pads
			(clearance 0)
		)
		(min_thickness 0.25)
		(keepout
			(tracks not_allowed)
			(vias allowed)
			(pads allowed)
			(copperpour not_allowed)
			(footprints allowed)
		)
		(placement
			(enabled no)
			(sheetname "")
		)
		(fill yes
			(thermal_gap 0.5)
			(thermal_bridge_width 0.5)
			(island_removal_mode 0)
		)
		(polygon
			(pts
				(arc
					(start 379.752606 -265.314176)
					(mid 379.099826 -265.314176)
					(end 379.752606 -265.314176)
				)
			)
		)
	)
	(zone
		(layers "B.Cu" "In6.Cu" "In11.Cu" "In13.Cu" "In15.Cu")
		(hatch none 0.5)
		(connect_pads
			(clearance 0)
		)
		(min_thickness 0.25)
		(keepout
			(tracks not_allowed)
			(vias allowed)
			(pads allowed)
			(copperpour not_allowed)
			(footprints allowed)
		)
		(placement
			(enabled no)
			(sheetname "")
		)
		(fill yes
			(thermal_gap 0.5)
			(thermal_bridge_width 0.5)
			(island_removal_mode 0)
		)
		(polygon
			(pts
				(arc
					(start 340.171024 -239.0394)
					(mid 339.518244 -239.0394)
					(end 340.171024 -239.0394)
				)
			)
		)
	)
	(zone
		(layers "B.Cu" "In6.Cu" "In11.Cu" "In13.Cu" "In15.Cu")
		(hatch none 0.5)
		(connect_pads
			(clearance 0)
		)
		(min_thickness 0.25)
		(keepout
			(tracks not_allowed)
			(vias allowed)
			(pads allowed)
			(copperpour not_allowed)
			(footprints allowed)
		)
		(placement
			(enabled no)
			(sheetname "")
		)
		(fill yes
			(thermal_gap 0.5)
			(thermal_bridge_width 0.5)
			(island_removal_mode 0)
		)
		(polygon
			(pts
				(arc
					(start 91.760802 -244.73662)
					(mid 91.108022 -244.73662)
					(end 91.760802 -244.73662)
				)
			)
		)
	)
	(zone
		(layers "B.Cu" "In6.Cu" "In11.Cu" "In13.Cu" "In15.Cu")
		(hatch none 0.5)
		(connect_pads
			(clearance 0)
		)
		(min_thickness 0.25)
		(keepout
			(tracks not_allowed)
			(vias allowed)
			(pads allowed)
			(copperpour not_allowed)
			(footprints allowed)
		)
		(placement
			(enabled no)
			(sheetname "")
		)
		(fill yes
			(thermal_gap 0.5)
			(thermal_bridge_width 0.5)
			(island_removal_mode 0)
		)
		(polygon
			(pts
				(arc
					(start 130.292602 -238.225584)
					(mid 129.639822 -238.225584)
					(end 130.292602 -238.225584)
				)
			)
		)
	)
	(zone
		(layers "B.Cu" "In6.Cu" "In11.Cu" "In13.Cu" "In15.Cu")
		(hatch none 0.5)
		(connect_pads
			(clearance 0)
		)
		(min_thickness 0.25)
		(keepout
			(tracks not_allowed)
			(vias allowed)
			(pads allowed)
			(copperpour not_allowed)
			(footprints allowed)
		)
		(placement
			(enabled no)
			(sheetname "")
		)
		(fill yes
			(thermal_gap 0.5)
			(thermal_bridge_width 0.5)
			(island_removal_mode 0)
		)
		(polygon
			(pts
				(arc
					(start 299.356272 -284.016958)
					(mid 298.703492 -284.016958)
					(end 299.356272 -284.016958)
				)
			)
		)
	)
	(zone
		(layers "B.Cu" "In6.Cu" "In11.Cu" "In13.Cu" "In15.Cu")
		(hatch none 0.5)
		(connect_pads
			(clearance 0)
		)
		(min_thickness 0.25)
		(keepout
			(tracks not_allowed)
			(vias allowed)
			(pads allowed)
			(copperpour not_allowed)
			(footprints allowed)
		)
		(placement
			(enabled no)
			(sheetname "")
		)
		(fill yes
			(thermal_gap 0.5)
			(thermal_bridge_width 0.5)
			(island_removal_mode 0)
		)
		(polygon
			(pts
				(arc
					(start 379.752606 -266.941808)
					(mid 379.099826 -266.941808)
					(end 379.752606 -266.941808)
				)
			)
		)
	)
	(zone
		(layers "B.Cu" "In6.Cu" "In11.Cu" "In13.Cu" "In15.Cu")
		(hatch none 0.5)
		(connect_pads
			(clearance 0)
		)
		(min_thickness 0.25)
		(keepout
			(tracks not_allowed)
			(vias allowed)
			(pads allowed)
			(copperpour not_allowed)
			(footprints allowed)
		)
		(placement
			(enabled no)
			(sheetname "")
		)
		(fill yes
			(thermal_gap 0.5)
			(thermal_bridge_width 0.5)
			(island_removal_mode 0)
		)
		(polygon
			(pts
				(arc
					(start 93.640402 -218.692222)
					(mid 92.987622 -218.692222)
					(end 93.640402 -218.692222)
				)
			)
		)
	)
	(zone
		(layers "B.Cu" "In6.Cu" "In11.Cu" "In13.Cu" "In15.Cu")
		(hatch none 0.5)
		(connect_pads
			(clearance 0)
		)
		(min_thickness 0.25)
		(keepout
			(tracks not_allowed)
			(vias allowed)
			(pads allowed)
			(copperpour not_allowed)
			(footprints allowed)
		)
		(placement
			(enabled no)
			(sheetname "")
		)
		(fill yes
			(thermal_gap 0.5)
			(thermal_bridge_width 0.5)
			(island_removal_mode 0)
		)
		(polygon
			(pts
				(arc
					(start 378.702824 -239.0394)
					(mid 378.050044 -239.0394)
					(end 378.702824 -239.0394)
				)
			)
		)
	)
	(zone
		(layers "B.Cu" "In6.Cu" "In11.Cu" "In13.Cu" "In15.Cu")
		(hatch none 0.5)
		(connect_pads
			(clearance 0)
		)
		(min_thickness 0.25)
		(keepout
			(tracks not_allowed)
			(vias allowed)
			(pads allowed)
			(copperpour not_allowed)
			(footprints allowed)
		)
		(placement
			(enabled no)
			(sheetname "")
		)
		(fill yes
			(thermal_gap 0.5)
			(thermal_bridge_width 0.5)
			(island_removal_mode 0)
		)
		(polygon
			(pts
				(arc
					(start 436.150004 -314.616592)
					(mid 435.497224 -314.616592)
					(end 436.150004 -314.616592)
				)
			)
		)
	)
	(zone
		(layers "B.Cu" "In6.Cu" "In11.Cu" "In13.Cu" "In15.Cu")
		(hatch none 0.5)
		(connect_pads
			(clearance 0)
		)
		(min_thickness 0.25)
		(keepout
			(tracks not_allowed)
			(vias allowed)
			(pads allowed)
			(copperpour not_allowed)
			(footprints allowed)
		)
		(placement
			(enabled no)
			(sheetname "")
		)
		(fill yes
			(thermal_gap 0.5)
			(thermal_bridge_width 0.5)
			(island_removal_mode 0)
		)
		(polygon
			(pts
				(arc
					(start 346.859606 -288.103056)
					(mid 346.206826 -288.103056)
					(end 346.859606 -288.103056)
				)
			)
		)
	)
	(zone
		(layers "B.Cu" "In6.Cu" "In11.Cu" "In13.Cu" "In15.Cu")
		(hatch none 0.5)
		(connect_pads
			(clearance 0)
		)
		(min_thickness 0.25)
		(keepout
			(tracks not_allowed)
			(vias allowed)
			(pads allowed)
			(copperpour not_allowed)
			(footprints allowed)
		)
		(placement
			(enabled no)
			(sheetname "")
		)
		(fill yes
			(thermal_gap 0.5)
			(thermal_bridge_width 0.5)
			(island_removal_mode 0)
		)
		(polygon
			(pts
				(arc
					(start 131.702556 -234.15625)
					(mid 131.049776 -234.15625)
					(end 131.702556 -234.15625)
				)
			)
		)
	)
	(zone
		(layers "B.Cu" "In6.Cu" "In11.Cu" "In13.Cu" "In15.Cu")
		(hatch none 0.5)
		(connect_pads
			(clearance 0)
		)
		(min_thickness 0.25)
		(keepout
			(tracks not_allowed)
			(vias allowed)
			(pads allowed)
			(copperpour not_allowed)
			(footprints allowed)
		)
		(placement
			(enabled no)
			(sheetname "")
		)
		(fill yes
			(thermal_gap 0.5)
			(thermal_bridge_width 0.5)
			(island_removal_mode 0)
		)
		(polygon
			(pts
				(arc
					(start 177.222404 -227.066602)
					(mid 176.569624 -227.066602)
					(end 177.222404 -227.066602)
				)
			)
		)
	)
	(zone
		(layers "B.Cu" "In6.Cu" "In11.Cu" "In13.Cu" "In15.Cu")
		(hatch none 0.5)
		(connect_pads
			(clearance 0)
		)
		(min_thickness 0.25)
		(keepout
			(tracks not_allowed)
			(vias allowed)
			(pads allowed)
			(copperpour not_allowed)
			(footprints allowed)
		)
		(placement
			(enabled no)
			(sheetname "")
		)
		(fill yes
			(thermal_gap 0.5)
			(thermal_bridge_width 0.5)
			(island_removal_mode 0)
		)
		(polygon
			(pts
				(arc
					(start 376.94489 5.895594)
					(mid 376.24131 5.895594)
					(end 376.94489 5.895594)
				)
			)
		)
	)
	(zone
		(layers "B.Cu" "In6.Cu" "In11.Cu" "In13.Cu" "In15.Cu")
		(hatch none 0.5)
		(connect_pads
			(clearance 0)
		)
		(min_thickness 0.25)
		(keepout
			(tracks not_allowed)
			(vias allowed)
			(pads allowed)
			(copperpour not_allowed)
			(footprints allowed)
		)
		(placement
			(enabled no)
			(sheetname "")
		)
		(fill yes
			(thermal_gap 0.5)
			(thermal_bridge_width 0.5)
			(island_removal_mode 0)
		)
		(polygon
			(pts
				(arc
					(start 51.390804 -287.416748)
					(mid 50.738024 -287.416748)
					(end 51.390804 -287.416748)
				)
			)
		)
	)
	(zone
		(layers "B.Cu" "In6.Cu" "In11.Cu" "In13.Cu" "In15.Cu")
		(hatch none 0.5)
		(connect_pads
			(clearance 0)
		)
		(min_thickness 0.25)
		(keepout
			(tracks not_allowed)
			(vias allowed)
			(pads allowed)
			(copperpour not_allowed)
			(footprints allowed)
		)
		(placement
			(enabled no)
			(sheetname "")
		)
		(fill yes
			(thermal_gap 0.5)
			(thermal_bridge_width 0.5)
			(island_removal_mode 0)
		)
		(polygon
			(pts
				(arc
					(start 125.123956 -217.878406)
					(mid 124.471176 -217.878406)
					(end 125.123956 -217.878406)
				)
			)
		)
	)
	(zone
		(layers "B.Cu" "In6.Cu" "In11.Cu" "In13.Cu" "In15.Cu")
		(hatch none 0.5)
		(connect_pads
			(clearance 0)
		)
		(min_thickness 0.25)
		(keepout
			(tracks not_allowed)
			(vias allowed)
			(pads allowed)
			(copperpour not_allowed)
			(footprints allowed)
		)
		(placement
			(enabled no)
			(sheetname "")
		)
		(fill yes
			(thermal_gap 0.5)
			(thermal_bridge_width 0.5)
			(island_removal_mode 0)
		)
		(polygon
			(pts
				(arc
					(start 92.340938 -271.825212)
					(mid 91.688158 -271.825212)
					(end 92.340938 -271.825212)
				)
			)
		)
	)
	(zone
		(layers "B.Cu" "In6.Cu" "In11.Cu" "In13.Cu" "In15.Cu")
		(hatch none 0.5)
		(connect_pads
			(clearance 0)
		)
		(min_thickness 0.25)
		(keepout
			(tracks not_allowed)
			(vias allowed)
			(pads allowed)
			(copperpour not_allowed)
			(footprints allowed)
		)
		(placement
			(enabled no)
			(sheetname "")
		)
		(fill yes
			(thermal_gap 0.5)
			(thermal_bridge_width 0.5)
			(island_removal_mode 0)
		)
		(polygon
			(pts
				(arc
					(start 188.209936 -235.566712)
					(mid 187.557156 -235.566712)
					(end 188.209936 -235.566712)
				)
			)
		)
	)
	(zone
		(layers "B.Cu" "In6.Cu" "In11.Cu" "In13.Cu" "In15.Cu")
		(hatch none 0.5)
		(connect_pads
			(clearance 0)
		)
		(min_thickness 0.25)
		(keepout
			(tracks not_allowed)
			(vias allowed)
			(pads allowed)
			(copperpour not_allowed)
			(footprints allowed)
		)
		(placement
			(enabled no)
			(sheetname "")
		)
		(fill yes
			(thermal_gap 0.5)
			(thermal_bridge_width 0.5)
			(island_removal_mode 0)
		)
		(polygon
			(pts
				(arc
					(start 436.150004 -241.516662)
					(mid 435.497224 -241.516662)
					(end 436.150004 -241.516662)
				)
			)
		)
	)
	(zone
		(layers "B.Cu" "In6.Cu" "In11.Cu" "In13.Cu" "In15.Cu")
		(hatch none 0.5)
		(connect_pads
			(clearance 0)
		)
		(min_thickness 0.25)
		(keepout
			(tracks not_allowed)
			(vias allowed)
			(pads allowed)
			(copperpour not_allowed)
			(footprints allowed)
		)
		(placement
			(enabled no)
			(sheetname "")
		)
		(fill yes
			(thermal_gap 0.5)
			(thermal_bridge_width 0.5)
			(island_removal_mode 0)
		)
		(polygon
			(pts
				(arc
					(start 299.330872 -201.56678)
					(mid 298.678092 -201.56678)
					(end 299.330872 -201.56678)
				)
			)
		)
	)
	(zone
		(layers "B.Cu" "In6.Cu" "In11.Cu" "In13.Cu" "In15.Cu")
		(hatch none 0.5)
		(connect_pads
			(clearance 0)
		)
		(min_thickness 0.25)
		(keepout
			(tracks not_allowed)
			(vias allowed)
			(pads allowed)
			(copperpour not_allowed)
			(footprints allowed)
		)
		(placement
			(enabled no)
			(sheetname "")
		)
		(fill yes
			(thermal_gap 0.5)
			(thermal_bridge_width 0.5)
			(island_removal_mode 0)
		)
		(polygon
			(pts
				(arc
					(start 177.222404 -231.316784)
					(mid 176.569624 -231.316784)
					(end 177.222404 -231.316784)
				)
			)
		)
	)
	(zone
		(layers "B.Cu" "In6.Cu" "In11.Cu" "In13.Cu" "In15.Cu")
		(hatch none 0.5)
		(connect_pads
			(clearance 0)
		)
		(min_thickness 0.25)
		(keepout
			(tracks not_allowed)
			(vias allowed)
			(pads allowed)
			(copperpour not_allowed)
			(footprints allowed)
		)
		(placement
			(enabled no)
			(sheetname "")
		)
		(fill yes
			(thermal_gap 0.5)
			(thermal_bridge_width 0.5)
			(island_removal_mode 0)
		)
		(polygon
			(pts
				(arc
					(start 130.292602 -236.597952)
					(mid 129.639822 -236.597952)
					(end 130.292602 -236.597952)
				)
			)
		)
	)
	(zone
		(layers "B.Cu" "In6.Cu" "In11.Cu" "In13.Cu" "In15.Cu")
		(hatch none 0.5)
		(connect_pads
			(clearance 0)
		)
		(min_thickness 0.25)
		(keepout
			(tracks not_allowed)
			(vias allowed)
			(pads allowed)
			(copperpour not_allowed)
			(footprints allowed)
		)
		(placement
			(enabled no)
			(sheetname "")
		)
		(fill yes
			(thermal_gap 0.5)
			(thermal_bridge_width 0.5)
			(island_removal_mode 0)
		)
		(polygon
			(pts
				(arc
					(start 436.150004 -245.76659)
					(mid 435.497224 -245.76659)
					(end 436.150004 -245.76659)
				)
			)
		)
	)
	(zone
		(layers "B.Cu" "In6.Cu" "In11.Cu" "In13.Cu" "In15.Cu")
		(hatch none 0.5)
		(connect_pads
			(clearance 0)
		)
		(min_thickness 0.25)
		(keepout
			(tracks not_allowed)
			(vias allowed)
			(pads allowed)
			(copperpour not_allowed)
			(footprints allowed)
		)
		(placement
			(enabled no)
			(sheetname "")
		)
		(fill yes
			(thermal_gap 0.5)
			(thermal_bridge_width 0.5)
			(island_removal_mode 0)
		)
		(polygon
			(pts
				(arc
					(start 92.810584 -279.150318)
					(mid 92.157804 -279.150318)
					(end 92.810584 -279.150318)
				)
			)
		)
	)
	(zone
		(layers "B.Cu" "In6.Cu" "In11.Cu" "In13.Cu" "In15.Cu")
		(hatch none 0.5)
		(connect_pads
			(clearance 0)
		)
		(min_thickness 0.25)
		(keepout
			(tracks not_allowed)
			(vias allowed)
			(pads allowed)
			(copperpour not_allowed)
			(footprints allowed)
		)
		(placement
			(enabled no)
			(sheetname "")
		)
		(fill yes
			(thermal_gap 0.5)
			(thermal_bridge_width 0.5)
			(island_removal_mode 0)
		)
		(polygon
			(pts
				(arc
					(start 381.522224 -217.878406)
					(mid 380.869444 -217.878406)
					(end 381.522224 -217.878406)
				)
			)
		)
	)
	(zone
		(layers "B.Cu" "In6.Cu" "In11.Cu" "In13.Cu" "In15.Cu")
		(hatch none 0.5)
		(connect_pads
			(clearance 0)
		)
		(min_thickness 0.25)
		(keepout
			(tracks not_allowed)
			(vias allowed)
			(pads allowed)
			(copperpour not_allowed)
			(footprints allowed)
		)
		(placement
			(enabled no)
			(sheetname "")
		)
		(fill yes
			(thermal_gap 0.5)
			(thermal_bridge_width 0.5)
			(island_removal_mode 0)
		)
		(polygon
			(pts
				(arc
					(start 127.943356 -217.878406)
					(mid 127.290576 -217.878406)
					(end 127.943356 -217.878406)
				)
			)
		)
	)
	(zone
		(layers "B.Cu" "In6.Cu" "In11.Cu" "In13.Cu" "In15.Cu")
		(hatch none 0.5)
		(connect_pads
			(clearance 0)
		)
		(min_thickness 0.25)
		(keepout
			(tracks not_allowed)
			(vias allowed)
			(pads allowed)
			(copperpour not_allowed)
			(footprints allowed)
		)
		(placement
			(enabled no)
			(sheetname "")
		)
		(fill yes
			(thermal_gap 0.5)
			(thermal_bridge_width 0.5)
			(island_removal_mode 0)
		)
		(polygon
			(pts
				(arc
					(start 128.522984 -256.361438)
					(mid 127.870204 -256.361438)
					(end 128.522984 -256.361438)
				)
			)
		)
	)
	(zone
		(layers "B.Cu" "In6.Cu" "In11.Cu" "In13.Cu" "In15.Cu")
		(hatch none 0.5)
		(connect_pads
			(clearance 0)
		)
		(min_thickness 0.25)
		(keepout
			(tracks not_allowed)
			(vias allowed)
			(pads allowed)
			(copperpour not_allowed)
			(footprints allowed)
		)
		(placement
			(enabled no)
			(sheetname "")
		)
		(fill yes
			(thermal_gap 0.5)
			(thermal_bridge_width 0.5)
			(island_removal_mode 0)
		)
		(polygon
			(pts
				(arc
					(start 95.050356 -217.878406)
					(mid 94.397576 -217.878406)
					(end 95.050356 -217.878406)
				)
			)
		)
	)
	(zone
		(layers "B.Cu" "In6.Cu" "In11.Cu" "In13.Cu" "In15.Cu")
		(hatch none 0.5)
		(connect_pads
			(clearance 0)
		)
		(min_thickness 0.25)
		(keepout
			(tracks not_allowed)
			(vias allowed)
			(pads allowed)
			(copperpour not_allowed)
			(footprints allowed)
		)
		(placement
			(enabled no)
			(sheetname "")
		)
		(fill yes
			(thermal_gap 0.5)
			(thermal_bridge_width 0.5)
			(island_removal_mode 0)
		)
		(polygon
			(pts
				(arc
					(start 188.209936 -213.46668)
					(mid 187.557156 -213.46668)
					(end 188.209936 -213.46668)
				)
			)
		)
	)
	(zone
		(layers "B.Cu" "In6.Cu" "In11.Cu" "In13.Cu" "In15.Cu")
		(hatch none 0.5)
		(connect_pads
			(clearance 0)
		)
		(min_thickness 0.25)
		(keepout
			(tracks not_allowed)
			(vias allowed)
			(pads allowed)
			(copperpour not_allowed)
			(footprints allowed)
		)
		(placement
			(enabled no)
			(sheetname "")
		)
		(fill yes
			(thermal_gap 0.5)
			(thermal_bridge_width 0.5)
			(island_removal_mode 0)
		)
		(polygon
			(pts
				(arc
					(start 340.750652 -274.266914)
					(mid 340.097872 -274.266914)
					(end 340.750652 -274.266914)
				)
			)
		)
	)
	(zone
		(layers "B.Cu" "In6.Cu" "In11.Cu" "In13.Cu" "In15.Cu")
		(hatch none 0.5)
		(connect_pads
			(clearance 0)
		)
		(min_thickness 0.25)
		(keepout
			(tracks not_allowed)
			(vias allowed)
			(pads allowed)
			(copperpour not_allowed)
			(footprints allowed)
		)
		(placement
			(enabled no)
			(sheetname "")
		)
		(fill yes
			(thermal_gap 0.5)
			(thermal_bridge_width 0.5)
			(island_removal_mode 0)
		)
		(polygon
			(pts
				(arc
					(start 129.932938 -275.08073)
					(mid 129.280158 -275.08073)
					(end 129.932938 -275.08073)
				)
			)
		)
	)
	(zone
		(layers "B.Cu" "In6.Cu" "In11.Cu" "In13.Cu" "In15.Cu")
		(hatch none 0.5)
		(connect_pads
			(clearance 0)
		)
		(min_thickness 0.25)
		(keepout
			(tracks not_allowed)
			(vias allowed)
			(pads allowed)
			(copperpour not_allowed)
			(footprints allowed)
		)
		(placement
			(enabled no)
			(sheetname "")
		)
		(fill yes
			(thermal_gap 0.5)
			(thermal_bridge_width 0.5)
			(island_removal_mode 0)
		)
		(polygon
			(pts
				(arc
					(start 340.750652 -261.244842)
					(mid 340.097872 -261.244842)
					(end 340.750652 -261.244842)
				)
			)
		)
	)
	(zone
		(layers "B.Cu" "In6.Cu" "In11.Cu" "In13.Cu" "In15.Cu")
		(hatch none 0.5)
		(connect_pads
			(clearance 0)
		)
		(min_thickness 0.25)
		(keepout
			(tracks not_allowed)
			(vias allowed)
			(pads allowed)
			(copperpour not_allowed)
			(footprints allowed)
		)
		(placement
			(enabled no)
			(sheetname "")
		)
		(fill yes
			(thermal_gap 0.5)
			(thermal_bridge_width 0.5)
			(island_removal_mode 0)
		)
		(polygon
			(pts
				(arc
					(start 440.250072 -293.366698)
					(mid 439.597292 -293.366698)
					(end 440.250072 -293.366698)
				)
			)
		)
	)
	(zone
		(layers "B.Cu" "In6.Cu" "In11.Cu" "In13.Cu" "In15.Cu")
		(hatch none 0.5)
		(connect_pads
			(clearance 0)
		)
		(min_thickness 0.25)
		(keepout
			(tracks not_allowed)
			(vias allowed)
			(pads allowed)
			(copperpour not_allowed)
			(footprints allowed)
		)
		(placement
			(enabled no)
			(sheetname "")
		)
		(fill yes
			(thermal_gap 0.5)
			(thermal_bridge_width 0.5)
			(island_removal_mode 0)
		)
		(polygon
			(pts
				(arc
					(start 131.702556 -245.55069)
					(mid 131.049776 -245.55069)
					(end 131.702556 -245.55069)
				)
			)
		)
	)
	(zone
		(layers "B.Cu" "In6.Cu" "In11.Cu" "In13.Cu" "In15.Cu")
		(hatch none 0.5)
		(connect_pads
			(clearance 0)
		)
		(min_thickness 0.25)
		(keepout
			(tracks not_allowed)
			(vias allowed)
			(pads allowed)
			(copperpour not_allowed)
			(footprints allowed)
		)
		(placement
			(enabled no)
			(sheetname "")
		)
		(fill yes
			(thermal_gap 0.5)
			(thermal_bridge_width 0.5)
			(island_removal_mode 0)
		)
		(polygon
			(pts
				(arc
					(start 131.812538 -273.453098)
					(mid 131.159758 -273.453098)
					(end 131.812538 -273.453098)
				)
			)
		)
	)
	(zone
		(layers "B.Cu" "In6.Cu" "In11.Cu" "In13.Cu" "In15.Cu")
		(hatch none 0.5)
		(connect_pads
			(clearance 0)
		)
		(min_thickness 0.25)
		(keepout
			(tracks not_allowed)
			(vias allowed)
			(pads allowed)
			(copperpour not_allowed)
			(footprints allowed)
		)
		(placement
			(enabled no)
			(sheetname "")
		)
		(fill yes
			(thermal_gap 0.5)
			(thermal_bridge_width 0.5)
			(island_removal_mode 0)
		)
		(polygon
			(pts
				(arc
					(start 280.143204 -261.066788)
					(mid 279.490424 -261.066788)
					(end 280.143204 -261.066788)
				)
			)
		)
	)
	(zone
		(layers "B.Cu" "In6.Cu" "In11.Cu" "In13.Cu" "In15.Cu")
		(hatch none 0.5)
		(connect_pads
			(clearance 0)
		)
		(min_thickness 0.25)
		(keepout
			(tracks not_allowed)
			(vias allowed)
			(pads allowed)
			(copperpour not_allowed)
			(footprints allowed)
		)
		(placement
			(enabled no)
			(sheetname "")
		)
		(fill yes
			(thermal_gap 0.5)
			(thermal_bridge_width 0.5)
			(island_removal_mode 0)
		)
		(polygon
			(pts
				(arc
					(start 51.390804 -203.266802)
					(mid 50.738024 -203.266802)
					(end 51.390804 -203.266802)
				)
			)
		)
	)
	(zone
		(layers "B.Cu" "In6.Cu" "In11.Cu" "In13.Cu" "In15.Cu")
		(hatch none 0.5)
		(connect_pads
			(clearance 0)
		)
		(min_thickness 0.25)
		(keepout
			(tracks not_allowed)
			(vias allowed)
			(pads allowed)
			(copperpour not_allowed)
			(footprints allowed)
		)
		(placement
			(enabled no)
			(sheetname "")
		)
		(fill yes
			(thermal_gap 0.5)
			(thermal_bridge_width 0.5)
			(island_removal_mode 0)
		)
		(polygon
			(pts
				(arc
					(start 379.642624 -217.878406)
					(mid 378.989844 -217.878406)
					(end 379.642624 -217.878406)
				)
			)
		)
	)
	(zone
		(layers "B.Cu" "In6.Cu" "In11.Cu" "In13.Cu" "In15.Cu")
		(hatch none 0.5)
		(connect_pads
			(clearance 0)
		)
		(min_thickness 0.25)
		(keepout
			(tracks not_allowed)
			(vias allowed)
			(pads allowed)
			(copperpour not_allowed)
			(footprints allowed)
		)
		(placement
			(enabled no)
			(sheetname "")
		)
		(fill yes
			(thermal_gap 0.5)
			(thermal_bridge_width 0.5)
			(island_removal_mode 0)
		)
		(polygon
			(pts
				(arc
					(start 91.291156 -217.878406)
					(mid 90.638376 -217.878406)
					(end 91.291156 -217.878406)
				)
			)
		)
	)
	(zone
		(layers "B.Cu" "In6.Cu" "In11.Cu" "In13.Cu" "In15.Cu")
		(hatch none 0.5)
		(connect_pads
			(clearance 0)
		)
		(min_thickness 0.25)
		(keepout
			(tracks not_allowed)
			(vias allowed)
			(pads allowed)
			(copperpour not_allowed)
			(footprints allowed)
		)
		(placement
			(enabled no)
			(sheetname "")
		)
		(fill yes
			(thermal_gap 0.5)
			(thermal_bridge_width 0.5)
			(island_removal_mode 0)
		)
		(polygon
			(pts
				(arc
					(start 131.702556 -232.528364)
					(mid 131.049776 -232.528364)
					(end 131.702556 -232.528364)
				)
			)
		)
	)
	(zone
		(layers "B.Cu" "In6.Cu" "In11.Cu" "In13.Cu" "In15.Cu")
		(hatch none 0.5)
		(connect_pads
			(clearance 0)
		)
		(min_thickness 0.25)
		(keepout
			(tracks not_allowed)
			(vias allowed)
			(pads allowed)
			(copperpour not_allowed)
			(footprints allowed)
		)
		(placement
			(enabled no)
			(sheetname "")
		)
		(fill yes
			(thermal_gap 0.5)
			(thermal_bridge_width 0.5)
			(island_removal_mode 0)
		)
		(polygon
			(pts
				(arc
					(start 379.752606 -260.430772)
					(mid 379.099826 -260.430772)
					(end 379.752606 -260.430772)
				)
			)
		)
	)
	(zone
		(layers "B.Cu" "In6.Cu" "In11.Cu" "In13.Cu" "In15.Cu")
		(hatch none 0.5)
		(connect_pads
			(clearance 0)
		)
		(min_thickness 0.25)
		(keepout
			(tracks not_allowed)
			(vias allowed)
			(pads allowed)
			(copperpour not_allowed)
			(footprints allowed)
		)
		(placement
			(enabled no)
			(sheetname "")
		)
		(fill yes
			(thermal_gap 0.5)
			(thermal_bridge_width 0.5)
			(island_removal_mode 0)
		)
		(polygon
			(pts
				(arc
					(start 356.147624 -217.878406)
					(mid 355.494844 -217.878406)
					(end 356.147624 -217.878406)
				)
			)
		)
	)
	(zone
		(layers "B.Cu" "In6.Cu" "In11.Cu" "In13.Cu" "In15.Cu")
		(hatch none 0.5)
		(connect_pads
			(clearance 0)
		)
		(min_thickness 0.25)
		(keepout
			(tracks not_allowed)
			(vias allowed)
			(pads allowed)
			(copperpour not_allowed)
			(footprints allowed)
		)
		(placement
			(enabled no)
			(sheetname "")
		)
		(fill yes
			(thermal_gap 0.5)
			(thermal_bridge_width 0.5)
			(island_removal_mode 0)
		)
		(polygon
			(pts
				(arc
					(start 124.764038 -288.917126)
					(mid 124.111258 -288.917126)
					(end 124.764038 -288.917126)
				)
			)
		)
	)
	(zone
		(layers "B.Cu" "In6.Cu" "In11.Cu" "In13.Cu" "In15.Cu")
		(hatch none 0.5)
		(connect_pads
			(clearance 0)
		)
		(min_thickness 0.25)
		(keepout
			(tracks not_allowed)
			(vias allowed)
			(pads allowed)
			(copperpour not_allowed)
			(footprints allowed)
		)
		(placement
			(enabled no)
			(sheetname "")
		)
		(fill yes
			(thermal_gap 0.5)
			(thermal_bridge_width 0.5)
			(island_removal_mode 0)
		)
		(polygon
			(pts
				(arc
					(start 378.23267 -241.481102)
					(mid 377.57989 -241.481102)
					(end 378.23267 -241.481102)
				)
			)
		)
	)
	(zone
		(layers "B.Cu" "In6.Cu" "In11.Cu" "In13.Cu" "In15.Cu")
		(hatch none 0.5)
		(connect_pads
			(clearance 0)
		)
		(min_thickness 0.25)
		(keepout
			(tracks not_allowed)
			(vias allowed)
			(pads allowed)
			(copperpour not_allowed)
			(footprints allowed)
		)
		(placement
			(enabled no)
			(sheetname "")
		)
		(fill yes
			(thermal_gap 0.5)
			(thermal_bridge_width 0.5)
			(island_removal_mode 0)
		)
		(polygon
			(pts
				(arc
					(start 379.642624 -234.15625)
					(mid 378.989844 -234.15625)
					(end 379.642624 -234.15625)
				)
			)
		)
	)
	(zone
		(layers "B.Cu" "In6.Cu" "In11.Cu" "In13.Cu" "In15.Cu")
		(hatch none 0.5)
		(connect_pads
			(clearance 0)
		)
		(min_thickness 0.25)
		(keepout
			(tracks not_allowed)
			(vias allowed)
			(pads allowed)
			(copperpour not_allowed)
			(footprints allowed)
		)
		(placement
			(enabled no)
			(sheetname "")
		)
		(fill yes
			(thermal_gap 0.5)
			(thermal_bridge_width 0.5)
			(island_removal_mode 0)
		)
		(polygon
			(pts
				(arc
					(start 350.618806 -288.103056)
					(mid 349.966026 -288.103056)
					(end 350.618806 -288.103056)
				)
			)
		)
	)
	(zone
		(layers "B.Cu" "In6.Cu" "In11.Cu" "In13.Cu" "In15.Cu")
		(hatch none 0.5)
		(connect_pads
			(clearance 0)
		)
		(min_thickness 0.25)
		(keepout
			(tracks not_allowed)
			(vias allowed)
			(pads allowed)
			(copperpour not_allowed)
			(footprints allowed)
		)
		(placement
			(enabled no)
			(sheetname "")
		)
		(fill yes
			(thermal_gap 0.5)
			(thermal_bridge_width 0.5)
			(island_removal_mode 0)
		)
		(polygon
			(pts
				(arc
					(start 378.342652 -266.128246)
					(mid 377.689872 -266.128246)
					(end 378.342652 -266.128246)
				)
			)
		)
	)
	(zone
		(layers "B.Cu" "In6.Cu" "In11.Cu" "In13.Cu" "In15.Cu")
		(hatch none 0.5)
		(connect_pads
			(clearance 0)
		)
		(min_thickness 0.25)
		(keepout
			(tracks not_allowed)
			(vias allowed)
			(pads allowed)
			(copperpour not_allowed)
			(footprints allowed)
		)
		(placement
			(enabled no)
			(sheetname "")
		)
		(fill yes
			(thermal_gap 0.5)
			(thermal_bridge_width 0.5)
			(island_removal_mode 0)
		)
		(polygon
			(pts
				(arc
					(start 92.340938 -253.919736)
					(mid 91.688158 -253.919736)
					(end 92.340938 -253.919736)
				)
			)
		)
	)
	(zone
		(layers "B.Cu" "In6.Cu" "In11.Cu" "In13.Cu" "In15.Cu")
		(hatch none 0.5)
		(connect_pads
			(clearance 0)
		)
		(min_thickness 0.25)
		(keepout
			(tracks not_allowed)
			(vias allowed)
			(pads allowed)
			(copperpour not_allowed)
			(footprints allowed)
		)
		(placement
			(enabled no)
			(sheetname "")
		)
		(fill yes
			(thermal_gap 0.5)
			(thermal_bridge_width 0.5)
			(island_removal_mode 0)
		)
		(polygon
			(pts
				(arc
					(start 121.944638 -288.917126)
					(mid 121.291858 -288.917126)
					(end 121.944638 -288.917126)
				)
			)
		)
	)
	(zone
		(layers "B.Cu" "In6.Cu" "In11.Cu" "In13.Cu" "In15.Cu")
		(hatch none 0.5)
		(connect_pads
			(clearance 0)
		)
		(min_thickness 0.25)
		(keepout
			(tracks not_allowed)
			(vias allowed)
			(pads allowed)
			(copperpour not_allowed)
			(footprints allowed)
		)
		(placement
			(enabled no)
			(sheetname "")
		)
		(fill yes
			(thermal_gap 0.5)
			(thermal_bridge_width 0.5)
			(island_removal_mode 0)
		)
		(polygon
			(pts
				(arc
					(start 341.58047 -231.714548)
					(mid 340.92769 -231.714548)
					(end 341.58047 -231.714548)
				)
			)
		)
	)
	(zone
		(layers "B.Cu" "In6.Cu" "In11.Cu" "In13.Cu" "In15.Cu")
		(hatch none 0.5)
		(connect_pads
			(clearance 0)
		)
		(min_thickness 0.25)
		(keepout
			(tracks not_allowed)
			(vias allowed)
			(pads allowed)
			(copperpour not_allowed)
			(footprints allowed)
		)
		(placement
			(enabled no)
			(sheetname "")
		)
		(fill yes
			(thermal_gap 0.5)
			(thermal_bridge_width 0.5)
			(island_removal_mode 0)
		)
		(polygon
			(pts
				(arc
					(start 421.062404 -299.316648)
					(mid 420.409624 -299.316648)
					(end 421.062404 -299.316648)
				)
			)
		)
	)
	(zone
		(layers "B.Cu" "In6.Cu" "In11.Cu" "In13.Cu" "In15.Cu")
		(hatch none 0.5)
		(connect_pads
			(clearance 0)
		)
		(min_thickness 0.25)
		(keepout
			(tracks not_allowed)
			(vias allowed)
			(pads allowed)
			(copperpour not_allowed)
			(footprints allowed)
		)
		(placement
			(enabled no)
			(sheetname "")
		)
		(fill yes
			(thermal_gap 0.5)
			(thermal_bridge_width 0.5)
			(island_removal_mode 0)
		)
		(polygon
			(pts
				(arc
					(start 94.110556 -245.55069)
					(mid 93.457776 -245.55069)
					(end 94.110556 -245.55069)
				)
			)
		)
	)
	(zone
		(layers "B.Cu" "In6.Cu" "In11.Cu" "In13.Cu" "In15.Cu")
		(hatch none 0.5)
		(connect_pads
			(clearance 0)
		)
		(min_thickness 0.25)
		(keepout
			(tracks not_allowed)
			(vias allowed)
			(pads allowed)
			(copperpour not_allowed)
			(footprints allowed)
		)
		(placement
			(enabled no)
			(sheetname "")
		)
		(fill yes
			(thermal_gap 0.5)
			(thermal_bridge_width 0.5)
			(island_removal_mode 0)
		)
		(polygon
			(pts
				(arc
					(start 378.23267 -243.108988)
					(mid 377.57989 -243.108988)
					(end 378.23267 -243.108988)
				)
			)
		)
	)
	(zone
		(layers "B.Cu" "In6.Cu" "In11.Cu" "In13.Cu" "In15.Cu")
		(hatch none 0.5)
		(connect_pads
			(clearance 0)
		)
		(min_thickness 0.25)
		(keepout
			(tracks not_allowed)
			(vias allowed)
			(pads allowed)
			(copperpour not_allowed)
			(footprints allowed)
		)
		(placement
			(enabled no)
			(sheetname "")
		)
		(fill yes
			(thermal_gap 0.5)
			(thermal_bridge_width 0.5)
			(island_removal_mode 0)
		)
		(polygon
			(pts
				(arc
					(start 284.243272 -267.016738)
					(mid 283.590492 -267.016738)
					(end 284.243272 -267.016738)
				)
			)
		)
	)
	(zone
		(layers "B.Cu" "In6.Cu" "In11.Cu" "In13.Cu" "In15.Cu")
		(hatch none 0.5)
		(connect_pads
			(clearance 0)
		)
		(min_thickness 0.25)
		(keepout
			(tracks not_allowed)
			(vias allowed)
			(pads allowed)
			(copperpour not_allowed)
			(footprints allowed)
		)
		(placement
			(enabled no)
			(sheetname "")
		)
		(fill yes
			(thermal_gap 0.5)
			(thermal_bridge_width 0.5)
			(island_removal_mode 0)
		)
		(polygon
			(pts
				(arc
					(start 440.250072 -261.916672)
					(mid 439.597292 -261.916672)
					(end 440.250072 -261.916672)
				)
			)
		)
	)
	(zone
		(layers "B.Cu" "In6.Cu" "In11.Cu" "In13.Cu" "In15.Cu")
		(hatch none 0.5)
		(connect_pads
			(clearance 0)
		)
		(min_thickness 0.25)
		(keepout
			(tracks not_allowed)
			(vias allowed)
			(pads allowed)
			(copperpour not_allowed)
			(footprints allowed)
		)
		(placement
			(enabled no)
			(sheetname "")
		)
		(fill yes
			(thermal_gap 0.5)
			(thermal_bridge_width 0.5)
			(island_removal_mode 0)
		)
		(polygon
			(pts
				(arc
					(start 94.690184 -262.872474)
					(mid 94.037404 -262.872474)
					(end 94.690184 -262.872474)
				)
			)
		)
	)
	(zone
		(layers "B.Cu" "In6.Cu" "In11.Cu" "In13.Cu" "In15.Cu")
		(hatch none 0.5)
		(connect_pads
			(clearance 0)
		)
		(min_thickness 0.25)
		(keepout
			(tracks not_allowed)
			(vias allowed)
			(pads allowed)
			(copperpour not_allowed)
			(footprints allowed)
		)
		(placement
			(enabled no)
			(sheetname "")
		)
		(fill yes
			(thermal_gap 0.5)
			(thermal_bridge_width 0.5)
			(island_removal_mode 0)
		)
		(polygon
			(pts
				(arc
					(start 341.690452 -277.522432)
					(mid 341.037672 -277.522432)
					(end 341.690452 -277.522432)
				)
			)
		)
	)
	(zone
		(layers "B.Cu" "In6.Cu" "In11.Cu" "In13.Cu" "In15.Cu")
		(hatch none 0.5)
		(connect_pads
			(clearance 0)
		)
		(min_thickness 0.25)
		(keepout
			(tracks not_allowed)
			(vias allowed)
			(pads allowed)
			(copperpour not_allowed)
			(footprints allowed)
		)
		(placement
			(enabled no)
			(sheetname "")
		)
		(fill yes
			(thermal_gap 0.5)
			(thermal_bridge_width 0.5)
			(island_removal_mode 0)
		)
		(polygon
			(pts
				(arc
					(start 91.870784 -267.755878)
					(mid 91.218004 -267.755878)
					(end 91.870784 -267.755878)
				)
			)
		)
	)
	(zone
		(layers "B.Cu" "In6.Cu" "In11.Cu" "In13.Cu" "In15.Cu")
		(hatch none 0.5)
		(connect_pads
			(clearance 0)
		)
		(min_thickness 0.25)
		(keepout
			(tracks not_allowed)
			(vias allowed)
			(pads allowed)
			(copperpour not_allowed)
			(footprints allowed)
		)
		(placement
			(enabled no)
			(sheetname "")
		)
		(fill yes
			(thermal_gap 0.5)
			(thermal_bridge_width 0.5)
			(island_removal_mode 0)
		)
		(polygon
			(pts
				(arc
					(start 242.66017 -52.90185)
					(mid 241.95659 -52.90185)
					(end 242.66017 -52.90185)
				)
			)
		)
	)
	(zone
		(layers "B.Cu" "In6.Cu" "In11.Cu" "In13.Cu" "In15.Cu")
		(hatch none 0.5)
		(connect_pads
			(clearance 0)
		)
		(min_thickness 0.25)
		(keepout
			(tracks not_allowed)
			(vias allowed)
			(pads allowed)
			(copperpour not_allowed)
			(footprints allowed)
		)
		(placement
			(enabled no)
			(sheetname "")
		)
		(fill yes
			(thermal_gap 0.5)
			(thermal_bridge_width 0.5)
			(island_removal_mode 0)
		)
		(polygon
			(pts
				(arc
					(start 378.23267 -238.225584)
					(mid 377.57989 -238.225584)
					(end 378.23267 -238.225584)
				)
			)
		)
	)
	(zone
		(layers "B.Cu" "In6.Cu" "In11.Cu" "In13.Cu" "In15.Cu")
		(hatch none 0.5)
		(connect_pads
			(clearance 0)
		)
		(min_thickness 0.25)
		(keepout
			(tracks not_allowed)
			(vias allowed)
			(pads allowed)
			(copperpour not_allowed)
			(footprints allowed)
		)
		(placement
			(enabled no)
			(sheetname "")
		)
		(fill yes
			(thermal_gap 0.5)
			(thermal_bridge_width 0.5)
			(island_removal_mode 0)
		)
		(polygon
			(pts
				(arc
					(start 32.203136 -291.666676)
					(mid 31.550356 -291.666676)
					(end 32.203136 -291.666676)
				)
			)
		)
	)
	(zone
		(layers "B.Cu" "In6.Cu" "In11.Cu" "In13.Cu" "In15.Cu")
		(hatch none 0.5)
		(connect_pads
			(clearance 0)
		)
		(min_thickness 0.25)
		(keepout
			(tracks not_allowed)
			(vias allowed)
			(pads allowed)
			(copperpour not_allowed)
			(footprints allowed)
		)
		(placement
			(enabled no)
			(sheetname "")
		)
		(fill yes
			(thermal_gap 0.5)
			(thermal_bridge_width 0.5)
			(island_removal_mode 0)
		)
		(polygon
			(pts
				(arc
					(start 51.416204 -284.016958)
					(mid 50.763424 -284.016958)
					(end 51.416204 -284.016958)
				)
			)
		)
	)
	(zone
		(layers "B.Cu" "In6.Cu" "In11.Cu" "In13.Cu" "In15.Cu")
		(hatch none 0.5)
		(connect_pads
			(clearance 0)
		)
		(min_thickness 0.25)
		(keepout
			(tracks not_allowed)
			(vias allowed)
			(pads allowed)
			(copperpour not_allowed)
			(footprints allowed)
		)
		(placement
			(enabled no)
			(sheetname "")
		)
		(fill yes
			(thermal_gap 0.5)
			(thermal_bridge_width 0.5)
			(island_removal_mode 0)
		)
		(polygon
			(pts
				(arc
					(start 355.67747 -217.064336)
					(mid 355.02469 -217.064336)
					(end 355.67747 -217.064336)
				)
			)
		)
	)
	(zone
		(layers "B.Cu" "In6.Cu" "In11.Cu" "In13.Cu" "In15.Cu")
		(hatch none 0.5)
		(connect_pads
			(clearance 0)
		)
		(min_thickness 0.25)
		(keepout
			(tracks not_allowed)
			(vias allowed)
			(pads allowed)
			(copperpour not_allowed)
			(footprints allowed)
		)
		(placement
			(enabled no)
			(sheetname "")
		)
		(fill yes
			(thermal_gap 0.5)
			(thermal_bridge_width 0.5)
			(island_removal_mode 0)
		)
		(polygon
			(pts
				(arc
					(start 101.269038 -288.917126)
					(mid 100.616258 -288.917126)
					(end 101.269038 -288.917126)
				)
			)
		)
	)
	(zone
		(layers "B.Cu" "In6.Cu" "In11.Cu" "In13.Cu" "In15.Cu")
		(hatch none 0.5)
		(connect_pads
			(clearance 0)
		)
		(min_thickness 0.25)
		(keepout
			(tracks not_allowed)
			(vias allowed)
			(pads allowed)
			(copperpour not_allowed)
			(footprints allowed)
		)
		(placement
			(enabled no)
			(sheetname "")
		)
		(fill yes
			(thermal_gap 0.5)
			(thermal_bridge_width 0.5)
			(island_removal_mode 0)
		)
		(polygon
			(pts
				(arc
					(start 299.330872 -285.716726)
					(mid 298.678092 -285.716726)
					(end 299.330872 -285.716726)
				)
			)
		)
	)
	(zone
		(layers "B.Cu" "In6.Cu" "In11.Cu" "In13.Cu" "In15.Cu")
		(hatch none 0.5)
		(connect_pads
			(clearance 0)
		)
		(min_thickness 0.25)
		(keepout
			(tracks not_allowed)
			(vias allowed)
			(pads allowed)
			(copperpour not_allowed)
			(footprints allowed)
		)
		(placement
			(enabled no)
			(sheetname "")
		)
		(fill yes
			(thermal_gap 0.5)
			(thermal_bridge_width 0.5)
			(island_removal_mode 0)
		)
		(polygon
			(pts
				(arc
					(start 92.810584 -269.38351)
					(mid 92.157804 -269.38351)
					(end 92.810584 -269.38351)
				)
			)
		)
	)
	(zone
		(layers "B.Cu" "In6.Cu" "In11.Cu" "In13.Cu" "In15.Cu")
		(hatch none 0.5)
		(connect_pads
			(clearance 0)
		)
		(min_thickness 0.25)
		(keepout
			(tracks not_allowed)
			(vias allowed)
			(pads allowed)
			(copperpour not_allowed)
			(footprints allowed)
		)
		(placement
			(enabled no)
			(sheetname "")
		)
		(fill yes
			(thermal_gap 0.5)
			(thermal_bridge_width 0.5)
			(island_removal_mode 0)
		)
		(polygon
			(pts
				(arc
					(start 128.883156 -217.878406)
					(mid 128.230376 -217.878406)
					(end 128.883156 -217.878406)
				)
			)
		)
	)
	(zone
		(layers "B.Cu" "In6.Cu" "In11.Cu" "In13.Cu" "In15.Cu")
		(hatch none 0.5)
		(connect_pads
			(clearance 0)
		)
		(min_thickness 0.25)
		(keepout
			(tracks not_allowed)
			(vias allowed)
			(pads allowed)
			(copperpour not_allowed)
			(footprints allowed)
		)
		(placement
			(enabled no)
			(sheetname "")
		)
		(fill yes
			(thermal_gap 0.5)
			(thermal_bridge_width 0.5)
			(island_removal_mode 0)
		)
		(polygon
			(pts
				(arc
					(start 128.523238 -288.917126)
					(mid 127.870458 -288.917126)
					(end 128.523238 -288.917126)
				)
			)
		)
	)
	(zone
		(layers "B.Cu" "In6.Cu" "In11.Cu" "In13.Cu" "In15.Cu")
		(hatch none 0.5)
		(connect_pads
			(clearance 0)
		)
		(min_thickness 0.25)
		(keepout
			(tracks not_allowed)
			(vias allowed)
			(pads allowed)
			(copperpour not_allowed)
			(footprints allowed)
		)
		(placement
			(enabled no)
			(sheetname "")
		)
		(fill yes
			(thermal_gap 0.5)
			(thermal_bridge_width 0.5)
			(island_removal_mode 0)
		)
		(polygon
			(pts
				(arc
					(start 103.508556 -217.878406)
					(mid 102.855776 -217.878406)
					(end 103.508556 -217.878406)
				)
			)
		)
	)
	(zone
		(layers "B.Cu" "In6.Cu" "In11.Cu" "In13.Cu" "In15.Cu")
		(hatch none 0.5)
		(connect_pads
			(clearance 0)
		)
		(min_thickness 0.25)
		(keepout
			(tracks not_allowed)
			(vias allowed)
			(pads allowed)
			(copperpour not_allowed)
			(footprints allowed)
		)
		(placement
			(enabled no)
			(sheetname "")
		)
		(fill yes
			(thermal_gap 0.5)
			(thermal_bridge_width 0.5)
			(island_removal_mode 0)
		)
		(polygon
			(pts
				(arc
					(start 98.919538 -288.103056)
					(mid 98.266758 -288.103056)
					(end 98.919538 -288.103056)
				)
			)
		)
	)
	(zone
		(layers "B.Cu" "In6.Cu" "In11.Cu" "In13.Cu" "In15.Cu")
		(hatch none 0.5)
		(connect_pads
			(clearance 0)
		)
		(min_thickness 0.25)
		(keepout
			(tracks not_allowed)
			(vias allowed)
			(pads allowed)
			(copperpour not_allowed)
			(footprints allowed)
		)
		(placement
			(enabled no)
			(sheetname "")
		)
		(fill yes
			(thermal_gap 0.5)
			(thermal_bridge_width 0.5)
			(island_removal_mode 0)
		)
		(polygon
			(pts
				(arc
					(start 36.303204 -210.916774)
					(mid 35.650424 -210.916774)
					(end 36.303204 -210.916774)
				)
			)
		)
	)
	(zone
		(layers "B.Cu" "In6.Cu" "In11.Cu" "In13.Cu" "In15.Cu")
		(hatch none 0.5)
		(connect_pads
			(clearance 0)
		)
		(min_thickness 0.25)
		(keepout
			(tracks not_allowed)
			(vias allowed)
			(pads allowed)
			(copperpour not_allowed)
			(footprints allowed)
		)
		(placement
			(enabled no)
			(sheetname "")
		)
		(fill yes
			(thermal_gap 0.5)
			(thermal_bridge_width 0.5)
			(island_removal_mode 0)
		)
		(polygon
			(pts
				(arc
					(start 336.991198 -288.917126)
					(mid 336.338418 -288.917126)
					(end 336.991198 -288.917126)
				)
			)
		)
	)
	(zone
		(layers "B.Cu" "In6.Cu" "In11.Cu" "In13.Cu" "In15.Cu")
		(hatch none 0.5)
		(connect_pads
			(clearance 0)
		)
		(min_thickness 0.25)
		(keepout
			(tracks not_allowed)
			(vias allowed)
			(pads allowed)
			(copperpour not_allowed)
			(footprints allowed)
		)
		(placement
			(enabled no)
			(sheetname "")
		)
		(fill yes
			(thermal_gap 0.5)
			(thermal_bridge_width 0.5)
			(island_removal_mode 0)
		)
		(polygon
			(pts
				(arc
					(start 425.162472 -298.466764)
					(mid 424.509692 -298.466764)
					(end 425.162472 -298.466764)
				)
			)
		)
	)
	(zone
		(layers "B.Cu" "In6.Cu" "In11.Cu" "In13.Cu" "In15.Cu")
		(hatch none 0.5)
		(connect_pads
			(clearance 0)
		)
		(min_thickness 0.25)
		(keepout
			(tracks not_allowed)
			(vias allowed)
			(pads allowed)
			(copperpour not_allowed)
			(footprints allowed)
		)
		(placement
			(enabled no)
			(sheetname "")
		)
		(fill yes
			(thermal_gap 0.5)
			(thermal_bridge_width 0.5)
			(island_removal_mode 0)
		)
		(polygon
			(pts
				(arc
					(start 188.209936 -262.766556)
					(mid 187.557156 -262.766556)
					(end 188.209936 -262.766556)
				)
			)
		)
	)
	(zone
		(layers "B.Cu" "In6.Cu" "In11.Cu" "In13.Cu" "In15.Cu")
		(hatch none 0.5)
		(connect_pads
			(clearance 0)
		)
		(min_thickness 0.25)
		(keepout
			(tracks not_allowed)
			(vias allowed)
			(pads allowed)
			(copperpour not_allowed)
			(footprints allowed)
		)
		(placement
			(enabled no)
			(sheetname "")
		)
		(fill yes
			(thermal_gap 0.5)
			(thermal_bridge_width 0.5)
			(island_removal_mode 0)
		)
		(polygon
			(pts
				(arc
					(start 421.062404 -224.516696)
					(mid 420.409624 -224.516696)
					(end 421.062404 -224.516696)
				)
			)
		)
	)
	(zone
		(layers "B.Cu" "In6.Cu" "In11.Cu" "In13.Cu" "In15.Cu")
		(hatch none 0.5)
		(connect_pads
			(clearance 0)
		)
		(min_thickness 0.25)
		(keepout
			(tracks not_allowed)
			(vias allowed)
			(pads allowed)
			(copperpour not_allowed)
			(footprints allowed)
		)
		(placement
			(enabled no)
			(sheetname "")
		)
		(fill yes
			(thermal_gap 0.5)
			(thermal_bridge_width 0.5)
			(island_removal_mode 0)
		)
		(polygon
			(pts
				(arc
					(start 284.243272 -237.266734)
					(mid 283.590492 -237.266734)
					(end 284.243272 -237.266734)
				)
			)
		)
	)
	(zone
		(layers "B.Cu" "In6.Cu" "In11.Cu" "In13.Cu" "In15.Cu")
		(hatch none 0.5)
		(connect_pads
			(clearance 0)
		)
		(min_thickness 0.25)
		(keepout
			(tracks not_allowed)
			(vias allowed)
			(pads allowed)
			(copperpour not_allowed)
			(footprints allowed)
		)
		(placement
			(enabled no)
			(sheetname "")
		)
		(fill yes
			(thermal_gap 0.5)
			(thermal_bridge_width 0.5)
			(island_removal_mode 0)
		)
		(polygon
			(pts
				(arc
					(start 131.702556 -242.294918)
					(mid 131.049776 -242.294918)
					(end 131.702556 -242.294918)
				)
			)
		)
	)
	(zone
		(layers "B.Cu" "In6.Cu" "In11.Cu" "In13.Cu" "In15.Cu")
		(hatch none 0.5)
		(connect_pads
			(clearance 0)
		)
		(min_thickness 0.25)
		(keepout
			(tracks not_allowed)
			(vias allowed)
			(pads allowed)
			(copperpour not_allowed)
			(footprints allowed)
		)
		(placement
			(enabled no)
			(sheetname "")
		)
		(fill yes
			(thermal_gap 0.5)
			(thermal_bridge_width 0.5)
			(island_removal_mode 0)
		)
		(polygon
			(pts
				(arc
					(start 372.59387 -217.064336)
					(mid 371.94109 -217.064336)
					(end 372.59387 -217.064336)
				)
			)
		)
	)
	(zone
		(layers "B.Cu" "In6.Cu" "In11.Cu" "In13.Cu" "In15.Cu")
		(hatch none 0.5)
		(connect_pads
			(clearance 0)
		)
		(min_thickness 0.25)
		(keepout
			(tracks not_allowed)
			(vias allowed)
			(pads allowed)
			(copperpour not_allowed)
			(footprints allowed)
		)
		(placement
			(enabled no)
			(sheetname "")
		)
		(fill yes
			(thermal_gap 0.5)
			(thermal_bridge_width 0.5)
			(island_removal_mode 0)
		)
		(polygon
			(pts
				(arc
					(start 192.310004 -289.11677)
					(mid 191.657224 -289.11677)
					(end 192.310004 -289.11677)
				)
			)
		)
	)
	(zone
		(layers "B.Cu" "In6.Cu" "In11.Cu" "In13.Cu" "In15.Cu")
		(hatch none 0.5)
		(connect_pads
			(clearance 0)
		)
		(min_thickness 0.25)
		(keepout
			(tracks not_allowed)
			(vias allowed)
			(pads allowed)
			(copperpour not_allowed)
			(footprints allowed)
		)
		(placement
			(enabled no)
			(sheetname "")
		)
		(fill yes
			(thermal_gap 0.5)
			(thermal_bridge_width 0.5)
			(island_removal_mode 0)
		)
		(polygon
			(pts
				(arc
					(start 130.292602 -241.481102)
					(mid 129.639822 -241.481102)
					(end 130.292602 -241.481102)
				)
			)
		)
	)
	(zone
		(layers "B.Cu" "In6.Cu" "In11.Cu" "In13.Cu" "In15.Cu")
		(hatch none 0.5)
		(connect_pads
			(clearance 0)
		)
		(min_thickness 0.25)
		(keepout
			(tracks not_allowed)
			(vias allowed)
			(pads allowed)
			(copperpour not_allowed)
			(footprints allowed)
		)
		(placement
			(enabled no)
			(sheetname "")
		)
		(fill yes
			(thermal_gap 0.5)
			(thermal_bridge_width 0.5)
			(island_removal_mode 0)
		)
		(polygon
			(pts
				(arc
					(start 130.762756 -234.15625)
					(mid 130.109976 -234.15625)
					(end 130.762756 -234.15625)
				)
			)
		)
	)
	(zone
		(layers "B.Cu" "In6.Cu" "In11.Cu" "In13.Cu" "In15.Cu")
		(hatch none 0.5)
		(connect_pads
			(clearance 0)
		)
		(min_thickness 0.25)
		(keepout
			(tracks not_allowed)
			(vias allowed)
			(pads allowed)
			(copperpour not_allowed)
			(footprints allowed)
		)
		(placement
			(enabled no)
			(sheetname "")
		)
		(fill yes
			(thermal_gap 0.5)
			(thermal_bridge_width 0.5)
			(island_removal_mode 0)
		)
		(polygon
			(pts
				(arc
					(start 92.810584 -254.733552)
					(mid 92.157804 -254.733552)
					(end 92.810584 -254.733552)
				)
			)
		)
	)
	(zone
		(layers "B.Cu" "In6.Cu" "In11.Cu" "In13.Cu" "In15.Cu")
		(hatch none 0.5)
		(connect_pads
			(clearance 0)
		)
		(min_thickness 0.25)
		(keepout
			(tracks not_allowed)
			(vias allowed)
			(pads allowed)
			(copperpour not_allowed)
			(footprints allowed)
		)
		(placement
			(enabled no)
			(sheetname "")
		)
		(fill yes
			(thermal_gap 0.5)
			(thermal_bridge_width 0.5)
			(island_removal_mode 0)
		)
		(polygon
			(pts
				(arc
					(start 368.474752 -289.807142)
					(mid 367.821972 -289.807142)
					(end 368.474752 -289.807142)
				)
			)
		)
	)
	(zone
		(layers "B.Cu" "In6.Cu" "In11.Cu" "In13.Cu" "In15.Cu")
		(hatch none 0.5)
		(connect_pads
			(clearance 0)
		)
		(min_thickness 0.25)
		(keepout
			(tracks not_allowed)
			(vias allowed)
			(pads allowed)
			(copperpour not_allowed)
			(footprints allowed)
		)
		(placement
			(enabled no)
			(sheetname "")
		)
		(fill yes
			(thermal_gap 0.5)
			(thermal_bridge_width 0.5)
			(island_removal_mode 0)
		)
		(polygon
			(pts
				(arc
					(start 92.340938 -263.686544)
					(mid 91.688158 -263.686544)
					(end 92.340938 -263.686544)
				)
			)
		)
	)
	(zone
		(layers "B.Cu" "In6.Cu" "In11.Cu" "In13.Cu" "In15.Cu")
		(hatch none 0.5)
		(connect_pads
			(clearance 0)
		)
		(min_thickness 0.25)
		(keepout
			(tracks not_allowed)
			(vias allowed)
			(pads allowed)
			(copperpour not_allowed)
			(footprints allowed)
		)
		(placement
			(enabled no)
			(sheetname "")
		)
		(fill yes
			(thermal_gap 0.5)
			(thermal_bridge_width 0.5)
			(island_removal_mode 0)
		)
		(polygon
			(pts
				(arc
					(start 92.230956 -229.272846)
					(mid 91.578176 -229.272846)
					(end 92.230956 -229.272846)
				)
			)
		)
	)
	(zone
		(layers "B.Cu" "In6.Cu" "In11.Cu" "In13.Cu" "In15.Cu")
		(hatch none 0.5)
		(connect_pads
			(clearance 0)
		)
		(min_thickness 0.25)
		(keepout
			(tracks not_allowed)
			(vias allowed)
			(pads allowed)
			(copperpour not_allowed)
			(footprints allowed)
		)
		(placement
			(enabled no)
			(sheetname "")
		)
		(fill yes
			(thermal_gap 0.5)
			(thermal_bridge_width 0.5)
			(island_removal_mode 0)
		)
		(polygon
			(pts
				(arc
					(start 342.160606 -268.569694)
					(mid 341.507826 -268.569694)
					(end 342.160606 -268.569694)
				)
			)
		)
	)
	(zone
		(layers "B.Cu" "In6.Cu" "In11.Cu" "In13.Cu" "In15.Cu")
		(hatch none 0.5)
		(connect_pads
			(clearance 0)
		)
		(min_thickness 0.25)
		(keepout
			(tracks not_allowed)
			(vias allowed)
			(pads allowed)
			(copperpour not_allowed)
			(footprints allowed)
		)
		(placement
			(enabled no)
			(sheetname "")
		)
		(fill yes
			(thermal_gap 0.5)
			(thermal_bridge_width 0.5)
			(island_removal_mode 0)
		)
		(polygon
			(pts
				(arc
					(start 101.158802 -218.692222)
					(mid 100.506022 -218.692222)
					(end 101.158802 -218.692222)
				)
			)
		)
	)
	(zone
		(layers "B.Cu" "In6.Cu" "In11.Cu" "In13.Cu" "In15.Cu")
		(hatch none 0.5)
		(connect_pads
			(clearance 0)
		)
		(min_thickness 0.25)
		(keepout
			(tracks not_allowed)
			(vias allowed)
			(pads allowed)
			(copperpour not_allowed)
			(footprints allowed)
		)
		(placement
			(enabled no)
			(sheetname "")
		)
		(fill yes
			(thermal_gap 0.5)
			(thermal_bridge_width 0.5)
			(island_removal_mode 0)
		)
		(polygon
			(pts
				(arc
					(start 127.473202 -247.992138)
					(mid 126.820422 -247.992138)
					(end 127.473202 -247.992138)
				)
			)
		)
	)
	(zone
		(layers "B.Cu" "In6.Cu" "In11.Cu" "In13.Cu" "In15.Cu")
		(hatch none 0.5)
		(connect_pads
			(clearance 0)
		)
		(min_thickness 0.25)
		(keepout
			(tracks not_allowed)
			(vias allowed)
			(pads allowed)
			(copperpour not_allowed)
			(footprints allowed)
		)
		(placement
			(enabled no)
			(sheetname "")
		)
		(fill yes
			(thermal_gap 0.5)
			(thermal_bridge_width 0.5)
			(island_removal_mode 0)
		)
		(polygon
			(pts
				(arc
					(start 372.233952 -289.807142)
					(mid 371.581172 -289.807142)
					(end 372.233952 -289.807142)
				)
			)
		)
	)
	(zone
		(layers "B.Cu" "In6.Cu" "In11.Cu" "In13.Cu" "In15.Cu")
		(hatch none 0.5)
		(connect_pads
			(clearance 0)
		)
		(min_thickness 0.25)
		(keepout
			(tracks not_allowed)
			(vias allowed)
			(pads allowed)
			(copperpour not_allowed)
			(footprints allowed)
		)
		(placement
			(enabled no)
			(sheetname "")
		)
		(fill yes
			(thermal_gap 0.5)
			(thermal_bridge_width 0.5)
			(island_removal_mode 0)
		)
		(polygon
			(pts
				(arc
					(start 284.243272 -307.816758)
					(mid 283.590492 -307.816758)
					(end 284.243272 -307.816758)
				)
			)
		)
	)
	(zone
		(layers "B.Cu" "In6.Cu" "In11.Cu" "In13.Cu" "In15.Cu")
		(hatch none 0.5)
		(connect_pads
			(clearance 0)
		)
		(min_thickness 0.25)
		(keepout
			(tracks not_allowed)
			(vias allowed)
			(pads allowed)
			(copperpour not_allowed)
			(footprints allowed)
		)
		(placement
			(enabled no)
			(sheetname "")
		)
		(fill yes
			(thermal_gap 0.5)
			(thermal_bridge_width 0.5)
			(island_removal_mode 0)
		)
		(polygon
			(pts
				(arc
					(start 177.222404 -279.766776)
					(mid 176.569624 -279.766776)
					(end 177.222404 -279.766776)
				)
			)
		)
	)
	(zone
		(layers "B.Cu" "In6.Cu" "In11.Cu" "In13.Cu" "In15.Cu")
		(hatch none 0.5)
		(connect_pads
			(clearance 0)
		)
		(min_thickness 0.25)
		(keepout
			(tracks not_allowed)
			(vias allowed)
			(pads allowed)
			(copperpour not_allowed)
			(footprints allowed)
		)
		(placement
			(enabled no)
			(sheetname "")
		)
		(fill yes
			(thermal_gap 0.5)
			(thermal_bridge_width 0.5)
			(island_removal_mode 0)
		)
		(polygon
			(pts
				(arc
					(start 344.39987 -217.064336)
					(mid 343.74709 -217.064336)
					(end 344.39987 -217.064336)
				)
			)
		)
	)
	(zone
		(layers "B.Cu" "In6.Cu" "In11.Cu" "In13.Cu" "In15.Cu")
		(hatch none 0.5)
		(connect_pads
			(clearance 0)
		)
		(min_thickness 0.25)
		(keepout
			(tracks not_allowed)
			(vias allowed)
			(pads allowed)
			(copperpour not_allowed)
			(footprints allowed)
		)
		(placement
			(enabled no)
			(sheetname "")
		)
		(fill yes
			(thermal_gap 0.5)
			(thermal_bridge_width 0.5)
			(island_removal_mode 0)
		)
		(polygon
			(pts
				(arc
					(start 339.70087 -244.73662)
					(mid 339.04809 -244.73662)
					(end 339.70087 -244.73662)
				)
			)
		)
	)
	(zone
		(layers "B.Cu" "In6.Cu" "In11.Cu" "In13.Cu" "In15.Cu")
		(hatch none 0.5)
		(connect_pads
			(clearance 0)
		)
		(min_thickness 0.25)
		(keepout
			(tracks not_allowed)
			(vias allowed)
			(pads allowed)
			(copperpour not_allowed)
			(footprints allowed)
		)
		(placement
			(enabled no)
			(sheetname "")
		)
		(fill yes
			(thermal_gap 0.5)
			(thermal_bridge_width 0.5)
			(island_removal_mode 0)
		)
		(polygon
			(pts
				(arc
					(start 129.822956 -227.64496)
					(mid 129.170176 -227.64496)
					(end 129.822956 -227.64496)
				)
			)
		)
	)
	(zone
		(layers "B.Cu" "In6.Cu" "In11.Cu" "In13.Cu" "In15.Cu")
		(hatch none 0.5)
		(connect_pads
			(clearance 0)
		)
		(min_thickness 0.25)
		(keepout
			(tracks not_allowed)
			(vias allowed)
			(pads allowed)
			(copperpour not_allowed)
			(footprints allowed)
		)
		(placement
			(enabled no)
			(sheetname "")
		)
		(fill yes
			(thermal_gap 0.5)
			(thermal_bridge_width 0.5)
			(island_removal_mode 0)
		)
		(polygon
			(pts
				(arc
					(start 192.310004 -234.716574)
					(mid 191.657224 -234.716574)
					(end 192.310004 -234.716574)
				)
			)
		)
	)
	(zone
		(layers "B.Cu" "In6.Cu" "In11.Cu" "In13.Cu" "In15.Cu")
		(hatch none 0.5)
		(connect_pads
			(clearance 0)
		)
		(min_thickness 0.25)
		(keepout
			(tracks not_allowed)
			(vias allowed)
			(pads allowed)
			(copperpour not_allowed)
			(footprints allowed)
		)
		(placement
			(enabled no)
			(sheetname "")
		)
		(fill yes
			(thermal_gap 0.5)
			(thermal_bridge_width 0.5)
			(island_removal_mode 0)
		)
		(polygon
			(pts
				(arc
					(start 378.812806 -263.686544)
					(mid 378.160026 -263.686544)
					(end 378.812806 -263.686544)
				)
			)
		)
	)
	(zone
		(layers "B.Cu" "In6.Cu" "In11.Cu" "In13.Cu" "In15.Cu")
		(hatch none 0.5)
		(connect_pads
			(clearance 0)
		)
		(min_thickness 0.25)
		(keepout
			(tracks not_allowed)
			(vias allowed)
			(pads allowed)
			(copperpour not_allowed)
			(footprints allowed)
		)
		(placement
			(enabled no)
			(sheetname "")
		)
		(fill yes
			(thermal_gap 0.5)
			(thermal_bridge_width 0.5)
			(island_removal_mode 0)
		)
		(polygon
			(pts
				(arc
					(start 335.47177 -226.017328)
					(mid 334.81899 -226.017328)
					(end 335.47177 -226.017328)
				)
			)
		)
	)
	(zone
		(layers "B.Cu" "In6.Cu" "In11.Cu" "In13.Cu" "In15.Cu")
		(hatch none 0.5)
		(connect_pads
			(clearance 0)
		)
		(min_thickness 0.25)
		(keepout
			(tracks not_allowed)
			(vias allowed)
			(pads allowed)
			(copperpour not_allowed)
			(footprints allowed)
		)
		(placement
			(enabled no)
			(sheetname "")
		)
		(fill yes
			(thermal_gap 0.5)
			(thermal_bridge_width 0.5)
			(island_removal_mode 0)
		)
		(polygon
			(pts
				(arc
					(start 28.759404 -244.916706)
					(mid 28.106624 -244.916706)
					(end 28.759404 -244.916706)
				)
			)
		)
	)
	(zone
		(layers "B.Cu" "In6.Cu" "In11.Cu" "In13.Cu" "In15.Cu")
		(hatch none 0.5)
		(connect_pads
			(clearance 0)
		)
		(min_thickness 0.25)
		(keepout
			(tracks not_allowed)
			(vias allowed)
			(pads allowed)
			(copperpour not_allowed)
			(footprints allowed)
		)
		(placement
			(enabled no)
			(sheetname "")
		)
		(fill yes
			(thermal_gap 0.5)
			(thermal_bridge_width 0.5)
			(island_removal_mode 0)
		)
		(polygon
			(pts
				(arc
					(start 47.290736 -284.016704)
					(mid 46.637956 -284.016704)
					(end 47.290736 -284.016704)
				)
			)
		)
	)
	(zone
		(layers "B.Cu" "In6.Cu" "In11.Cu" "In13.Cu" "In15.Cu")
		(hatch none 0.5)
		(connect_pads
			(clearance 0)
		)
		(min_thickness 0.25)
		(keepout
			(tracks not_allowed)
			(vias allowed)
			(pads allowed)
			(copperpour not_allowed)
			(footprints allowed)
		)
		(placement
			(enabled no)
			(sheetname "")
		)
		(fill yes
			(thermal_gap 0.5)
			(thermal_bridge_width 0.5)
			(island_removal_mode 0)
		)
		(polygon
			(pts
				(arc
					(start 92.810584 -275.8948)
					(mid 92.157804 -275.8948)
					(end 92.810584 -275.8948)
				)
			)
		)
	)
	(zone
		(layers "B.Cu" "In6.Cu" "In11.Cu" "In13.Cu" "In15.Cu")
		(hatch none 0.5)
		(connect_pads
			(clearance 0)
		)
		(min_thickness 0.25)
		(keepout
			(tracks not_allowed)
			(vias allowed)
			(pads allowed)
			(copperpour not_allowed)
			(footprints allowed)
		)
		(placement
			(enabled no)
			(sheetname "")
		)
		(fill yes
			(thermal_gap 0.5)
			(thermal_bridge_width 0.5)
			(island_removal_mode 0)
		)
		(polygon
			(pts
				(arc
					(start 376.933206 -258.80314)
					(mid 376.280426 -258.80314)
					(end 376.933206 -258.80314)
				)
			)
		)
	)
	(zone
		(layers "B.Cu" "In6.Cu" "In11.Cu" "In13.Cu" "In15.Cu")
		(hatch none 0.5)
		(connect_pads
			(clearance 0)
		)
		(min_thickness 0.25)
		(keepout
			(tracks not_allowed)
			(vias allowed)
			(pads allowed)
			(copperpour not_allowed)
			(footprints allowed)
		)
		(placement
			(enabled no)
			(sheetname "")
		)
		(fill yes
			(thermal_gap 0.5)
			(thermal_bridge_width 0.5)
			(island_removal_mode 0)
		)
		(polygon
			(pts
				(arc
					(start 32.203136 -250.866656)
					(mid 31.550356 -250.866656)
					(end 32.203136 -250.866656)
				)
			)
		)
	)
	(zone
		(layers "B.Cu" "In6.Cu" "In11.Cu" "In13.Cu" "In15.Cu")
		(hatch none 0.5)
		(connect_pads
			(clearance 0)
		)
		(min_thickness 0.25)
		(keepout
			(tracks not_allowed)
			(vias allowed)
			(pads allowed)
			(copperpour not_allowed)
			(footprints allowed)
		)
		(placement
			(enabled no)
			(sheetname "")
		)
		(fill yes
			(thermal_gap 0.5)
			(thermal_bridge_width 0.5)
			(island_removal_mode 0)
		)
		(polygon
			(pts
				(arc
					(start 362.726224 -217.878406)
					(mid 362.073444 -217.878406)
					(end 362.726224 -217.878406)
				)
			)
		)
	)
	(zone
		(layers "B.Cu" "In6.Cu" "In11.Cu" "In13.Cu" "In15.Cu")
		(hatch none 0.5)
		(connect_pads
			(clearance 0)
		)
		(min_thickness 0.25)
		(keepout
			(tracks not_allowed)
			(vias allowed)
			(pads allowed)
			(copperpour not_allowed)
			(footprints allowed)
		)
		(placement
			(enabled no)
			(sheetname "")
		)
		(fill yes
			(thermal_gap 0.5)
			(thermal_bridge_width 0.5)
			(island_removal_mode 0)
		)
		(polygon
			(pts
				(arc
					(start 130.762756 -243.922804)
					(mid 130.109976 -243.922804)
					(end 130.762756 -243.922804)
				)
			)
		)
	)
	(zone
		(layers "B.Cu" "In6.Cu" "In11.Cu" "In13.Cu" "In15.Cu")
		(hatch none 0.5)
		(connect_pads
			(clearance 0)
		)
		(min_thickness 0.25)
		(keepout
			(tracks not_allowed)
			(vias allowed)
			(pads allowed)
			(copperpour not_allowed)
			(footprints allowed)
		)
		(placement
			(enabled no)
			(sheetname "")
		)
		(fill yes
			(thermal_gap 0.5)
			(thermal_bridge_width 0.5)
			(island_removal_mode 0)
		)
		(polygon
			(pts
				(arc
					(start 374.583706 -288.917126)
					(mid 373.930926 -288.917126)
					(end 374.583706 -288.917126)
				)
			)
		)
	)
	(zone
		(layers "B.Cu" "In6.Cu" "In11.Cu" "In13.Cu" "In15.Cu")
		(hatch none 0.5)
		(connect_pads
			(clearance 0)
		)
		(min_thickness 0.25)
		(keepout
			(tracks not_allowed)
			(vias allowed)
			(pads allowed)
			(copperpour not_allowed)
			(footprints allowed)
		)
		(placement
			(enabled no)
			(sheetname "")
		)
		(fill yes
			(thermal_gap 0.5)
			(thermal_bridge_width 0.5)
			(island_removal_mode 0)
		)
		(polygon
			(pts
				(arc
					(start 173.122336 -302.716692)
					(mid 172.469556 -302.716692)
					(end 173.122336 -302.716692)
				)
			)
		)
	)
	(zone
		(layers "B.Cu" "In6.Cu" "In11.Cu" "In13.Cu" "In15.Cu")
		(hatch none 0.5)
		(connect_pads
			(clearance 0)
		)
		(min_thickness 0.25)
		(keepout
			(tracks not_allowed)
			(vias allowed)
			(pads allowed)
			(copperpour not_allowed)
			(footprints allowed)
		)
		(placement
			(enabled no)
			(sheetname "")
		)
		(fill yes
			(thermal_gap 0.5)
			(thermal_bridge_width 0.5)
			(island_removal_mode 0)
		)
		(polygon
			(pts
				(arc
					(start 342.050624 -217.878406)
					(mid 341.397844 -217.878406)
					(end 342.050624 -217.878406)
				)
			)
		)
	)
	(zone
		(layers "B.Cu" "In6.Cu" "In11.Cu" "In13.Cu" "In15.Cu")
		(hatch none 0.5)
		(connect_pads
			(clearance 0)
		)
		(min_thickness 0.25)
		(keepout
			(tracks not_allowed)
			(vias allowed)
			(pads allowed)
			(copperpour not_allowed)
			(footprints allowed)
		)
		(placement
			(enabled no)
			(sheetname "")
		)
		(fill yes
			(thermal_gap 0.5)
			(thermal_bridge_width 0.5)
			(island_removal_mode 0)
		)
		(polygon
			(pts
				(arc
					(start 371.65407 -218.692222)
					(mid 371.00129 -218.692222)
					(end 371.65407 -218.692222)
				)
			)
		)
	)
	(zone
		(layers "B.Cu" "In6.Cu" "In11.Cu" "In13.Cu" "In15.Cu")
		(hatch none 0.5)
		(connect_pads
			(clearance 0)
		)
		(min_thickness 0.25)
		(keepout
			(tracks not_allowed)
			(vias allowed)
			(pads allowed)
			(copperpour not_allowed)
			(footprints allowed)
		)
		(placement
			(enabled no)
			(sheetname "")
		)
		(fill yes
			(thermal_gap 0.5)
			(thermal_bridge_width 0.5)
			(island_removal_mode 0)
		)
		(polygon
			(pts
				(arc
					(start 383.981706 -288.917126)
					(mid 383.328926 -288.917126)
					(end 383.981706 -288.917126)
				)
			)
		)
	)
	(zone
		(layers "B.Cu" "In6.Cu" "In11.Cu" "In13.Cu" "In15.Cu")
		(hatch none 0.5)
		(connect_pads
			(clearance 0)
		)
		(min_thickness 0.25)
		(keepout
			(tracks not_allowed)
			(vias allowed)
			(pads allowed)
			(copperpour not_allowed)
			(footprints allowed)
		)
		(placement
			(enabled no)
			(sheetname "")
		)
		(fill yes
			(thermal_gap 0.5)
			(thermal_bridge_width 0.5)
			(island_removal_mode 0)
		)
		(polygon
			(pts
				(arc
					(start 421.062404 -196.466714)
					(mid 420.409624 -196.466714)
					(end 421.062404 -196.466714)
				)
			)
		)
	)
	(zone
		(layers "B.Cu" "In6.Cu" "In11.Cu" "In13.Cu" "In15.Cu")
		(hatch none 0.5)
		(connect_pads
			(clearance 0)
		)
		(min_thickness 0.25)
		(keepout
			(tracks not_allowed)
			(vias allowed)
			(pads allowed)
			(copperpour not_allowed)
			(footprints allowed)
		)
		(placement
			(enabled no)
			(sheetname "")
		)
		(fill yes
			(thermal_gap 0.5)
			(thermal_bridge_width 0.5)
			(island_removal_mode 0)
		)
		(polygon
			(pts
				(arc
					(start 131.812538 -271.825212)
					(mid 131.159758 -271.825212)
					(end 131.812538 -271.825212)
				)
			)
		)
	)
	(zone
		(layers "B.Cu" "In6.Cu" "In11.Cu" "In13.Cu" "In15.Cu")
		(hatch none 0.5)
		(connect_pads
			(clearance 0)
		)
		(min_thickness 0.25)
		(keepout
			(tracks not_allowed)
			(vias allowed)
			(pads allowed)
			(copperpour not_allowed)
			(footprints allowed)
		)
		(placement
			(enabled no)
			(sheetname "")
		)
		(fill yes
			(thermal_gap 0.5)
			(thermal_bridge_width 0.5)
			(island_removal_mode 0)
		)
		(polygon
			(pts
				(arc
					(start 375.883424 -217.878406)
					(mid 375.230644 -217.878406)
					(end 375.883424 -217.878406)
				)
			)
		)
	)
	(zone
		(layers "B.Cu" "In6.Cu" "In11.Cu" "In13.Cu" "In15.Cu")
		(hatch none 0.5)
		(connect_pads
			(clearance 0)
		)
		(min_thickness 0.25)
		(keepout
			(tracks not_allowed)
			(vias allowed)
			(pads allowed)
			(copperpour not_allowed)
			(footprints allowed)
		)
		(placement
			(enabled no)
			(sheetname "")
		)
		(fill yes
			(thermal_gap 0.5)
			(thermal_bridge_width 0.5)
			(island_removal_mode 0)
		)
		(polygon
			(pts
				(arc
					(start 375.993152 -289.807142)
					(mid 375.340372 -289.807142)
					(end 375.993152 -289.807142)
				)
			)
		)
	)
	(zone
		(layers "B.Cu" "In6.Cu" "In11.Cu" "In13.Cu" "In15.Cu")
		(hatch none 0.5)
		(connect_pads
			(clearance 0)
		)
		(min_thickness 0.25)
		(keepout
			(tracks not_allowed)
			(vias allowed)
			(pads allowed)
			(copperpour not_allowed)
			(footprints allowed)
		)
		(placement
			(enabled no)
			(sheetname "")
		)
		(fill yes
			(thermal_gap 0.5)
			(thermal_bridge_width 0.5)
			(island_removal_mode 0)
		)
		(polygon
			(pts
				(arc
					(start 360.846624 -217.878406)
					(mid 360.193844 -217.878406)
					(end 360.846624 -217.878406)
				)
			)
		)
	)
	(zone
		(layers "B.Cu" "In6.Cu" "In11.Cu" "In13.Cu" "In15.Cu")
		(hatch none 0.5)
		(connect_pads
			(clearance 0)
		)
		(min_thickness 0.25)
		(keepout
			(tracks not_allowed)
			(vias allowed)
			(pads allowed)
			(copperpour not_allowed)
			(footprints allowed)
		)
		(placement
			(enabled no)
			(sheetname "")
		)
		(fill yes
			(thermal_gap 0.5)
			(thermal_bridge_width 0.5)
			(island_removal_mode 0)
		)
		(polygon
			(pts
				(arc
					(start 135.571738 -288.103056)
					(mid 134.918958 -288.103056)
					(end 135.571738 -288.103056)
				)
			)
		)
	)
	(zone
		(layers "B.Cu" "In6.Cu" "In11.Cu" "In13.Cu" "In15.Cu")
		(hatch none 0.5)
		(connect_pads
			(clearance 0)
		)
		(min_thickness 0.25)
		(keepout
			(tracks not_allowed)
			(vias allowed)
			(pads allowed)
			(copperpour not_allowed)
			(footprints allowed)
		)
		(placement
			(enabled no)
			(sheetname "")
		)
		(fill yes
			(thermal_gap 0.5)
			(thermal_bridge_width 0.5)
			(island_removal_mode 0)
		)
		(polygon
			(pts
				(arc
					(start 341.156798 5.031994)
					(mid 340.453218 5.031994)
					(end 341.156798 5.031994)
				)
			)
		)
	)
	(zone
		(layers "B.Cu" "In6.Cu" "In11.Cu" "In13.Cu" "In15.Cu")
		(hatch none 0.5)
		(connect_pads
			(clearance 0)
		)
		(min_thickness 0.25)
		(keepout
			(tracks not_allowed)
			(vias allowed)
			(pads allowed)
			(copperpour not_allowed)
			(footprints allowed)
		)
		(placement
			(enabled no)
			(sheetname "")
		)
		(fill yes
			(thermal_gap 0.5)
			(thermal_bridge_width 0.5)
			(island_removal_mode 0)
		)
		(polygon
			(pts
				(arc
					(start 342.990424 -217.878406)
					(mid 342.337644 -217.878406)
					(end 342.990424 -217.878406)
				)
			)
		)
	)
	(zone
		(layers "B.Cu" "In6.Cu" "In11.Cu" "In13.Cu" "In15.Cu")
		(hatch none 0.5)
		(connect_pads
			(clearance 0)
		)
		(min_thickness 0.25)
		(keepout
			(tracks not_allowed)
			(vias allowed)
			(pads allowed)
			(copperpour not_allowed)
			(footprints allowed)
		)
		(placement
			(enabled no)
			(sheetname "")
		)
		(fill yes
			(thermal_gap 0.5)
			(thermal_bridge_width 0.5)
			(island_removal_mode 0)
		)
		(polygon
			(pts
				(arc
					(start 340.281006 -278.336502)
					(mid 339.628226 -278.336502)
					(end 340.281006 -278.336502)
				)
			)
		)
	)
	(zone
		(layers "B.Cu" "In6.Cu" "In11.Cu" "In13.Cu" "In15.Cu")
		(hatch none 0.5)
		(connect_pads
			(clearance 0)
		)
		(min_thickness 0.25)
		(keepout
			(tracks not_allowed)
			(vias allowed)
			(pads allowed)
			(copperpour not_allowed)
			(footprints allowed)
		)
		(placement
			(enabled no)
			(sheetname "")
		)
		(fill yes
			(thermal_gap 0.5)
			(thermal_bridge_width 0.5)
			(island_removal_mode 0)
		)
		(polygon
			(pts
				(arc
					(start 341.690706 -288.917126)
					(mid 341.037926 -288.917126)
					(end 341.690706 -288.917126)
				)
			)
		)
	)
	(zone
		(layers "B.Cu" "In6.Cu" "In11.Cu" "In13.Cu" "In15.Cu")
		(hatch none 0.5)
		(connect_pads
			(clearance 0)
		)
		(min_thickness 0.25)
		(keepout
			(tracks not_allowed)
			(vias allowed)
			(pads allowed)
			(copperpour not_allowed)
			(footprints allowed)
		)
		(placement
			(enabled no)
			(sheetname "")
		)
		(fill yes
			(thermal_gap 0.5)
			(thermal_bridge_width 0.5)
			(island_removal_mode 0)
		)
		(polygon
			(pts
				(arc
					(start 367.425224 -217.878406)
					(mid 366.772444 -217.878406)
					(end 367.425224 -217.878406)
				)
			)
		)
	)
	(zone
		(layers "B.Cu" "In6.Cu" "In11.Cu" "In13.Cu" "In15.Cu")
		(hatch none 0.5)
		(connect_pads
			(clearance 0)
		)
		(min_thickness 0.25)
		(keepout
			(tracks not_allowed)
			(vias allowed)
			(pads allowed)
			(copperpour not_allowed)
			(footprints allowed)
		)
		(placement
			(enabled no)
			(sheetname "")
		)
		(fill yes
			(thermal_gap 0.5)
			(thermal_bridge_width 0.5)
			(island_removal_mode 0)
		)
		(polygon
			(pts
				(arc
					(start 377.402852 -257.98907)
					(mid 376.750072 -257.98907)
					(end 377.402852 -257.98907)
				)
			)
		)
	)
	(zone
		(layers "B.Cu" "In6.Cu" "In11.Cu" "In13.Cu" "In15.Cu")
		(hatch none 0.5)
		(connect_pads
			(clearance 0)
		)
		(min_thickness 0.25)
		(keepout
			(tracks not_allowed)
			(vias allowed)
			(pads allowed)
			(copperpour not_allowed)
			(footprints allowed)
		)
		(placement
			(enabled no)
			(sheetname "")
		)
		(fill yes
			(thermal_gap 0.5)
			(thermal_bridge_width 0.5)
			(island_removal_mode 0)
		)
		(polygon
			(pts
				(arc
					(start 343.570306 -288.917126)
					(mid 342.917526 -288.917126)
					(end 343.570306 -288.917126)
				)
			)
		)
	)
	(zone
		(layers "B.Cu" "In6.Cu" "In11.Cu" "In13.Cu" "In15.Cu")
		(hatch none 0.5)
		(connect_pads
			(clearance 0)
		)
		(min_thickness 0.25)
		(keepout
			(tracks not_allowed)
			(vias allowed)
			(pads allowed)
			(copperpour not_allowed)
			(footprints allowed)
		)
		(placement
			(enabled no)
			(sheetname "")
		)
		(fill yes
			(thermal_gap 0.5)
			(thermal_bridge_width 0.5)
			(island_removal_mode 0)
		)
		(polygon
			(pts
				(arc
					(start 131.702556 -243.922804)
					(mid 131.049776 -243.922804)
					(end 131.702556 -243.922804)
				)
			)
		)
	)
	(zone
		(layers "B.Cu" "In6.Cu" "In11.Cu" "In13.Cu" "In15.Cu")
		(hatch none 0.5)
		(connect_pads
			(clearance 0)
		)
		(min_thickness 0.25)
		(keepout
			(tracks not_allowed)
			(vias allowed)
			(pads allowed)
			(copperpour not_allowed)
			(footprints allowed)
		)
		(placement
			(enabled no)
			(sheetname "")
		)
		(fill yes
			(thermal_gap 0.5)
			(thermal_bridge_width 0.5)
			(island_removal_mode 0)
		)
		(polygon
			(pts
				(arc
					(start 344.980006 -288.103056)
					(mid 344.327226 -288.103056)
					(end 344.980006 -288.103056)
				)
			)
		)
	)
	(zone
		(layers "B.Cu" "In6.Cu" "In11.Cu" "In13.Cu" "In15.Cu")
		(hatch none 0.5)
		(connect_pads
			(clearance 0)
		)
		(min_thickness 0.25)
		(keepout
			(tracks not_allowed)
			(vias allowed)
			(pads allowed)
			(copperpour not_allowed)
			(footprints allowed)
		)
		(placement
			(enabled no)
			(sheetname "")
		)
		(fill yes
			(thermal_gap 0.5)
			(thermal_bridge_width 0.5)
			(island_removal_mode 0)
		)
		(polygon
			(pts
				(arc
					(start 421.062404 -286.56661)
					(mid 420.409624 -286.56661)
					(end 421.062404 -286.56661)
				)
			)
		)
	)
	(zone
		(layers "B.Cu" "In6.Cu" "In11.Cu" "In13.Cu" "In15.Cu")
		(hatch none 0.5)
		(connect_pads
			(clearance 0)
		)
		(min_thickness 0.25)
		(keepout
			(tracks not_allowed)
			(vias allowed)
			(pads allowed)
			(copperpour not_allowed)
			(footprints allowed)
		)
		(placement
			(enabled no)
			(sheetname "")
		)
		(fill yes
			(thermal_gap 0.5)
			(thermal_bridge_width 0.5)
			(island_removal_mode 0)
		)
		(polygon
			(pts
				(arc
					(start 341.58047 -218.692222)
					(mid 340.92769 -218.692222)
					(end 341.58047 -218.692222)
				)
			)
		)
	)
	(zone
		(layers "B.Cu" "In6.Cu" "In11.Cu" "In13.Cu" "In15.Cu")
		(hatch none 0.5)
		(connect_pads
			(clearance 0)
		)
		(min_thickness 0.25)
		(keepout
			(tracks not_allowed)
			(vias allowed)
			(pads allowed)
			(copperpour not_allowed)
			(footprints allowed)
		)
		(placement
			(enabled no)
			(sheetname "")
		)
		(fill yes
			(thermal_gap 0.5)
			(thermal_bridge_width 0.5)
			(island_removal_mode 0)
		)
		(polygon
			(pts
				(arc
					(start 86.122256 -223.575626)
					(mid 85.469476 -223.575626)
					(end 86.122256 -223.575626)
				)
			)
		)
	)
	(zone
		(layers "B.Cu" "In6.Cu" "In11.Cu" "In13.Cu" "In15.Cu")
		(hatch none 0.5)
		(connect_pads
			(clearance 0)
		)
		(min_thickness 0.25)
		(keepout
			(tracks not_allowed)
			(vias allowed)
			(pads allowed)
			(copperpour not_allowed)
			(footprints allowed)
		)
		(placement
			(enabled no)
			(sheetname "")
		)
		(fill yes
			(thermal_gap 0.5)
			(thermal_bridge_width 0.5)
			(island_removal_mode 0)
		)
		(polygon
			(pts
				(arc
					(start 192.310004 -208.366614)
					(mid 191.657224 -208.366614)
					(end 192.310004 -208.366614)
				)
			)
		)
	)
	(zone
		(layers "B.Cu" "In6.Cu" "In11.Cu" "In13.Cu" "In15.Cu")
		(hatch none 0.5)
		(connect_pads
			(clearance 0)
		)
		(min_thickness 0.25)
		(keepout
			(tracks not_allowed)
			(vias allowed)
			(pads allowed)
			(copperpour not_allowed)
			(footprints allowed)
		)
		(placement
			(enabled no)
			(sheetname "")
		)
		(fill yes
			(thermal_gap 0.5)
			(thermal_bridge_width 0.5)
			(island_removal_mode 0)
		)
		(polygon
			(pts
				(arc
					(start 131.702556 -235.783882)
					(mid 131.049776 -235.783882)
					(end 131.702556 -235.783882)
				)
			)
		)
	)
	(zone
		(layers "B.Cu" "In6.Cu" "In11.Cu" "In13.Cu" "In15.Cu")
		(hatch none 0.5)
		(connect_pads
			(clearance 0)
		)
		(min_thickness 0.25)
		(keepout
			(tracks not_allowed)
			(vias allowed)
			(pads allowed)
			(copperpour not_allowed)
			(footprints allowed)
		)
		(placement
			(enabled no)
			(sheetname "")
		)
		(fill yes
			(thermal_gap 0.5)
			(thermal_bridge_width 0.5)
			(island_removal_mode 0)
		)
		(polygon
			(pts
				(arc
					(start 350.148906 -288.917126)
					(mid 349.496126 -288.917126)
					(end 350.148906 -288.917126)
				)
			)
		)
	)
	(zone
		(layers "B.Cu" "In6.Cu" "In11.Cu" "In13.Cu" "In15.Cu")
		(hatch none 0.5)
		(connect_pads
			(clearance 0)
		)
		(min_thickness 0.25)
		(keepout
			(tracks not_allowed)
			(vias allowed)
			(pads allowed)
			(copperpour not_allowed)
			(footprints allowed)
		)
		(placement
			(enabled no)
			(sheetname "")
		)
		(fill yes
			(thermal_gap 0.5)
			(thermal_bridge_width 0.5)
			(island_removal_mode 0)
		)
		(polygon
			(pts
				(arc
					(start 341.58047 -246.364506)
					(mid 340.92769 -246.364506)
					(end 341.58047 -246.364506)
				)
			)
		)
	)
	(zone
		(layers "B.Cu" "In6.Cu" "In11.Cu" "In13.Cu" "In15.Cu")
		(hatch none 0.5)
		(connect_pads
			(clearance 0)
		)
		(min_thickness 0.25)
		(keepout
			(tracks not_allowed)
			(vias allowed)
			(pads allowed)
			(copperpour not_allowed)
			(footprints allowed)
		)
		(placement
			(enabled no)
			(sheetname "")
		)
		(fill yes
			(thermal_gap 0.5)
			(thermal_bridge_width 0.5)
			(island_removal_mode 0)
		)
		(polygon
			(pts
				(arc
					(start 32.203136 -210.066636)
					(mid 31.550356 -210.066636)
					(end 32.203136 -210.066636)
				)
			)
		)
	)
	(zone
		(layers "B.Cu" "In6.Cu" "In11.Cu" "In13.Cu" "In15.Cu")
		(hatch none 0.5)
		(connect_pads
			(clearance 0)
		)
		(min_thickness 0.25)
		(keepout
			(tracks not_allowed)
			(vias allowed)
			(pads allowed)
			(copperpour not_allowed)
			(footprints allowed)
		)
		(placement
			(enabled no)
			(sheetname "")
		)
		(fill yes
			(thermal_gap 0.5)
			(thermal_bridge_width 0.5)
			(island_removal_mode 0)
		)
		(polygon
			(pts
				(arc
					(start 340.281006 -276.708616)
					(mid 339.628226 -276.708616)
					(end 340.281006 -276.708616)
				)
			)
		)
	)
	(zone
		(layers "B.Cu" "In6.Cu" "In11.Cu" "In13.Cu" "In15.Cu")
		(hatch none 0.5)
		(connect_pads
			(clearance 0)
		)
		(min_thickness 0.25)
		(keepout
			(tracks not_allowed)
			(vias allowed)
			(pads allowed)
			(copperpour not_allowed)
			(footprints allowed)
		)
		(placement
			(enabled no)
			(sheetname "")
		)
		(fill yes
			(thermal_gap 0.5)
			(thermal_bridge_width 0.5)
			(island_removal_mode 0)
		)
		(polygon
			(pts
				(arc
					(start 130.872738 -268.569694)
					(mid 130.219958 -268.569694)
					(end 130.872738 -268.569694)
				)
			)
		)
	)
	(zone
		(layers "B.Cu" "In6.Cu" "In11.Cu" "In13.Cu" "In15.Cu")
		(hatch none 0.5)
		(connect_pads
			(clearance 0)
		)
		(min_thickness 0.25)
		(keepout
			(tracks not_allowed)
			(vias allowed)
			(pads allowed)
			(copperpour not_allowed)
			(footprints allowed)
		)
		(placement
			(enabled no)
			(sheetname "")
		)
		(fill yes
			(thermal_gap 0.5)
			(thermal_bridge_width 0.5)
			(island_removal_mode 0)
		)
		(polygon
			(pts
				(arc
					(start 280.143204 -210.066636)
					(mid 279.490424 -210.066636)
					(end 280.143204 -210.066636)
				)
			)
		)
	)
	(zone
		(layers "B.Cu" "In6.Cu" "In11.Cu" "In13.Cu" "In15.Cu")
		(hatch none 0.5)
		(connect_pads
			(clearance 0)
		)
		(min_thickness 0.25)
		(keepout
			(tracks not_allowed)
			(vias allowed)
			(pads allowed)
			(copperpour not_allowed)
			(footprints allowed)
		)
		(placement
			(enabled no)
			(sheetname "")
		)
		(fill yes
			(thermal_gap 0.5)
			(thermal_bridge_width 0.5)
			(island_removal_mode 0)
		)
		(polygon
			(pts
				(arc
					(start 295.230804 -303.566576)
					(mid 294.578024 -303.566576)
					(end 295.230804 -303.566576)
				)
			)
		)
	)
	(zone
		(layers "B.Cu" "In6.Cu" "In11.Cu" "In13.Cu" "In15.Cu")
		(hatch none 0.5)
		(connect_pads
			(clearance 0)
		)
		(min_thickness 0.25)
		(keepout
			(tracks not_allowed)
			(vias allowed)
			(pads allowed)
			(copperpour not_allowed)
			(footprints allowed)
		)
		(placement
			(enabled no)
			(sheetname "")
		)
		(fill yes
			(thermal_gap 0.5)
			(thermal_bridge_width 0.5)
			(island_removal_mode 0)
		)
		(polygon
			(pts
				(arc
					(start 98.339402 -217.064336)
					(mid 97.686622 -217.064336)
					(end 98.339402 -217.064336)
				)
			)
		)
	)
	(zone
		(layers "B.Cu" "In6.Cu" "In11.Cu" "In13.Cu" "In15.Cu")
		(hatch none 0.5)
		(connect_pads
			(clearance 0)
		)
		(min_thickness 0.25)
		(keepout
			(tracks not_allowed)
			(vias allowed)
			(pads allowed)
			(copperpour not_allowed)
			(footprints allowed)
		)
		(placement
			(enabled no)
			(sheetname "")
		)
		(fill yes
			(thermal_gap 0.5)
			(thermal_bridge_width 0.5)
			(island_removal_mode 0)
		)
		(polygon
			(pts
				(arc
					(start 188.209936 -211.766658)
					(mid 187.557156 -211.766658)
					(end 188.209936 -211.766658)
				)
			)
		)
	)
	(zone
		(layers "B.Cu" "In6.Cu" "In11.Cu" "In13.Cu" "In15.Cu")
		(hatch none 0.5)
		(connect_pads
			(clearance 0)
		)
		(min_thickness 0.25)
		(keepout
			(tracks not_allowed)
			(vias allowed)
			(pads allowed)
			(copperpour not_allowed)
			(footprints allowed)
		)
		(placement
			(enabled no)
			(sheetname "")
		)
		(fill yes
			(thermal_gap 0.5)
			(thermal_bridge_width 0.5)
			(island_removal_mode 0)
		)
		(polygon
			(pts
				(arc
					(start 47.290736 -200.716642)
					(mid 46.637956 -200.716642)
					(end 47.290736 -200.716642)
				)
			)
		)
	)
	(zone
		(layers "B.Cu" "In6.Cu" "In11.Cu" "In13.Cu" "In15.Cu")
		(hatch none 0.5)
		(connect_pads
			(clearance 0)
		)
		(min_thickness 0.25)
		(keepout
			(tracks not_allowed)
			(vias allowed)
			(pads allowed)
			(copperpour not_allowed)
			(footprints allowed)
		)
		(placement
			(enabled no)
			(sheetname "")
		)
		(fill yes
			(thermal_gap 0.5)
			(thermal_bridge_width 0.5)
			(island_removal_mode 0)
		)
		(polygon
			(pts
				(arc
					(start 369.884706 -288.917126)
					(mid 369.231926 -288.917126)
					(end 369.884706 -288.917126)
				)
			)
		)
	)
	(zone
		(layers "B.Cu" "In6.Cu" "In11.Cu" "In13.Cu" "In15.Cu")
		(hatch none 0.5)
		(connect_pads
			(clearance 0)
		)
		(min_thickness 0.25)
		(keepout
			(tracks not_allowed)
			(vias allowed)
			(pads allowed)
			(copperpour not_allowed)
			(footprints allowed)
		)
		(placement
			(enabled no)
			(sheetname "")
		)
		(fill yes
			(thermal_gap 0.5)
			(thermal_bridge_width 0.5)
			(island_removal_mode 0)
		)
		(polygon
			(pts
				(arc
					(start 340.750652 -275.8948)
					(mid 340.097872 -275.8948)
					(end 340.750652 -275.8948)
				)
			)
		)
	)
	(zone
		(layers "B.Cu" "In6.Cu" "In11.Cu" "In13.Cu" "In15.Cu")
		(hatch none 0.5)
		(connect_pads
			(clearance 0)
		)
		(min_thickness 0.25)
		(keepout
			(tracks not_allowed)
			(vias allowed)
			(pads allowed)
			(copperpour not_allowed)
			(footprints allowed)
		)
		(placement
			(enabled no)
			(sheetname "")
		)
		(fill yes
			(thermal_gap 0.5)
			(thermal_bridge_width 0.5)
			(island_removal_mode 0)
		)
		(polygon
			(pts
				(arc
					(start 436.150004 -297.616626)
					(mid 435.497224 -297.616626)
					(end 436.150004 -297.616626)
				)
			)
		)
	)
	(zone
		(layers "B.Cu" "In6.Cu" "In11.Cu" "In13.Cu" "In15.Cu")
		(hatch none 0.5)
		(connect_pads
			(clearance 0)
		)
		(min_thickness 0.25)
		(keepout
			(tracks not_allowed)
			(vias allowed)
			(pads allowed)
			(copperpour not_allowed)
			(footprints allowed)
		)
		(placement
			(enabled no)
			(sheetname "")
		)
		(fill yes
			(thermal_gap 0.5)
			(thermal_bridge_width 0.5)
			(island_removal_mode 0)
		)
		(polygon
			(pts
				(arc
					(start 339.70087 -230.086662)
					(mid 339.04809 -230.086662)
					(end 339.70087 -230.086662)
				)
			)
		)
	)
	(zone
		(layers "B.Cu" "In6.Cu" "In11.Cu" "In13.Cu" "In15.Cu")
		(hatch none 0.5)
		(connect_pads
			(clearance 0)
		)
		(min_thickness 0.25)
		(keepout
			(tracks not_allowed)
			(vias allowed)
			(pads allowed)
			(copperpour not_allowed)
			(footprints allowed)
		)
		(placement
			(enabled no)
			(sheetname "")
		)
		(fill yes
			(thermal_gap 0.5)
			(thermal_bridge_width 0.5)
			(island_removal_mode 0)
		)
		(polygon
			(pts
				(arc
					(start 369.304824 -217.878406)
					(mid 368.652044 -217.878406)
					(end 369.304824 -217.878406)
				)
			)
		)
	)
	(zone
		(layers "B.Cu" "In6.Cu" "In11.Cu" "In13.Cu" "In15.Cu")
		(hatch none 0.5)
		(connect_pads
			(clearance 0)
		)
		(min_thickness 0.25)
		(keepout
			(tracks not_allowed)
			(vias allowed)
			(pads allowed)
			(copperpour not_allowed)
			(footprints allowed)
		)
		(placement
			(enabled no)
			(sheetname "")
		)
		(fill yes
			(thermal_gap 0.5)
			(thermal_bridge_width 0.5)
			(island_removal_mode 0)
		)
		(polygon
			(pts
				(arc
					(start 280.143204 -237.266734)
					(mid 279.490424 -237.266734)
					(end 280.143204 -237.266734)
				)
			)
		)
	)
	(zone
		(layers "B.Cu" "In6.Cu" "In11.Cu" "In13.Cu" "In15.Cu")
		(hatch none 0.5)
		(connect_pads
			(clearance 0)
		)
		(min_thickness 0.25)
		(keepout
			(tracks not_allowed)
			(vias allowed)
			(pads allowed)
			(copperpour not_allowed)
			(footprints allowed)
		)
		(placement
			(enabled no)
			(sheetname "")
		)
		(fill yes
			(thermal_gap 0.5)
			(thermal_bridge_width 0.5)
			(island_removal_mode 0)
		)
		(polygon
			(pts
				(arc
					(start 128.053084 -289.807142)
					(mid 127.400304 -289.807142)
					(end 128.053084 -289.807142)
				)
			)
		)
	)
	(zone
		(layers "B.Cu" "In6.Cu" "In11.Cu" "In13.Cu" "In15.Cu")
		(hatch none 0.5)
		(connect_pads
			(clearance 0)
		)
		(min_thickness 0.25)
		(keepout
			(tracks not_allowed)
			(vias allowed)
			(pads allowed)
			(copperpour not_allowed)
			(footprints allowed)
		)
		(placement
			(enabled no)
			(sheetname "")
		)
		(fill yes
			(thermal_gap 0.5)
			(thermal_bridge_width 0.5)
			(island_removal_mode 0)
		)
		(polygon
			(pts
				(arc
					(start 47.290736 -288.266632)
					(mid 46.637956 -288.266632)
					(end 47.290736 -288.266632)
				)
			)
		)
	)
	(zone
		(layers "B.Cu" "In6.Cu" "In11.Cu" "In13.Cu" "In15.Cu")
		(hatch none 0.5)
		(connect_pads
			(clearance 0)
		)
		(min_thickness 0.25)
		(keepout
			(tracks not_allowed)
			(vias allowed)
			(pads allowed)
			(copperpour not_allowed)
			(footprints allowed)
		)
		(placement
			(enabled no)
			(sheetname "")
		)
		(fill yes
			(thermal_gap 0.5)
			(thermal_bridge_width 0.5)
			(island_removal_mode 0)
		)
		(polygon
			(pts
				(arc
					(start 106.327956 -217.878406)
					(mid 105.675176 -217.878406)
					(end 106.327956 -217.878406)
				)
			)
		)
	)
	(zone
		(layers "B.Cu" "In6.Cu" "In11.Cu" "In13.Cu" "In15.Cu")
		(hatch none 0.5)
		(connect_pads
			(clearance 0)
		)
		(min_thickness 0.25)
		(keepout
			(tracks not_allowed)
			(vias allowed)
			(pads allowed)
			(copperpour not_allowed)
			(footprints allowed)
		)
		(placement
			(enabled no)
			(sheetname "")
		)
		(fill yes
			(thermal_gap 0.5)
			(thermal_bridge_width 0.5)
			(island_removal_mode 0)
		)
		(polygon
			(pts
				(arc
					(start 447.793872 -267.016738)
					(mid 447.141092 -267.016738)
					(end 447.793872 -267.016738)
				)
			)
		)
	)
	(zone
		(layers "B.Cu" "In6.Cu" "In11.Cu" "In13.Cu" "In15.Cu")
		(hatch none 0.5)
		(connect_pads
			(clearance 0)
		)
		(min_thickness 0.25)
		(keepout
			(tracks not_allowed)
			(vias allowed)
			(pads allowed)
			(copperpour not_allowed)
			(footprints allowed)
		)
		(placement
			(enabled no)
			(sheetname "")
		)
		(fill yes
			(thermal_gap 0.5)
			(thermal_bridge_width 0.5)
			(island_removal_mode 0)
		)
		(polygon
			(pts
				(arc
					(start 341.690452 -272.639282)
					(mid 341.037672 -272.639282)
					(end 341.690452 -272.639282)
				)
			)
		)
	)
	(zone
		(layers "B.Cu" "In6.Cu" "In11.Cu" "In13.Cu" "In15.Cu")
		(hatch none 0.5)
		(connect_pads
			(clearance 0)
		)
		(min_thickness 0.25)
		(keepout
			(tracks not_allowed)
			(vias allowed)
			(pads allowed)
			(copperpour not_allowed)
			(footprints allowed)
		)
		(placement
			(enabled no)
			(sheetname "")
		)
		(fill yes
			(thermal_gap 0.5)
			(thermal_bridge_width 0.5)
			(island_removal_mode 0)
		)
		(polygon
			(pts
				(arc
					(start 94.110556 -239.0394)
					(mid 93.457776 -239.0394)
					(end 94.110556 -239.0394)
				)
			)
		)
	)
	(zone
		(layers "B.Cu" "In6.Cu" "In11.Cu" "In13.Cu" "In15.Cu")
		(hatch none 0.5)
		(connect_pads
			(clearance 0)
		)
		(min_thickness 0.25)
		(keepout
			(tracks not_allowed)
			(vias allowed)
			(pads allowed)
			(copperpour not_allowed)
			(footprints allowed)
		)
		(placement
			(enabled no)
			(sheetname "")
		)
		(fill yes
			(thermal_gap 0.5)
			(thermal_bridge_width 0.5)
			(island_removal_mode 0)
		)
		(polygon
			(pts
				(arc
					(start 36.303204 -250.016772)
					(mid 35.650424 -250.016772)
					(end 36.303204 -250.016772)
				)
			)
		)
	)
	(zone
		(layers "B.Cu" "In6.Cu" "In11.Cu" "In13.Cu" "In15.Cu")
		(hatch none 0.5)
		(connect_pads
			(clearance 0)
		)
		(min_thickness 0.25)
		(keepout
			(tracks not_allowed)
			(vias allowed)
			(pads allowed)
			(copperpour not_allowed)
			(footprints allowed)
		)
		(placement
			(enabled no)
			(sheetname "")
		)
		(fill yes
			(thermal_gap 0.5)
			(thermal_bridge_width 0.5)
			(island_removal_mode 0)
		)
		(polygon
			(pts
				(arc
					(start 378.23267 -246.364506)
					(mid 377.57989 -246.364506)
					(end 378.23267 -246.364506)
				)
			)
		)
	)
	(zone
		(layers "B.Cu" "In6.Cu" "In11.Cu" "In13.Cu" "In15.Cu")
		(hatch none 0.5)
		(connect_pads
			(clearance 0)
		)
		(min_thickness 0.25)
		(keepout
			(tracks not_allowed)
			(vias allowed)
			(pads allowed)
			(copperpour not_allowed)
			(footprints allowed)
		)
		(placement
			(enabled no)
			(sheetname "")
		)
		(fill yes
			(thermal_gap 0.5)
			(thermal_bridge_width 0.5)
			(island_removal_mode 0)
		)
		(polygon
			(pts
				(arc
					(start 377.29287 -226.831144)
					(mid 376.64009 -226.831144)
					(end 377.29287 -226.831144)
				)
			)
		)
	)
	(zone
		(layers "B.Cu" "In6.Cu" "In11.Cu" "In13.Cu" "In15.Cu")
		(hatch none 0.5)
		(connect_pads
			(clearance 0)
		)
		(min_thickness 0.25)
		(keepout
			(tracks not_allowed)
			(vias allowed)
			(pads allowed)
			(copperpour not_allowed)
			(footprints allowed)
		)
		(placement
			(enabled no)
			(sheetname "")
		)
		(fill yes
			(thermal_gap 0.5)
			(thermal_bridge_width 0.5)
			(island_removal_mode 0)
		)
		(polygon
			(pts
				(arc
					(start 299.356272 -298.466764)
					(mid 298.703492 -298.466764)
					(end 299.356272 -298.466764)
				)
			)
		)
	)
	(zone
		(layers "B.Cu" "In6.Cu" "In11.Cu" "In13.Cu" "In15.Cu")
		(hatch none 0.5)
		(connect_pads
			(clearance 0)
		)
		(min_thickness 0.25)
		(keepout
			(tracks not_allowed)
			(vias allowed)
			(pads allowed)
			(copperpour not_allowed)
			(footprints allowed)
		)
		(placement
			(enabled no)
			(sheetname "")
		)
		(fill yes
			(thermal_gap 0.5)
			(thermal_bridge_width 0.5)
			(island_removal_mode 0)
		)
		(polygon
			(pts
				(arc
					(start 440.250072 -295.06672)
					(mid 439.597292 -295.06672)
					(end 440.250072 -295.06672)
				)
			)
		)
	)
	(zone
		(layers "B.Cu" "In6.Cu" "In11.Cu" "In13.Cu" "In15.Cu")
		(hatch none 0.5)
		(connect_pads
			(clearance 0)
		)
		(min_thickness 0.25)
		(keepout
			(tracks not_allowed)
			(vias allowed)
			(pads allowed)
			(copperpour not_allowed)
			(footprints allowed)
		)
		(placement
			(enabled no)
			(sheetname "")
		)
		(fill yes
			(thermal_gap 0.5)
			(thermal_bridge_width 0.5)
			(island_removal_mode 0)
		)
		(polygon
			(pts
				(arc
					(start 93.640402 -233.34218)
					(mid 92.987622 -233.34218)
					(end 93.640402 -233.34218)
				)
			)
		)
	)
	(zone
		(layers "B.Cu" "In6.Cu" "In11.Cu" "In13.Cu" "In15.Cu")
		(hatch none 0.5)
		(connect_pads
			(clearance 0)
		)
		(min_thickness 0.25)
		(keepout
			(tracks not_allowed)
			(vias allowed)
			(pads allowed)
			(copperpour not_allowed)
			(footprints allowed)
		)
		(placement
			(enabled no)
			(sheetname "")
		)
		(fill yes
			(thermal_gap 0.5)
			(thermal_bridge_width 0.5)
			(island_removal_mode 0)
		)
		(polygon
			(pts
				(arc
					(start 436.150004 -205.816708)
					(mid 435.497224 -205.816708)
					(end 436.150004 -205.816708)
				)
			)
		)
	)
	(zone
		(layers "B.Cu" "In6.Cu" "In11.Cu" "In13.Cu" "In15.Cu")
		(hatch none 0.5)
		(connect_pads
			(clearance 0)
		)
		(min_thickness 0.25)
		(keepout
			(tracks not_allowed)
			(vias allowed)
			(pads allowed)
			(copperpour not_allowed)
			(footprints allowed)
		)
		(placement
			(enabled no)
			(sheetname "")
		)
		(fill yes
			(thermal_gap 0.5)
			(thermal_bridge_width 0.5)
			(island_removal_mode 0)
		)
		(polygon
			(pts
				(arc
					(start 343.46007 -218.692222)
					(mid 342.80729 -218.692222)
					(end 343.46007 -218.692222)
				)
			)
		)
	)
	(zone
		(layers "B.Cu" "In6.Cu" "In11.Cu" "In13.Cu" "In15.Cu")
		(hatch none 0.5)
		(connect_pads
			(clearance 0)
		)
		(min_thickness 0.25)
		(keepout
			(tracks not_allowed)
			(vias allowed)
			(pads allowed)
			(copperpour not_allowed)
			(footprints allowed)
		)
		(placement
			(enabled no)
			(sheetname "")
		)
		(fill yes
			(thermal_gap 0.5)
			(thermal_bridge_width 0.5)
			(island_removal_mode 0)
		)
		(polygon
			(pts
				(arc
					(start 340.64067 -246.364506)
					(mid 339.98789 -246.364506)
					(end 340.64067 -246.364506)
				)
			)
		)
	)
	(zone
		(layers "B.Cu" "In6.Cu" "In11.Cu" "In13.Cu" "In15.Cu")
		(hatch none 0.5)
		(connect_pads
			(clearance 0)
		)
		(min_thickness 0.25)
		(keepout
			(tracks not_allowed)
			(vias allowed)
			(pads allowed)
			(copperpour not_allowed)
			(footprints allowed)
		)
		(placement
			(enabled no)
			(sheetname "")
		)
		(fill yes
			(thermal_gap 0.5)
			(thermal_bridge_width 0.5)
			(island_removal_mode 0)
		)
		(polygon
			(pts
				(arc
					(start 280.143204 -259.366766)
					(mid 279.490424 -259.366766)
					(end 280.143204 -259.366766)
				)
			)
		)
	)
	(zone
		(layers "B.Cu" "In6.Cu" "In11.Cu" "In13.Cu" "In15.Cu")
		(hatch none 0.5)
		(connect_pads
			(clearance 0)
		)
		(min_thickness 0.25)
		(keepout
			(tracks not_allowed)
			(vias allowed)
			(pads allowed)
			(copperpour not_allowed)
			(footprints allowed)
		)
		(placement
			(enabled no)
			(sheetname "")
		)
		(fill yes
			(thermal_gap 0.5)
			(thermal_bridge_width 0.5)
			(island_removal_mode 0)
		)
		(polygon
			(pts
				(arc
					(start 375.053606 -257.175254)
					(mid 374.400826 -257.175254)
					(end 375.053606 -257.175254)
				)
			)
		)
	)
	(zone
		(layers "B.Cu" "In6.Cu" "In11.Cu" "In13.Cu" "In15.Cu")
		(hatch none 0.5)
		(connect_pads
			(clearance 0)
		)
		(min_thickness 0.25)
		(keepout
			(tracks not_allowed)
			(vias allowed)
			(pads allowed)
			(copperpour not_allowed)
			(footprints allowed)
		)
		(placement
			(enabled no)
			(sheetname "")
		)
		(fill yes
			(thermal_gap 0.5)
			(thermal_bridge_width 0.5)
			(island_removal_mode 0)
		)
		(polygon
			(pts
				(arc
					(start 91.870784 -262.872474)
					(mid 91.218004 -262.872474)
					(end 91.870784 -262.872474)
				)
			)
		)
	)
	(zone
		(layers "B.Cu" "In6.Cu" "In11.Cu" "In13.Cu" "In15.Cu")
		(hatch none 0.5)
		(connect_pads
			(clearance 0)
		)
		(min_thickness 0.25)
		(keepout
			(tracks not_allowed)
			(vias allowed)
			(pads allowed)
			(copperpour not_allowed)
			(footprints allowed)
		)
		(placement
			(enabled no)
			(sheetname "")
		)
		(fill yes
			(thermal_gap 0.5)
			(thermal_bridge_width 0.5)
			(island_removal_mode 0)
		)
		(polygon
			(pts
				(arc
					(start 379.752606 -262.058658)
					(mid 379.099826 -262.058658)
					(end 379.752606 -262.058658)
				)
			)
		)
	)
	(zone
		(layers "B.Cu" "In6.Cu" "In11.Cu" "In13.Cu" "In15.Cu")
		(hatch none 0.5)
		(connect_pads
			(clearance 0)
		)
		(min_thickness 0.25)
		(keepout
			(tracks not_allowed)
			(vias allowed)
			(pads allowed)
			(copperpour not_allowed)
			(footprints allowed)
		)
		(placement
			(enabled no)
			(sheetname "")
		)
		(fill yes
			(thermal_gap 0.5)
			(thermal_bridge_width 0.5)
			(island_removal_mode 0)
		)
		(polygon
			(pts
				(arc
					(start 342.160606 -262.058658)
					(mid 341.507826 -262.058658)
					(end 342.160606 -262.058658)
				)
			)
		)
	)
	(zone
		(layers "B.Cu" "In6.Cu" "In11.Cu" "In13.Cu" "In15.Cu")
		(hatch none 0.5)
		(connect_pads
			(clearance 0)
		)
		(min_thickness 0.25)
		(keepout
			(tracks not_allowed)
			(vias allowed)
			(pads allowed)
			(copperpour not_allowed)
			(footprints allowed)
		)
		(placement
			(enabled no)
			(sheetname "")
		)
		(fill yes
			(thermal_gap 0.5)
			(thermal_bridge_width 0.5)
			(island_removal_mode 0)
		)
		(polygon
			(pts
				(arc
					(start 380.11227 -246.364506)
					(mid 379.45949 -246.364506)
					(end 380.11227 -246.364506)
				)
			)
		)
	)
	(zone
		(layers "B.Cu" "In6.Cu" "In11.Cu" "In13.Cu" "In15.Cu")
		(hatch none 0.5)
		(connect_pads
			(clearance 0)
		)
		(min_thickness 0.25)
		(keepout
			(tracks not_allowed)
			(vias allowed)
			(pads allowed)
			(copperpour not_allowed)
			(footprints allowed)
		)
		(placement
			(enabled no)
			(sheetname "")
		)
		(fill yes
			(thermal_gap 0.5)
			(thermal_bridge_width 0.5)
			(island_removal_mode 0)
		)
		(polygon
			(pts
				(arc
					(start 295.230804 -306.96662)
					(mid 294.578024 -306.96662)
					(end 295.230804 -306.96662)
				)
			)
		)
	)
	(zone
		(layers "B.Cu" "In6.Cu" "In11.Cu" "In13.Cu" "In15.Cu")
		(hatch none 0.5)
		(connect_pads
			(clearance 0)
		)
		(min_thickness 0.25)
		(keepout
			(tracks not_allowed)
			(vias allowed)
			(pads allowed)
			(copperpour not_allowed)
			(footprints allowed)
		)
		(placement
			(enabled no)
			(sheetname "")
		)
		(fill yes
			(thermal_gap 0.5)
			(thermal_bridge_width 0.5)
			(island_removal_mode 0)
		)
		(polygon
			(pts
				(arc
					(start 177.222404 -225.36658)
					(mid 176.569624 -225.36658)
					(end 177.222404 -225.36658)
				)
			)
		)
	)
	(zone
		(layers "B.Cu" "In6.Cu" "In11.Cu" "In13.Cu" "In15.Cu")
		(hatch none 0.5)
		(connect_pads
			(clearance 0)
		)
		(min_thickness 0.25)
		(keepout
			(tracks not_allowed)
			(vias allowed)
			(pads allowed)
			(copperpour not_allowed)
			(footprints allowed)
		)
		(placement
			(enabled no)
			(sheetname "")
		)
		(fill yes
			(thermal_gap 0.5)
			(thermal_bridge_width 0.5)
			(island_removal_mode 0)
		)
		(polygon
			(pts
				(arc
					(start 130.292602 -243.108988)
					(mid 129.639822 -243.108988)
					(end 130.292602 -243.108988)
				)
			)
		)
	)
	(zone
		(layers "B.Cu" "In6.Cu" "In11.Cu" "In13.Cu" "In15.Cu")
		(hatch none 0.5)
		(connect_pads
			(clearance 0)
		)
		(min_thickness 0.25)
		(keepout
			(tracks not_allowed)
			(vias allowed)
			(pads allowed)
			(copperpour not_allowed)
			(footprints allowed)
		)
		(placement
			(enabled no)
			(sheetname "")
		)
		(fill yes
			(thermal_gap 0.5)
			(thermal_bridge_width 0.5)
			(island_removal_mode 0)
		)
		(polygon
			(pts
				(arc
					(start 132.371846 -10.243312)
					(mid 131.668266 -10.243312)
					(end 132.371846 -10.243312)
				)
			)
		)
	)
	(zone
		(layers "B.Cu" "In6.Cu" "In11.Cu" "In13.Cu" "In15.Cu")
		(hatch none 0.5)
		(connect_pads
			(clearance 0)
		)
		(min_thickness 0.25)
		(keepout
			(tracks not_allowed)
			(vias allowed)
			(pads allowed)
			(copperpour not_allowed)
			(footprints allowed)
		)
		(placement
			(enabled no)
			(sheetname "")
		)
		(fill yes
			(thermal_gap 0.5)
			(thermal_bridge_width 0.5)
			(island_removal_mode 0)
		)
		(polygon
			(pts
				(arc
					(start 340.281006 -258.80314)
					(mid 339.628226 -258.80314)
					(end 340.281006 -258.80314)
				)
			)
		)
	)
	(zone
		(layers "B.Cu" "In6.Cu" "In11.Cu" "In13.Cu" "In15.Cu")
		(hatch none 0.5)
		(connect_pads
			(clearance 0)
		)
		(min_thickness 0.25)
		(keepout
			(tracks not_allowed)
			(vias allowed)
			(pads allowed)
			(copperpour not_allowed)
			(footprints allowed)
		)
		(placement
			(enabled no)
			(sheetname "")
		)
		(fill yes
			(thermal_gap 0.5)
			(thermal_bridge_width 0.5)
			(island_removal_mode 0)
		)
		(polygon
			(pts
				(arc
					(start 98.809556 -217.878406)
					(mid 98.156776 -217.878406)
					(end 98.809556 -217.878406)
				)
			)
		)
	)
	(zone
		(layers "B.Cu" "In6.Cu" "In11.Cu" "In13.Cu" "In15.Cu")
		(hatch none 0.5)
		(connect_pads
			(clearance 0)
		)
		(min_thickness 0.25)
		(keepout
			(tracks not_allowed)
			(vias allowed)
			(pads allowed)
			(copperpour not_allowed)
			(footprints allowed)
		)
		(placement
			(enabled no)
			(sheetname "")
		)
		(fill yes
			(thermal_gap 0.5)
			(thermal_bridge_width 0.5)
			(island_removal_mode 0)
		)
		(polygon
			(pts
				(arc
					(start 47.290736 -226.216718)
					(mid 46.637956 -226.216718)
					(end 47.290736 -226.216718)
				)
			)
		)
	)
	(zone
		(layers "B.Cu" "In6.Cu" "In11.Cu" "In13.Cu" "In15.Cu")
		(hatch none 0.5)
		(connect_pads
			(clearance 0)
		)
		(min_thickness 0.25)
		(keepout
			(tracks not_allowed)
			(vias allowed)
			(pads allowed)
			(copperpour not_allowed)
			(footprints allowed)
		)
		(placement
			(enabled no)
			(sheetname "")
		)
		(fill yes
			(thermal_gap 0.5)
			(thermal_bridge_width 0.5)
			(island_removal_mode 0)
		)
		(polygon
			(pts
				(arc
					(start 365.545624 -217.878406)
					(mid 364.892844 -217.878406)
					(end 365.545624 -217.878406)
				)
			)
		)
	)
	(zone
		(layers "B.Cu" "In6.Cu" "In11.Cu" "In13.Cu" "In15.Cu")
		(hatch none 0.5)
		(connect_pads
			(clearance 0)
		)
		(min_thickness 0.25)
		(keepout
			(tracks not_allowed)
			(vias allowed)
			(pads allowed)
			(copperpour not_allowed)
			(footprints allowed)
		)
		(placement
			(enabled no)
			(sheetname "")
		)
		(fill yes
			(thermal_gap 0.5)
			(thermal_bridge_width 0.5)
			(island_removal_mode 0)
		)
		(polygon
			(pts
				(arc
					(start 339.70087 -239.853216)
					(mid 339.04809 -239.853216)
					(end 339.70087 -239.853216)
				)
			)
		)
	)
	(zone
		(layers "B.Cu" "In6.Cu" "In11.Cu" "In13.Cu" "In15.Cu")
		(hatch none 0.5)
		(connect_pads
			(clearance 0)
		)
		(min_thickness 0.25)
		(keepout
			(tracks not_allowed)
			(vias allowed)
			(pads allowed)
			(copperpour not_allowed)
			(footprints allowed)
		)
		(placement
			(enabled no)
			(sheetname "")
		)
		(fill yes
			(thermal_gap 0.5)
			(thermal_bridge_width 0.5)
			(island_removal_mode 0)
		)
		(polygon
			(pts
				(arc
					(start 133.112002 -218.692222)
					(mid 132.459222 -218.692222)
					(end 133.112002 -218.692222)
				)
			)
		)
	)
	(zone
		(layers "B.Cu" "In6.Cu" "In11.Cu" "In13.Cu" "In15.Cu")
		(hatch none 0.5)
		(connect_pads
			(clearance 0)
		)
		(min_thickness 0.25)
		(keepout
			(tracks not_allowed)
			(vias allowed)
			(pads allowed)
			(copperpour not_allowed)
			(footprints allowed)
		)
		(placement
			(enabled no)
			(sheetname "")
		)
		(fill yes
			(thermal_gap 0.5)
			(thermal_bridge_width 0.5)
			(island_removal_mode 0)
		)
		(polygon
			(pts
				(arc
					(start 280.143204 -249.166634)
					(mid 279.490424 -249.166634)
					(end 280.143204 -249.166634)
				)
			)
		)
	)
	(zone
		(layers "B.Cu" "In6.Cu" "In11.Cu" "In13.Cu" "In15.Cu")
		(hatch none 0.5)
		(connect_pads
			(clearance 0)
		)
		(min_thickness 0.25)
		(keepout
			(tracks not_allowed)
			(vias allowed)
			(pads allowed)
			(copperpour not_allowed)
			(footprints allowed)
		)
		(placement
			(enabled no)
			(sheetname "")
		)
		(fill yes
			(thermal_gap 0.5)
			(thermal_bridge_width 0.5)
			(island_removal_mode 0)
		)
		(polygon
			(pts
				(arc
					(start 378.702824 -248.806208)
					(mid 378.050044 -248.806208)
					(end 378.702824 -248.806208)
				)
			)
		)
	)
	(zone
		(layers "B.Cu" "In6.Cu" "In11.Cu" "In13.Cu" "In15.Cu")
		(hatch none 0.5)
		(connect_pads
			(clearance 0)
		)
		(min_thickness 0.25)
		(keepout
			(tracks not_allowed)
			(vias allowed)
			(pads allowed)
			(copperpour not_allowed)
			(footprints allowed)
		)
		(placement
			(enabled no)
			(sheetname "")
		)
		(fill yes
			(thermal_gap 0.5)
			(thermal_bridge_width 0.5)
			(island_removal_mode 0)
		)
		(polygon
			(pts
				(arc
					(start 421.062404 -306.96662)
					(mid 420.409624 -306.96662)
					(end 421.062404 -306.96662)
				)
			)
		)
	)
	(zone
		(layers "B.Cu" "In6.Cu" "In11.Cu" "In13.Cu" "In15.Cu")
		(hatch none 0.5)
		(connect_pads
			(clearance 0)
		)
		(min_thickness 0.25)
		(keepout
			(tracks not_allowed)
			(vias allowed)
			(pads allowed)
			(copperpour not_allowed)
			(footprints allowed)
		)
		(placement
			(enabled no)
			(sheetname "")
		)
		(fill yes
			(thermal_gap 0.5)
			(thermal_bridge_width 0.5)
			(island_removal_mode 0)
		)
		(polygon
			(pts
				(arc
					(start 440.173872 -265.316716)
					(mid 439.521092 -265.316716)
					(end 440.173872 -265.316716)
				)
			)
		)
	)
	(zone
		(layers "B.Cu" "In6.Cu" "In11.Cu" "In13.Cu" "In15.Cu")
		(hatch none 0.5)
		(connect_pads
			(clearance 0)
		)
		(min_thickness 0.25)
		(keepout
			(tracks not_allowed)
			(vias allowed)
			(pads allowed)
			(copperpour not_allowed)
			(footprints allowed)
		)
		(placement
			(enabled no)
			(sheetname "")
		)
		(fill yes
			(thermal_gap 0.5)
			(thermal_bridge_width 0.5)
			(island_removal_mode 0)
		)
		(polygon
			(pts
				(arc
					(start 32.203136 -266.1666)
					(mid 31.550356 -266.1666)
					(end 32.203136 -266.1666)
				)
			)
		)
	)
	(zone
		(layers "B.Cu" "In6.Cu" "In11.Cu" "In13.Cu" "In15.Cu")
		(hatch none 0.5)
		(connect_pads
			(clearance 0)
		)
		(min_thickness 0.25)
		(keepout
			(tracks not_allowed)
			(vias allowed)
			(pads allowed)
			(copperpour not_allowed)
			(footprints allowed)
		)
		(placement
			(enabled no)
			(sheetname "")
		)
		(fill yes
			(thermal_gap 0.5)
			(thermal_bridge_width 0.5)
			(island_removal_mode 0)
		)
		(polygon
			(pts
				(arc
					(start 36.303204 -313.766708)
					(mid 35.650424 -313.766708)
					(end 36.303204 -313.766708)
				)
			)
		)
	)
	(zone
		(layers "B.Cu" "In6.Cu" "In11.Cu" "In13.Cu" "In15.Cu")
		(hatch none 0.5)
		(connect_pads
			(clearance 0)
		)
		(min_thickness 0.25)
		(keepout
			(tracks not_allowed)
			(vias allowed)
			(pads allowed)
			(copperpour not_allowed)
			(footprints allowed)
		)
		(placement
			(enabled no)
			(sheetname "")
		)
		(fill yes
			(thermal_gap 0.5)
			(thermal_bridge_width 0.5)
			(island_removal_mode 0)
		)
		(polygon
			(pts
				(arc
					(start 440.250072 -233.016806)
					(mid 439.597292 -233.016806)
					(end 440.250072 -233.016806)
				)
			)
		)
	)
	(zone
		(layers "B.Cu" "In6.Cu" "In11.Cu" "In13.Cu" "In15.Cu")
		(hatch none 0.5)
		(connect_pads
			(clearance 0)
		)
		(min_thickness 0.25)
		(keepout
			(tracks not_allowed)
			(vias allowed)
			(pads allowed)
			(copperpour not_allowed)
			(footprints allowed)
		)
		(placement
			(enabled no)
			(sheetname "")
		)
		(fill yes
			(thermal_gap 0.5)
			(thermal_bridge_width 0.5)
			(island_removal_mode 0)
		)
		(polygon
			(pts
				(arc
					(start 51.390804 -229.616762)
					(mid 50.738024 -229.616762)
					(end 51.390804 -229.616762)
				)
			)
		)
	)
	(zone
		(layers "B.Cu" "In6.Cu" "In11.Cu" "In13.Cu" "In15.Cu")
		(hatch none 0.5)
		(connect_pads
			(clearance 0)
		)
		(min_thickness 0.25)
		(keepout
			(tracks not_allowed)
			(vias allowed)
			(pads allowed)
			(copperpour not_allowed)
			(footprints allowed)
		)
		(placement
			(enabled no)
			(sheetname "")
		)
		(fill yes
			(thermal_gap 0.5)
			(thermal_bridge_width 0.5)
			(island_removal_mode 0)
		)
		(polygon
			(pts
				(arc
					(start 96.459802 -217.064336)
					(mid 95.807022 -217.064336)
					(end 96.459802 -217.064336)
				)
			)
		)
	)
	(zone
		(layers "B.Cu" "In6.Cu" "In11.Cu" "In13.Cu" "In15.Cu")
		(hatch none 0.5)
		(connect_pads
			(clearance 0)
		)
		(min_thickness 0.25)
		(keepout
			(tracks not_allowed)
			(vias allowed)
			(pads allowed)
			(copperpour not_allowed)
			(footprints allowed)
		)
		(placement
			(enabled no)
			(sheetname "")
		)
		(fill yes
			(thermal_gap 0.5)
			(thermal_bridge_width 0.5)
			(island_removal_mode 0)
		)
		(polygon
			(pts
				(arc
					(start 436.150004 -310.366664)
					(mid 435.497224 -310.366664)
					(end 436.150004 -310.366664)
				)
			)
		)
	)
	(zone
		(layers "B.Cu" "In6.Cu" "In11.Cu" "In13.Cu" "In15.Cu")
		(hatch none 0.5)
		(connect_pads
			(clearance 0)
		)
		(min_thickness 0.25)
		(keepout
			(tracks not_allowed)
			(vias allowed)
			(pads allowed)
			(copperpour not_allowed)
			(footprints allowed)
		)
		(placement
			(enabled no)
			(sheetname "")
		)
		(fill yes
			(thermal_gap 0.5)
			(thermal_bridge_width 0.5)
			(island_removal_mode 0)
		)
		(polygon
			(pts
				(arc
					(start 351.448624 -217.878406)
					(mid 350.795844 -217.878406)
					(end 351.448624 -217.878406)
				)
			)
		)
	)
	(zone
		(layers "B.Cu" "In6.Cu" "In11.Cu" "In13.Cu" "In15.Cu")
		(hatch none 0.5)
		(connect_pads
			(clearance 0)
		)
		(min_thickness 0.25)
		(keepout
			(tracks not_allowed)
			(vias allowed)
			(pads allowed)
			(copperpour not_allowed)
			(footprints allowed)
		)
		(placement
			(enabled no)
			(sheetname "")
		)
		(fill yes
			(thermal_gap 0.5)
			(thermal_bridge_width 0.5)
			(island_removal_mode 0)
		)
		(polygon
			(pts
				(arc
					(start 276.699472 -244.916706)
					(mid 276.046692 -244.916706)
					(end 276.699472 -244.916706)
				)
			)
		)
	)
	(zone
		(layers "B.Cu" "In6.Cu" "In11.Cu" "In13.Cu" "In15.Cu")
		(hatch none 0.5)
		(connect_pads
			(clearance 0)
		)
		(min_thickness 0.25)
		(keepout
			(tracks not_allowed)
			(vias allowed)
			(pads allowed)
			(copperpour not_allowed)
			(footprints allowed)
		)
		(placement
			(enabled no)
			(sheetname "")
		)
		(fill yes
			(thermal_gap 0.5)
			(thermal_bridge_width 0.5)
			(island_removal_mode 0)
		)
		(polygon
			(pts
				(arc
					(start 92.700602 -238.225584)
					(mid 92.047822 -238.225584)
					(end 92.700602 -238.225584)
				)
			)
		)
	)
	(zone
		(layers "B.Cu" "In6.Cu" "In11.Cu" "In13.Cu" "In15.Cu")
		(hatch none 0.5)
		(connect_pads
			(clearance 0)
		)
		(min_thickness 0.25)
		(keepout
			(tracks not_allowed)
			(vias allowed)
			(pads allowed)
			(copperpour not_allowed)
			(footprints allowed)
		)
		(placement
			(enabled no)
			(sheetname "")
		)
		(fill yes
			(thermal_gap 0.5)
			(thermal_bridge_width 0.5)
			(island_removal_mode 0)
		)
		(polygon
			(pts
				(arc
					(start 130.292602 -217.064336)
					(mid 129.639822 -217.064336)
					(end 130.292602 -217.064336)
				)
			)
		)
	)
	(zone
		(layers "B.Cu" "In6.Cu" "In11.Cu" "In13.Cu" "In15.Cu")
		(hatch none 0.5)
		(connect_pads
			(clearance 0)
		)
		(min_thickness 0.25)
		(keepout
			(tracks not_allowed)
			(vias allowed)
			(pads allowed)
			(copperpour not_allowed)
			(footprints allowed)
		)
		(placement
			(enabled no)
			(sheetname "")
		)
		(fill yes
			(thermal_gap 0.5)
			(thermal_bridge_width 0.5)
			(island_removal_mode 0)
		)
		(polygon
			(pts
				(arc
					(start 340.64067 -234.970066)
					(mid 339.98789 -234.970066)
					(end 340.64067 -234.970066)
				)
			)
		)
	)
	(zone
		(layers "B.Cu" "In6.Cu" "In11.Cu" "In13.Cu" "In15.Cu")
		(hatch none 0.5)
		(connect_pads
			(clearance 0)
		)
		(min_thickness 0.25)
		(keepout
			(tracks not_allowed)
			(vias allowed)
			(pads allowed)
			(copperpour not_allowed)
			(footprints allowed)
		)
		(placement
			(enabled no)
			(sheetname "")
		)
		(fill yes
			(thermal_gap 0.5)
			(thermal_bridge_width 0.5)
			(island_removal_mode 0)
		)
		(polygon
			(pts
				(arc
					(start 93.750384 -271.011396)
					(mid 93.097604 -271.011396)
					(end 93.750384 -271.011396)
				)
			)
		)
	)
	(zone
		(layers "B.Cu" "In6.Cu" "In11.Cu" "In13.Cu" "In15.Cu")
		(hatch none 0.5)
		(connect_pads
			(clearance 0)
		)
		(min_thickness 0.25)
		(keepout
			(tracks not_allowed)
			(vias allowed)
			(pads allowed)
			(copperpour not_allowed)
			(footprints allowed)
		)
		(placement
			(enabled no)
			(sheetname "")
		)
		(fill yes
			(thermal_gap 0.5)
			(thermal_bridge_width 0.5)
			(island_removal_mode 0)
		)
		(polygon
			(pts
				(arc
					(start 173.122336 -198.166736)
					(mid 172.469556 -198.166736)
					(end 173.122336 -198.166736)
				)
			)
		)
	)
	(zone
		(layers "B.Cu" "In6.Cu" "In11.Cu" "In13.Cu" "In15.Cu")
		(hatch none 0.5)
		(connect_pads
			(clearance 0)
		)
		(min_thickness 0.25)
		(keepout
			(tracks not_allowed)
			(vias allowed)
			(pads allowed)
			(copperpour not_allowed)
			(footprints allowed)
		)
		(placement
			(enabled no)
			(sheetname "")
		)
		(fill yes
			(thermal_gap 0.5)
			(thermal_bridge_width 0.5)
			(island_removal_mode 0)
		)
		(polygon
			(pts
				(arc
					(start 425.162472 -225.36658)
					(mid 424.509692 -225.36658)
					(end 425.162472 -225.36658)
				)
			)
		)
	)
	(zone
		(layers "B.Cu" "In6.Cu" "In11.Cu" "In13.Cu" "In15.Cu")
		(hatch none 0.5)
		(connect_pads
			(clearance 0)
		)
		(min_thickness 0.25)
		(keepout
			(tracks not_allowed)
			(vias allowed)
			(pads allowed)
			(copperpour not_allowed)
			(footprints allowed)
		)
		(placement
			(enabled no)
			(sheetname "")
		)
		(fill yes
			(thermal_gap 0.5)
			(thermal_bridge_width 0.5)
			(island_removal_mode 0)
		)
		(polygon
			(pts
				(arc
					(start 280.143204 -239.81664)
					(mid 279.490424 -239.81664)
					(end 280.143204 -239.81664)
				)
			)
		)
	)
	(zone
		(layers "B.Cu" "In6.Cu" "In11.Cu" "In13.Cu" "In15.Cu")
		(hatch none 0.5)
		(connect_pads
			(clearance 0)
		)
		(min_thickness 0.25)
		(keepout
			(tracks not_allowed)
			(vias allowed)
			(pads allowed)
			(copperpour not_allowed)
			(footprints allowed)
		)
		(placement
			(enabled no)
			(sheetname "")
		)
		(fill yes
			(thermal_gap 0.5)
			(thermal_bridge_width 0.5)
			(island_removal_mode 0)
		)
		(polygon
			(pts
				(arc
					(start 378.342652 -261.244842)
					(mid 377.689872 -261.244842)
					(end 378.342652 -261.244842)
				)
			)
		)
	)
	(zone
		(layers "B.Cu" "In6.Cu" "In11.Cu" "In13.Cu" "In15.Cu")
		(hatch none 0.5)
		(connect_pads
			(clearance 0)
		)
		(min_thickness 0.25)
		(keepout
			(tracks not_allowed)
			(vias allowed)
			(pads allowed)
			(copperpour not_allowed)
			(footprints allowed)
		)
		(placement
			(enabled no)
			(sheetname "")
		)
		(fill yes
			(thermal_gap 0.5)
			(thermal_bridge_width 0.5)
			(island_removal_mode 0)
		)
		(polygon
			(pts
				(arc
					(start 342.050624 -240.667286)
					(mid 341.397844 -240.667286)
					(end 342.050624 -240.667286)
				)
			)
		)
	)
	(zone
		(layers "B.Cu" "In6.Cu" "In11.Cu" "In13.Cu" "In15.Cu")
		(hatch none 0.5)
		(connect_pads
			(clearance 0)
		)
		(min_thickness 0.25)
		(keepout
			(tracks not_allowed)
			(vias allowed)
			(pads allowed)
			(copperpour not_allowed)
			(footprints allowed)
		)
		(placement
			(enabled no)
			(sheetname "")
		)
		(fill yes
			(thermal_gap 0.5)
			(thermal_bridge_width 0.5)
			(island_removal_mode 0)
		)
		(polygon
			(pts
				(arc
					(start 122.414284 -289.807142)
					(mid 121.761504 -289.807142)
					(end 122.414284 -289.807142)
				)
			)
		)
	)
	(zone
		(layers "B.Cu" "In6.Cu" "In11.Cu" "In13.Cu" "In15.Cu")
		(hatch none 0.5)
		(connect_pads
			(clearance 0)
		)
		(min_thickness 0.25)
		(keepout
			(tracks not_allowed)
			(vias allowed)
			(pads allowed)
			(copperpour not_allowed)
			(footprints allowed)
		)
		(placement
			(enabled no)
			(sheetname "")
		)
		(fill yes
			(thermal_gap 0.5)
			(thermal_bridge_width 0.5)
			(island_removal_mode 0)
		)
		(polygon
			(pts
				(arc
					(start 129.822956 -237.411514)
					(mid 129.170176 -237.411514)
					(end 129.822956 -237.411514)
				)
			)
		)
	)
	(zone
		(layers "B.Cu" "In6.Cu" "In11.Cu" "In13.Cu" "In15.Cu")
		(hatch none 0.5)
		(connect_pads
			(clearance 0)
		)
		(min_thickness 0.25)
		(keepout
			(tracks not_allowed)
			(vias allowed)
			(pads allowed)
			(copperpour not_allowed)
			(footprints allowed)
		)
		(placement
			(enabled no)
			(sheetname "")
		)
		(fill yes
			(thermal_gap 0.5)
			(thermal_bridge_width 0.5)
			(island_removal_mode 0)
		)
		(polygon
			(pts
				(arc
					(start 129.463038 -288.917126)
					(mid 128.810258 -288.917126)
					(end 129.463038 -288.917126)
				)
			)
		)
	)
	(zone
		(layers "B.Cu" "In6.Cu" "In11.Cu" "In13.Cu" "In15.Cu")
		(hatch none 0.5)
		(connect_pads
			(clearance 0)
		)
		(min_thickness 0.25)
		(keepout
			(tracks not_allowed)
			(vias allowed)
			(pads allowed)
			(copperpour not_allowed)
			(footprints allowed)
		)
		(placement
			(enabled no)
			(sheetname "")
		)
		(fill yes
			(thermal_gap 0.5)
			(thermal_bridge_width 0.5)
			(island_removal_mode 0)
		)
		(polygon
			(pts
				(arc
					(start 299.330872 -223.666558)
					(mid 298.678092 -223.666558)
					(end 299.330872 -223.666558)
				)
			)
		)
	)
	(zone
		(layers "B.Cu" "In6.Cu" "In11.Cu" "In13.Cu" "In15.Cu")
		(hatch none 0.5)
		(connect_pads
			(clearance 0)
		)
		(min_thickness 0.25)
		(keepout
			(tracks not_allowed)
			(vias allowed)
			(pads allowed)
			(copperpour not_allowed)
			(footprints allowed)
		)
		(placement
			(enabled no)
			(sheetname "")
		)
		(fill yes
			(thermal_gap 0.5)
			(thermal_bridge_width 0.5)
			(island_removal_mode 0)
		)
		(polygon
			(pts
				(arc
					(start 421.062404 -228.766624)
					(mid 420.409624 -228.766624)
					(end 421.062404 -228.766624)
				)
			)
		)
	)
	(zone
		(layers "B.Cu" "In6.Cu" "In11.Cu" "In13.Cu" "In15.Cu")
		(hatch none 0.5)
		(connect_pads
			(clearance 0)
		)
		(min_thickness 0.25)
		(keepout
			(tracks not_allowed)
			(vias allowed)
			(pads allowed)
			(copperpour not_allowed)
			(footprints allowed)
		)
		(placement
			(enabled no)
			(sheetname "")
		)
		(fill yes
			(thermal_gap 0.5)
			(thermal_bridge_width 0.5)
			(island_removal_mode 0)
		)
		(polygon
			(pts
				(arc
					(start 425.162472 -229.616762)
					(mid 424.509692 -229.616762)
					(end 425.162472 -229.616762)
				)
			)
		)
	)
	(zone
		(layers "B.Cu" "In6.Cu" "In11.Cu" "In13.Cu" "In15.Cu")
		(hatch none 0.5)
		(connect_pads
			(clearance 0)
		)
		(min_thickness 0.25)
		(keepout
			(tracks not_allowed)
			(vias allowed)
			(pads allowed)
			(copperpour not_allowed)
			(footprints allowed)
		)
		(placement
			(enabled no)
			(sheetname "")
		)
		(fill yes
			(thermal_gap 0.5)
			(thermal_bridge_width 0.5)
			(island_removal_mode 0)
		)
		(polygon
			(pts
				(arc
					(start 126.063756 -217.878406)
					(mid 125.410976 -217.878406)
					(end 126.063756 -217.878406)
				)
			)
		)
	)
	(zone
		(layers "B.Cu" "In6.Cu" "In11.Cu" "In13.Cu" "In15.Cu")
		(hatch none 0.5)
		(connect_pads
			(clearance 0)
		)
		(min_thickness 0.25)
		(keepout
			(tracks not_allowed)
			(vias allowed)
			(pads allowed)
			(copperpour not_allowed)
			(footprints allowed)
		)
		(placement
			(enabled no)
			(sheetname "")
		)
		(fill yes
			(thermal_gap 0.5)
			(thermal_bridge_width 0.5)
			(island_removal_mode 0)
		)
		(polygon
			(pts
				(arc
					(start 93.750384 -274.266914)
					(mid 93.097604 -274.266914)
					(end 93.750384 -274.266914)
				)
			)
		)
	)
	(zone
		(layers "B.Cu" "In6.Cu" "In11.Cu" "In13.Cu" "In15.Cu")
		(hatch none 0.5)
		(connect_pads
			(clearance 0)
		)
		(min_thickness 0.25)
		(keepout
			(tracks not_allowed)
			(vias allowed)
			(pads allowed)
			(copperpour not_allowed)
			(footprints allowed)
		)
		(placement
			(enabled no)
			(sheetname "")
		)
		(fill yes
			(thermal_gap 0.5)
			(thermal_bridge_width 0.5)
			(island_removal_mode 0)
		)
		(polygon
			(pts
				(arc
					(start 366.485424 -217.878406)
					(mid 365.832644 -217.878406)
					(end 366.485424 -217.878406)
				)
			)
		)
	)
	(zone
		(layers "B.Cu" "In6.Cu" "In11.Cu" "In13.Cu" "In15.Cu")
		(hatch none 0.5)
		(connect_pads
			(clearance 0)
		)
		(min_thickness 0.25)
		(keepout
			(tracks not_allowed)
			(vias allowed)
			(pads allowed)
			(copperpour not_allowed)
			(footprints allowed)
		)
		(placement
			(enabled no)
			(sheetname "")
		)
		(fill yes
			(thermal_gap 0.5)
			(thermal_bridge_width 0.5)
			(island_removal_mode 0)
		)
		(polygon
			(pts
				(arc
					(start 132.282184 -266.128246)
					(mid 131.629404 -266.128246)
					(end 132.282184 -266.128246)
				)
			)
		)
	)
	(zone
		(layers "B.Cu" "In6.Cu" "In11.Cu" "In13.Cu" "In15.Cu")
		(hatch none 0.5)
		(connect_pads
			(clearance 0)
		)
		(min_thickness 0.25)
		(keepout
			(tracks not_allowed)
			(vias allowed)
			(pads allowed)
			(copperpour not_allowed)
			(footprints allowed)
		)
		(placement
			(enabled no)
			(sheetname "")
		)
		(fill yes
			(thermal_gap 0.5)
			(thermal_bridge_width 0.5)
			(island_removal_mode 0)
		)
		(polygon
			(pts
				(arc
					(start 341.690452 -274.266914)
					(mid 341.037672 -274.266914)
					(end 341.690452 -274.266914)
				)
			)
		)
	)
	(zone
		(layers "B.Cu" "In6.Cu" "In11.Cu" "In13.Cu" "In15.Cu")
		(hatch none 0.5)
		(connect_pads
			(clearance 0)
		)
		(min_thickness 0.25)
		(keepout
			(tracks not_allowed)
			(vias allowed)
			(pads allowed)
			(copperpour not_allowed)
			(footprints allowed)
		)
		(placement
			(enabled no)
			(sheetname "")
		)
		(fill yes
			(thermal_gap 0.5)
			(thermal_bridge_width 0.5)
			(island_removal_mode 0)
		)
		(polygon
			(pts
				(arc
					(start 93.640402 -230.086662)
					(mid 92.987622 -230.086662)
					(end 93.640402 -230.086662)
				)
			)
		)
	)
	(zone
		(layers "B.Cu" "In6.Cu" "In11.Cu" "In13.Cu" "In15.Cu")
		(hatch none 0.5)
		(connect_pads
			(clearance 0)
		)
		(min_thickness 0.25)
		(keepout
			(tracks not_allowed)
			(vias allowed)
			(pads allowed)
			(copperpour not_allowed)
			(footprints allowed)
		)
		(placement
			(enabled no)
			(sheetname "")
		)
		(fill yes
			(thermal_gap 0.5)
			(thermal_bridge_width 0.5)
			(island_removal_mode 0)
		)
		(polygon
			(pts
				(arc
					(start 130.762756 -242.294918)
					(mid 130.109976 -242.294918)
					(end 130.762756 -242.294918)
				)
			)
		)
	)
	(zone
		(layers "B.Cu" "In6.Cu" "In11.Cu" "In13.Cu" "In15.Cu")
		(hatch none 0.5)
		(connect_pads
			(clearance 0)
		)
		(min_thickness 0.25)
		(keepout
			(tracks not_allowed)
			(vias allowed)
			(pads allowed)
			(copperpour not_allowed)
			(footprints allowed)
		)
		(placement
			(enabled no)
			(sheetname "")
		)
		(fill yes
			(thermal_gap 0.5)
			(thermal_bridge_width 0.5)
			(island_removal_mode 0)
		)
		(polygon
			(pts
				(arc
					(start 94.220538 -258.80314)
					(mid 93.567758 -258.80314)
					(end 94.220538 -258.80314)
				)
			)
		)
	)
	(zone
		(layers "B.Cu" "In6.Cu" "In11.Cu" "In13.Cu" "In15.Cu")
		(hatch none 0.5)
		(connect_pads
			(clearance 0)
		)
		(min_thickness 0.25)
		(keepout
			(tracks not_allowed)
			(vias allowed)
			(pads allowed)
			(copperpour not_allowed)
			(footprints allowed)
		)
		(placement
			(enabled no)
			(sheetname "")
		)
		(fill yes
			(thermal_gap 0.5)
			(thermal_bridge_width 0.5)
			(island_removal_mode 0)
		)
		(polygon
			(pts
				(arc
					(start 280.143204 -233.86669)
					(mid 279.490424 -233.86669)
					(end 280.143204 -233.86669)
				)
			)
		)
	)
	(zone
		(layers "B.Cu" "In6.Cu" "In11.Cu" "In13.Cu" "In15.Cu")
		(hatch none 0.5)
		(connect_pads
			(clearance 0)
		)
		(min_thickness 0.25)
		(keepout
			(tracks not_allowed)
			(vias allowed)
			(pads allowed)
			(copperpour not_allowed)
			(footprints allowed)
		)
		(placement
			(enabled no)
			(sheetname "")
		)
		(fill yes
			(thermal_gap 0.5)
			(thermal_bridge_width 0.5)
			(island_removal_mode 0)
		)
		(polygon
			(pts
				(arc
					(start 132.642356 -247.178322)
					(mid 131.989576 -247.178322)
					(end 132.642356 -247.178322)
				)
			)
		)
	)
	(zone
		(layers "B.Cu" "In6.Cu" "In11.Cu" "In13.Cu" "In15.Cu")
		(hatch none 0.5)
		(connect_pads
			(clearance 0)
		)
		(min_thickness 0.25)
		(keepout
			(tracks not_allowed)
			(vias allowed)
			(pads allowed)
			(copperpour not_allowed)
			(footprints allowed)
		)
		(placement
			(enabled no)
			(sheetname "")
		)
		(fill yes
			(thermal_gap 0.5)
			(thermal_bridge_width 0.5)
			(island_removal_mode 0)
		)
		(polygon
			(pts
				(arc
					(start 447.793872 -259.366766)
					(mid 447.141092 -259.366766)
					(end 447.793872 -259.366766)
				)
			)
		)
	)
	(zone
		(layers "B.Cu" "In6.Cu" "In11.Cu" "In13.Cu" "In15.Cu")
		(hatch none 0.5)
		(connect_pads
			(clearance 0)
		)
		(min_thickness 0.25)
		(keepout
			(tracks not_allowed)
			(vias allowed)
			(pads allowed)
			(copperpour not_allowed)
			(footprints allowed)
		)
		(placement
			(enabled no)
			(sheetname "")
		)
		(fill yes
			(thermal_gap 0.5)
			(thermal_bridge_width 0.5)
			(island_removal_mode 0)
		)
		(polygon
			(pts
				(arc
					(start 87.531956 -224.389442)
					(mid 86.879176 -224.389442)
					(end 87.531956 -224.389442)
				)
			)
		)
	)
	(zone
		(layers "B.Cu" "In6.Cu" "In11.Cu" "In13.Cu" "In15.Cu")
		(hatch none 0.5)
		(connect_pads
			(clearance 0)
		)
		(min_thickness 0.25)
		(keepout
			(tracks not_allowed)
			(vias allowed)
			(pads allowed)
			(copperpour not_allowed)
			(footprints allowed)
		)
		(placement
			(enabled no)
			(sheetname "")
		)
		(fill yes
			(thermal_gap 0.5)
			(thermal_bridge_width 0.5)
			(island_removal_mode 0)
		)
		(polygon
			(pts
				(arc
					(start 93.640402 -234.970066)
					(mid 92.987622 -234.970066)
					(end 93.640402 -234.970066)
				)
			)
		)
	)
	(zone
		(layers "B.Cu" "In6.Cu" "In11.Cu" "In13.Cu" "In15.Cu")
		(hatch none 0.5)
		(connect_pads
			(clearance 0)
		)
		(min_thickness 0.25)
		(keepout
			(tracks not_allowed)
			(vias allowed)
			(pads allowed)
			(copperpour not_allowed)
			(footprints allowed)
		)
		(placement
			(enabled no)
			(sheetname "")
		)
		(fill yes
			(thermal_gap 0.5)
			(thermal_bridge_width 0.5)
			(island_removal_mode 0)
		)
		(polygon
			(pts
				(arc
					(start 188.209936 -245.76659)
					(mid 187.557156 -245.76659)
					(end 188.209936 -245.76659)
				)
			)
		)
	)
	(zone
		(layers "B.Cu" "In6.Cu" "In11.Cu" "In13.Cu" "In15.Cu")
		(hatch none 0.5)
		(connect_pads
			(clearance 0)
		)
		(min_thickness 0.25)
		(keepout
			(tracks not_allowed)
			(vias allowed)
			(pads allowed)
			(copperpour not_allowed)
			(footprints allowed)
		)
		(placement
			(enabled no)
			(sheetname "")
		)
		(fill yes
			(thermal_gap 0.5)
			(thermal_bridge_width 0.5)
			(island_removal_mode 0)
		)
		(polygon
			(pts
				(arc
					(start 378.702824 -230.900478)
					(mid 378.050044 -230.900478)
					(end 378.702824 -230.900478)
				)
			)
		)
	)
	(zone
		(layers "B.Cu" "In6.Cu" "In11.Cu" "In13.Cu" "In15.Cu")
		(hatch none 0.5)
		(connect_pads
			(clearance 0)
		)
		(min_thickness 0.25)
		(keepout
			(tracks not_allowed)
			(vias allowed)
			(pads allowed)
			(copperpour not_allowed)
			(footprints allowed)
		)
		(placement
			(enabled no)
			(sheetname "")
		)
		(fill yes
			(thermal_gap 0.5)
			(thermal_bridge_width 0.5)
			(island_removal_mode 0)
		)
		(polygon
			(pts
				(arc
					(start 130.292602 -226.831144)
					(mid 129.639822 -226.831144)
					(end 130.292602 -226.831144)
				)
			)
		)
	)
	(zone
		(layers "B.Cu" "In6.Cu" "In11.Cu" "In13.Cu" "In15.Cu")
		(hatch none 0.5)
		(connect_pads
			(clearance 0)
		)
		(min_thickness 0.25)
		(keepout
			(tracks not_allowed)
			(vias allowed)
			(pads allowed)
			(copperpour not_allowed)
			(footprints allowed)
		)
		(placement
			(enabled no)
			(sheetname "")
		)
		(fill yes
			(thermal_gap 0.5)
			(thermal_bridge_width 0.5)
			(island_removal_mode 0)
		)
		(polygon
			(pts
				(arc
					(start 192.310004 -210.916774)
					(mid 191.657224 -210.916774)
					(end 192.310004 -210.916774)
				)
			)
		)
	)
	(zone
		(layers "B.Cu" "In6.Cu" "In11.Cu" "In13.Cu" "In15.Cu")
		(hatch none 0.5)
		(connect_pads
			(clearance 0)
		)
		(min_thickness 0.25)
		(keepout
			(tracks not_allowed)
			(vias allowed)
			(pads allowed)
			(copperpour not_allowed)
			(footprints allowed)
		)
		(placement
			(enabled no)
			(sheetname "")
		)
		(fill yes
			(thermal_gap 0.5)
			(thermal_bridge_width 0.5)
			(island_removal_mode 0)
		)
		(polygon
			(pts
				(arc
					(start 280.143204 -291.666676)
					(mid 279.490424 -291.666676)
					(end 280.143204 -291.666676)
				)
			)
		)
	)
	(zone
		(layers "B.Cu" "In6.Cu" "In11.Cu" "In13.Cu" "In15.Cu")
		(hatch none 0.5)
		(connect_pads
			(clearance 0)
		)
		(min_thickness 0.25)
		(keepout
			(tracks not_allowed)
			(vias allowed)
			(pads allowed)
			(copperpour not_allowed)
			(footprints allowed)
		)
		(placement
			(enabled no)
			(sheetname "")
		)
		(fill yes
			(thermal_gap 0.5)
			(thermal_bridge_width 0.5)
			(island_removal_mode 0)
		)
		(polygon
			(pts
				(arc
					(start 373.643906 -288.917126)
					(mid 372.991126 -288.917126)
					(end 373.643906 -288.917126)
				)
			)
		)
	)
	(zone
		(layers "B.Cu" "In6.Cu" "In11.Cu" "In13.Cu" "In15.Cu")
		(hatch none 0.5)
		(connect_pads
			(clearance 0)
		)
		(min_thickness 0.25)
		(keepout
			(tracks not_allowed)
			(vias allowed)
			(pads allowed)
			(copperpour not_allowed)
			(footprints allowed)
		)
		(placement
			(enabled no)
			(sheetname "")
		)
		(fill yes
			(thermal_gap 0.5)
			(thermal_bridge_width 0.5)
			(island_removal_mode 0)
		)
		(polygon
			(pts
				(arc
					(start 101.628956 -217.878406)
					(mid 100.976176 -217.878406)
					(end 101.628956 -217.878406)
				)
			)
		)
	)
	(zone
		(layers "B.Cu" "In6.Cu" "In11.Cu" "In13.Cu" "In15.Cu")
		(hatch none 0.5)
		(connect_pads
			(clearance 0)
		)
		(min_thickness 0.25)
		(keepout
			(tracks not_allowed)
			(vias allowed)
			(pads allowed)
			(copperpour not_allowed)
			(footprints allowed)
		)
		(placement
			(enabled no)
			(sheetname "")
		)
		(fill yes
			(thermal_gap 0.5)
			(thermal_bridge_width 0.5)
			(island_removal_mode 0)
		)
		(polygon
			(pts
				(arc
					(start 192.233804 -263.616694)
					(mid 191.581024 -263.616694)
					(end 192.233804 -263.616694)
				)
			)
		)
	)
	(zone
		(layers "B.Cu" "In6.Cu" "In11.Cu" "In13.Cu" "In15.Cu")
		(hatch none 0.5)
		(connect_pads
			(clearance 0)
		)
		(min_thickness 0.25)
		(keepout
			(tracks not_allowed)
			(vias allowed)
			(pads allowed)
			(copperpour not_allowed)
			(footprints allowed)
		)
		(placement
			(enabled no)
			(sheetname "")
		)
		(fill yes
			(thermal_gap 0.5)
			(thermal_bridge_width 0.5)
			(island_removal_mode 0)
		)
		(polygon
			(pts
				(arc
					(start 92.810584 -277.522432)
					(mid 92.157804 -277.522432)
					(end 92.810584 -277.522432)
				)
			)
		)
	)
	(zone
		(layers "B.Cu" "In6.Cu" "In11.Cu" "In13.Cu" "In15.Cu")
		(hatch none 0.5)
		(connect_pads
			(clearance 0)
		)
		(min_thickness 0.25)
		(keepout
			(tracks not_allowed)
			(vias allowed)
			(pads allowed)
			(copperpour not_allowed)
			(footprints allowed)
		)
		(placement
			(enabled no)
			(sheetname "")
		)
		(fill yes
			(thermal_gap 0.5)
			(thermal_bridge_width 0.5)
			(island_removal_mode 0)
		)
		(polygon
			(pts
				(arc
					(start 443.693804 -245.76659)
					(mid 443.041024 -245.76659)
					(end 443.693804 -245.76659)
				)
			)
		)
	)
	(zone
		(layers "B.Cu" "In6.Cu" "In11.Cu" "In13.Cu" "In15.Cu")
		(hatch none 0.5)
		(connect_pads
			(clearance 0)
		)
		(min_thickness 0.25)
		(keepout
			(tracks not_allowed)
			(vias allowed)
			(pads allowed)
			(copperpour not_allowed)
			(footprints allowed)
		)
		(placement
			(enabled no)
			(sheetname "")
		)
		(fill yes
			(thermal_gap 0.5)
			(thermal_bridge_width 0.5)
			(island_removal_mode 0)
		)
		(polygon
			(pts
				(arc
					(start 130.292602 -228.45903)
					(mid 129.639822 -228.45903)
					(end 130.292602 -228.45903)
				)
			)
		)
	)
	(zone
		(layers "B.Cu" "In6.Cu" "In11.Cu" "In13.Cu" "In15.Cu")
		(hatch none 0.5)
		(connect_pads
			(clearance 0)
		)
		(min_thickness 0.25)
		(keepout
			(tracks not_allowed)
			(vias allowed)
			(pads allowed)
			(copperpour not_allowed)
			(footprints allowed)
		)
		(placement
			(enabled no)
			(sheetname "")
		)
		(fill yes
			(thermal_gap 0.5)
			(thermal_bridge_width 0.5)
			(island_removal_mode 0)
		)
		(polygon
			(pts
				(arc
					(start 340.64067 -228.45903)
					(mid 339.98789 -228.45903)
					(end 340.64067 -228.45903)
				)
			)
		)
	)
	(zone
		(layers "B.Cu" "In6.Cu" "In11.Cu" "In13.Cu" "In15.Cu")
		(hatch none 0.5)
		(connect_pads
			(clearance 0)
		)
		(min_thickness 0.25)
		(keepout
			(tracks not_allowed)
			(vias allowed)
			(pads allowed)
			(copperpour not_allowed)
			(footprints allowed)
		)
		(placement
			(enabled no)
			(sheetname "")
		)
		(fill yes
			(thermal_gap 0.5)
			(thermal_bridge_width 0.5)
			(island_removal_mode 0)
		)
		(polygon
			(pts
				(arc
					(start 32.203136 -312.91657)
					(mid 31.550356 -312.91657)
					(end 32.203136 -312.91657)
				)
			)
		)
	)
	(zone
		(layers "B.Cu" "In6.Cu" "In11.Cu" "In13.Cu" "In15.Cu")
		(hatch none 0.5)
		(connect_pads
			(clearance 0)
		)
		(min_thickness 0.25)
		(keepout
			(tracks not_allowed)
			(vias allowed)
			(pads allowed)
			(copperpour not_allowed)
			(footprints allowed)
		)
		(placement
			(enabled no)
			(sheetname "")
		)
		(fill yes
			(thermal_gap 0.5)
			(thermal_bridge_width 0.5)
			(island_removal_mode 0)
		)
		(polygon
			(pts
				(arc
					(start 47.290736 -284.866588)
					(mid 46.637956 -284.866588)
					(end 47.290736 -284.866588)
				)
			)
		)
	)
	(zone
		(layers "B.Cu" "In6.Cu" "In11.Cu" "In13.Cu" "In15.Cu")
		(hatch none 0.5)
		(connect_pads
			(clearance 0)
		)
		(min_thickness 0.25)
		(keepout
			(tracks not_allowed)
			(vias allowed)
			(pads allowed)
			(copperpour not_allowed)
			(footprints allowed)
		)
		(placement
			(enabled no)
			(sheetname "")
		)
		(fill yes
			(thermal_gap 0.5)
			(thermal_bridge_width 0.5)
			(island_removal_mode 0)
		)
		(polygon
			(pts
				(arc
					(start 94.220538 -273.453098)
					(mid 93.567758 -273.453098)
					(end 94.220538 -273.453098)
				)
			)
		)
	)
	(zone
		(layers "B.Cu" "In6.Cu" "In11.Cu" "In13.Cu" "In15.Cu")
		(hatch none 0.5)
		(connect_pads
			(clearance 0)
		)
		(min_thickness 0.25)
		(keepout
			(tracks not_allowed)
			(vias allowed)
			(pads allowed)
			(copperpour not_allowed)
			(footprints allowed)
		)
		(placement
			(enabled no)
			(sheetname "")
		)
		(fill yes
			(thermal_gap 0.5)
			(thermal_bridge_width 0.5)
			(island_removal_mode 0)
		)
		(polygon
			(pts
				(arc
					(start 127.113538 -288.103056)
					(mid 126.460758 -288.103056)
					(end 127.113538 -288.103056)
				)
			)
		)
	)
	(zone
		(layers "B.Cu" "In6.Cu" "In11.Cu" "In13.Cu" "In15.Cu")
		(hatch none 0.5)
		(connect_pads
			(clearance 0)
		)
		(min_thickness 0.25)
		(keepout
			(tracks not_allowed)
			(vias allowed)
			(pads allowed)
			(copperpour not_allowed)
			(footprints allowed)
		)
		(placement
			(enabled no)
			(sheetname "")
		)
		(fill yes
			(thermal_gap 0.5)
			(thermal_bridge_width 0.5)
			(island_removal_mode 0)
		)
		(polygon
			(pts
				(arc
					(start 340.281006 -268.569694)
					(mid 339.628226 -268.569694)
					(end 340.281006 -268.569694)
				)
			)
		)
	)
	(zone
		(layers "B.Cu" "In6.Cu" "In11.Cu" "In13.Cu" "In15.Cu")
		(hatch none 0.5)
		(connect_pads
			(clearance 0)
		)
		(min_thickness 0.25)
		(keepout
			(tracks not_allowed)
			(vias allowed)
			(pads allowed)
			(copperpour not_allowed)
			(footprints allowed)
		)
		(placement
			(enabled no)
			(sheetname "")
		)
		(fill yes
			(thermal_gap 0.5)
			(thermal_bridge_width 0.5)
			(island_removal_mode 0)
		)
		(polygon
			(pts
				(arc
					(start 20.19427 -385.784344)
					(mid 19.49069 -385.784344)
					(end 20.19427 -385.784344)
				)
			)
		)
	)
	(zone
		(layers "B.Cu" "In6.Cu" "In11.Cu" "In13.Cu" "In15.Cu")
		(hatch none 0.5)
		(connect_pads
			(clearance 0)
		)
		(min_thickness 0.25)
		(keepout
			(tracks not_allowed)
			(vias allowed)
			(pads allowed)
			(copperpour not_allowed)
			(footprints allowed)
		)
		(placement
			(enabled no)
			(sheetname "")
		)
		(fill yes
			(thermal_gap 0.5)
			(thermal_bridge_width 0.5)
			(island_removal_mode 0)
		)
		(polygon
			(pts
				(arc
					(start 132.172202 -247.992138)
					(mid 131.519422 -247.992138)
					(end 132.172202 -247.992138)
				)
			)
		)
	)
	(zone
		(layers "B.Cu" "In6.Cu" "In11.Cu" "In13.Cu" "In15.Cu")
		(hatch none 0.5)
		(connect_pads
			(clearance 0)
		)
		(min_thickness 0.25)
		(keepout
			(tracks not_allowed)
			(vias allowed)
			(pads allowed)
			(copperpour not_allowed)
			(footprints allowed)
		)
		(placement
			(enabled no)
			(sheetname "")
		)
		(fill yes
			(thermal_gap 0.5)
			(thermal_bridge_width 0.5)
			(island_removal_mode 0)
		)
		(polygon
			(pts
				(arc
					(start 355.207824 -217.878406)
					(mid 354.555044 -217.878406)
					(end 355.207824 -217.878406)
				)
			)
		)
	)
	(zone
		(layers "B.Cu" "In6.Cu" "In11.Cu" "In13.Cu" "In15.Cu")
		(hatch none 0.5)
		(connect_pads
			(clearance 0)
		)
		(min_thickness 0.25)
		(keepout
			(tracks not_allowed)
			(vias allowed)
			(pads allowed)
			(copperpour not_allowed)
			(footprints allowed)
		)
		(placement
			(enabled no)
			(sheetname "")
		)
		(fill yes
			(thermal_gap 0.5)
			(thermal_bridge_width 0.5)
			(island_removal_mode 0)
		)
		(polygon
			(pts
				(arc
					(start 337.461352 -288.103056)
					(mid 336.808572 -288.103056)
					(end 337.461352 -288.103056)
				)
			)
		)
	)
	(zone
		(layers "B.Cu" "In6.Cu" "In11.Cu" "In13.Cu" "In15.Cu")
		(hatch none 0.5)
		(connect_pads
			(clearance 0)
		)
		(min_thickness 0.25)
		(keepout
			(tracks not_allowed)
			(vias allowed)
			(pads allowed)
			(copperpour not_allowed)
			(footprints allowed)
		)
		(placement
			(enabled no)
			(sheetname "")
		)
		(fill yes
			(thermal_gap 0.5)
			(thermal_bridge_width 0.5)
			(island_removal_mode 0)
		)
		(polygon
			(pts
				(arc
					(start 92.700602 -231.714548)
					(mid 92.047822 -231.714548)
					(end 92.700602 -231.714548)
				)
			)
		)
	)
	(zone
		(layers "B.Cu" "In6.Cu" "In11.Cu" "In13.Cu" "In15.Cu")
		(hatch none 0.5)
		(connect_pads
			(clearance 0)
		)
		(min_thickness 0.25)
		(keepout
			(tracks not_allowed)
			(vias allowed)
			(pads allowed)
			(copperpour not_allowed)
			(footprints allowed)
		)
		(placement
			(enabled no)
			(sheetname "")
		)
		(fill yes
			(thermal_gap 0.5)
			(thermal_bridge_width 0.5)
			(island_removal_mode 0)
		)
		(polygon
			(pts
				(arc
					(start 188.209936 -252.566678)
					(mid 187.557156 -252.566678)
					(end 188.209936 -252.566678)
				)
			)
		)
	)
	(zone
		(layers "B.Cu" "In6.Cu" "In11.Cu" "In13.Cu" "In15.Cu")
		(hatch none 0.5)
		(connect_pads
			(clearance 0)
		)
		(min_thickness 0.25)
		(keepout
			(tracks not_allowed)
			(vias allowed)
			(pads allowed)
			(copperpour not_allowed)
			(footprints allowed)
		)
		(placement
			(enabled no)
			(sheetname "")
		)
		(fill yes
			(thermal_gap 0.5)
			(thermal_bridge_width 0.5)
			(island_removal_mode 0)
		)
		(polygon
			(pts
				(arc
					(start 299.356272 -302.716946)
					(mid 298.703492 -302.716946)
					(end 299.356272 -302.716946)
				)
			)
		)
	)
	(zone
		(layers "B.Cu" "In6.Cu" "In11.Cu" "In13.Cu" "In15.Cu")
		(hatch none 0.5)
		(connect_pads
			(clearance 0)
		)
		(min_thickness 0.25)
		(keepout
			(tracks not_allowed)
			(vias allowed)
			(pads allowed)
			(copperpour not_allowed)
			(footprints allowed)
		)
		(placement
			(enabled no)
			(sheetname "")
		)
		(fill yes
			(thermal_gap 0.5)
			(thermal_bridge_width 0.5)
			(island_removal_mode 0)
		)
		(polygon
			(pts
				(arc
					(start 436.150004 -250.866656)
					(mid 435.497224 -250.866656)
					(end 436.150004 -250.866656)
				)
			)
		)
	)
	(zone
		(layers "B.Cu" "In6.Cu" "In11.Cu" "In13.Cu" "In15.Cu")
		(hatch none 0.5)
		(connect_pads
			(clearance 0)
		)
		(min_thickness 0.25)
		(keepout
			(tracks not_allowed)
			(vias allowed)
			(pads allowed)
			(copperpour not_allowed)
			(footprints allowed)
		)
		(placement
			(enabled no)
			(sheetname "")
		)
		(fill yes
			(thermal_gap 0.5)
			(thermal_bridge_width 0.5)
			(island_removal_mode 0)
		)
		(polygon
			(pts
				(arc
					(start 51.416204 -298.466764)
					(mid 50.763424 -298.466764)
					(end 51.416204 -298.466764)
				)
			)
		)
	)
	(zone
		(layers "B.Cu" "In6.Cu" "In11.Cu" "In13.Cu" "In15.Cu")
		(hatch none 0.5)
		(connect_pads
			(clearance 0)
		)
		(min_thickness 0.25)
		(keepout
			(tracks not_allowed)
			(vias allowed)
			(pads allowed)
			(copperpour not_allowed)
			(footprints allowed)
		)
		(placement
			(enabled no)
			(sheetname "")
		)
		(fill yes
			(thermal_gap 0.5)
			(thermal_bridge_width 0.5)
			(island_removal_mode 0)
		)
		(polygon
			(pts
				(arc
					(start 380.11227 -243.108988)
					(mid 379.45949 -243.108988)
					(end 380.11227 -243.108988)
				)
			)
		)
	)
	(zone
		(layers "B.Cu" "In6.Cu" "In11.Cu" "In13.Cu" "In15.Cu")
		(hatch none 0.5)
		(connect_pads
			(clearance 0)
		)
		(min_thickness 0.25)
		(keepout
			(tracks not_allowed)
			(vias allowed)
			(pads allowed)
			(copperpour not_allowed)
			(footprints allowed)
		)
		(placement
			(enabled no)
			(sheetname "")
		)
		(fill yes
			(thermal_gap 0.5)
			(thermal_bridge_width 0.5)
			(island_removal_mode 0)
		)
		(polygon
			(pts
				(arc
					(start 87.062056 -225.203258)
					(mid 86.409276 -225.203258)
					(end 87.062056 -225.203258)
				)
			)
		)
	)
	(zone
		(layers "B.Cu" "In6.Cu" "In11.Cu" "In13.Cu" "In15.Cu")
		(hatch none 0.5)
		(connect_pads
			(clearance 0)
		)
		(min_thickness 0.25)
		(keepout
			(tracks not_allowed)
			(vias allowed)
			(pads allowed)
			(copperpour not_allowed)
			(footprints allowed)
		)
		(placement
			(enabled no)
			(sheetname "")
		)
		(fill yes
			(thermal_gap 0.5)
			(thermal_bridge_width 0.5)
			(island_removal_mode 0)
		)
		(polygon
			(pts
				(arc
					(start 109.147356 -217.878406)
					(mid 108.494576 -217.878406)
					(end 109.147356 -217.878406)
				)
			)
		)
	)
	(zone
		(layers "B.Cu" "In6.Cu" "In11.Cu" "In13.Cu" "In15.Cu")
		(hatch none 0.5)
		(connect_pads
			(clearance 0)
		)
		(min_thickness 0.25)
		(keepout
			(tracks not_allowed)
			(vias allowed)
			(pads allowed)
			(copperpour not_allowed)
			(footprints allowed)
		)
		(placement
			(enabled no)
			(sheetname "")
		)
		(fill yes
			(thermal_gap 0.5)
			(thermal_bridge_width 0.5)
			(island_removal_mode 0)
		)
		(polygon
			(pts
				(arc
					(start 86.122256 -225.203258)
					(mid 85.469476 -225.203258)
					(end 86.122256 -225.203258)
				)
			)
		)
	)
	(zone
		(layers "B.Cu" "In6.Cu" "In11.Cu" "In13.Cu" "In15.Cu")
		(hatch none 0.5)
		(connect_pads
			(clearance 0)
		)
		(min_thickness 0.25)
		(keepout
			(tracks not_allowed)
			(vias allowed)
			(pads allowed)
			(copperpour not_allowed)
			(footprints allowed)
		)
		(placement
			(enabled no)
			(sheetname "")
		)
		(fill yes
			(thermal_gap 0.5)
			(thermal_bridge_width 0.5)
			(island_removal_mode 0)
		)
		(polygon
			(pts
				(arc
					(start 379.752352 -289.807142)
					(mid 379.099572 -289.807142)
					(end 379.752352 -289.807142)
				)
			)
		)
	)
	(zone
		(layers "B.Cu" "In6.Cu" "In11.Cu" "In13.Cu" "In15.Cu")
		(hatch none 0.5)
		(connect_pads
			(clearance 0)
		)
		(min_thickness 0.25)
		(keepout
			(tracks not_allowed)
			(vias allowed)
			(pads allowed)
			(copperpour not_allowed)
			(footprints allowed)
		)
		(placement
			(enabled no)
			(sheetname "")
		)
		(fill yes
			(thermal_gap 0.5)
			(thermal_bridge_width 0.5)
			(island_removal_mode 0)
		)
		(polygon
			(pts
				(arc
					(start 188.209936 -308.666642)
					(mid 187.557156 -308.666642)
					(end 188.209936 -308.666642)
				)
			)
		)
	)
	(zone
		(layers "B.Cu" "In6.Cu" "In11.Cu" "In13.Cu" "In15.Cu")
		(hatch none 0.5)
		(connect_pads
			(clearance 0)
		)
		(min_thickness 0.25)
		(keepout
			(tracks not_allowed)
			(vias allowed)
			(pads allowed)
			(copperpour not_allowed)
			(footprints allowed)
		)
		(placement
			(enabled no)
			(sheetname "")
		)
		(fill yes
			(thermal_gap 0.5)
			(thermal_bridge_width 0.5)
			(island_removal_mode 0)
		)
		(polygon
			(pts
				(arc
					(start 51.416204 -281.466798)
					(mid 50.763424 -281.466798)
					(end 51.416204 -281.466798)
				)
			)
		)
	)
	(zone
		(layers "B.Cu" "In6.Cu" "In11.Cu" "In13.Cu" "In15.Cu")
		(hatch none 0.5)
		(connect_pads
			(clearance 0)
		)
		(min_thickness 0.25)
		(keepout
			(tracks not_allowed)
			(vias allowed)
			(pads allowed)
			(copperpour not_allowed)
			(footprints allowed)
		)
		(placement
			(enabled no)
			(sheetname "")
		)
		(fill yes
			(thermal_gap 0.5)
			(thermal_bridge_width 0.5)
			(island_removal_mode 0)
		)
		(polygon
			(pts
				(arc
					(start 425.162472 -287.416748)
					(mid 424.509692 -287.416748)
					(end 425.162472 -287.416748)
				)
			)
		)
	)
	(zone
		(layers "B.Cu" "In6.Cu" "In11.Cu" "In13.Cu" "In15.Cu")
		(hatch none 0.5)
		(connect_pads
			(clearance 0)
		)
		(min_thickness 0.25)
		(keepout
			(tracks not_allowed)
			(vias allowed)
			(pads allowed)
			(copperpour not_allowed)
			(footprints allowed)
		)
		(placement
			(enabled no)
			(sheetname "")
		)
		(fill yes
			(thermal_gap 0.5)
			(thermal_bridge_width 0.5)
			(island_removal_mode 0)
		)
		(polygon
			(pts
				(arc
					(start 375.523252 -256.361438)
					(mid 374.870472 -256.361438)
					(end 375.523252 -256.361438)
				)
			)
		)
	)
	(zone
		(layers "B.Cu" "In6.Cu" "In11.Cu" "In13.Cu" "In15.Cu")
		(hatch none 0.5)
		(connect_pads
			(clearance 0)
		)
		(min_thickness 0.25)
		(keepout
			(tracks not_allowed)
			(vias allowed)
			(pads allowed)
			(copperpour not_allowed)
			(footprints allowed)
		)
		(placement
			(enabled no)
			(sheetname "")
		)
		(fill yes
			(thermal_gap 0.5)
			(thermal_bridge_width 0.5)
			(island_removal_mode 0)
		)
		(polygon
			(pts
				(arc
					(start 132.282184 -271.011396)
					(mid 131.629404 -271.011396)
					(end 132.282184 -271.011396)
				)
			)
		)
	)
	(zone
		(layers "B.Cu" "In6.Cu" "In11.Cu" "In13.Cu" "In15.Cu")
		(hatch none 0.5)
		(connect_pads
			(clearance 0)
		)
		(min_thickness 0.25)
		(keepout
			(tracks not_allowed)
			(vias allowed)
			(pads allowed)
			(copperpour not_allowed)
			(footprints allowed)
		)
		(placement
			(enabled no)
			(sheetname "")
		)
		(fill yes
			(thermal_gap 0.5)
			(thermal_bridge_width 0.5)
			(island_removal_mode 0)
		)
		(polygon
			(pts
				(arc
					(start 103.618284 -289.807142)
					(mid 102.965504 -289.807142)
					(end 103.618284 -289.807142)
				)
			)
		)
	)
	(zone
		(layers "B.Cu" "In6.Cu" "In11.Cu" "In13.Cu" "In15.Cu")
		(hatch none 0.5)
		(connect_pads
			(clearance 0)
		)
		(min_thickness 0.25)
		(keepout
			(tracks not_allowed)
			(vias allowed)
			(pads allowed)
			(copperpour not_allowed)
			(footprints allowed)
		)
		(placement
			(enabled no)
			(sheetname "")
		)
		(fill yes
			(thermal_gap 0.5)
			(thermal_bridge_width 0.5)
			(island_removal_mode 0)
		)
		(polygon
			(pts
				(arc
					(start 91.760802 -239.853216)
					(mid 91.108022 -239.853216)
					(end 91.760802 -239.853216)
				)
			)
		)
	)
	(zone
		(layers "B.Cu" "In6.Cu" "In11.Cu" "In13.Cu" "In15.Cu")
		(hatch none 0.5)
		(connect_pads
			(clearance 0)
		)
		(min_thickness 0.25)
		(keepout
			(tracks not_allowed)
			(vias allowed)
			(pads allowed)
			(copperpour not_allowed)
			(footprints allowed)
		)
		(placement
			(enabled no)
			(sheetname "")
		)
		(fill yes
			(thermal_gap 0.5)
			(thermal_bridge_width 0.5)
			(island_removal_mode 0)
		)
		(polygon
			(pts
				(arc
					(start 342.630252 -277.522432)
					(mid 341.977472 -277.522432)
					(end 342.630252 -277.522432)
				)
			)
		)
	)
	(zone
		(layers "B.Cu" "In6.Cu" "In11.Cu" "In13.Cu" "In15.Cu")
		(hatch none 0.5)
		(connect_pads
			(clearance 0)
		)
		(min_thickness 0.25)
		(keepout
			(tracks not_allowed)
			(vias allowed)
			(pads allowed)
			(copperpour not_allowed)
			(footprints allowed)
		)
		(placement
			(enabled no)
			(sheetname "")
		)
		(fill yes
			(thermal_gap 0.5)
			(thermal_bridge_width 0.5)
			(island_removal_mode 0)
		)
		(polygon
			(pts
				(arc
					(start 94.690184 -277.522432)
					(mid 94.037404 -277.522432)
					(end 94.690184 -277.522432)
				)
			)
		)
	)
	(zone
		(layers "B.Cu" "In6.Cu" "In11.Cu" "In13.Cu" "In15.Cu")
		(hatch none 0.5)
		(connect_pads
			(clearance 0)
		)
		(min_thickness 0.25)
		(keepout
			(tracks not_allowed)
			(vias allowed)
			(pads allowed)
			(copperpour not_allowed)
			(footprints allowed)
		)
		(placement
			(enabled no)
			(sheetname "")
		)
		(fill yes
			(thermal_gap 0.5)
			(thermal_bridge_width 0.5)
			(island_removal_mode 0)
		)
		(polygon
			(pts
				(arc
					(start 348.269306 -288.917126)
					(mid 347.616526 -288.917126)
					(end 348.269306 -288.917126)
				)
			)
		)
	)
	(zone
		(layers "B.Cu" "In6.Cu" "In11.Cu" "In13.Cu" "In15.Cu")
		(hatch none 0.5)
		(connect_pads
			(clearance 0)
		)
		(min_thickness 0.25)
		(keepout
			(tracks not_allowed)
			(vias allowed)
			(pads allowed)
			(copperpour not_allowed)
			(footprints allowed)
		)
		(placement
			(enabled no)
			(sheetname "")
		)
		(fill yes
			(thermal_gap 0.5)
			(thermal_bridge_width 0.5)
			(island_removal_mode 0)
		)
		(polygon
			(pts
				(arc
					(start 377.29287 -249.620024)
					(mid 376.64009 -249.620024)
					(end 377.29287 -249.620024)
				)
			)
		)
	)
	(zone
		(layers "B.Cu" "In6.Cu" "In11.Cu" "In13.Cu" "In15.Cu")
		(hatch none 0.5)
		(connect_pads
			(clearance 0)
		)
		(min_thickness 0.25)
		(keepout
			(tracks not_allowed)
			(vias allowed)
			(pads allowed)
			(copperpour not_allowed)
			(footprints allowed)
		)
		(placement
			(enabled no)
			(sheetname "")
		)
		(fill yes
			(thermal_gap 0.5)
			(thermal_bridge_width 0.5)
			(island_removal_mode 0)
		)
		(polygon
			(pts
				(arc
					(start 104.088438 -288.917126)
					(mid 103.435658 -288.917126)
					(end 104.088438 -288.917126)
				)
			)
		)
	)
	(zone
		(layers "B.Cu" "In6.Cu" "In11.Cu" "In13.Cu" "In15.Cu")
		(hatch none 0.5)
		(connect_pads
			(clearance 0)
		)
		(min_thickness 0.25)
		(keepout
			(tracks not_allowed)
			(vias allowed)
			(pads allowed)
			(copperpour not_allowed)
			(footprints allowed)
		)
		(placement
			(enabled no)
			(sheetname "")
		)
		(fill yes
			(thermal_gap 0.5)
			(thermal_bridge_width 0.5)
			(island_removal_mode 0)
		)
		(polygon
			(pts
				(arc
					(start 93.750384 -256.361438)
					(mid 93.097604 -256.361438)
					(end 93.750384 -256.361438)
				)
			)
		)
	)
	(zone
		(layers "B.Cu" "In6.Cu" "In11.Cu" "In13.Cu" "In15.Cu")
		(hatch none 0.5)
		(connect_pads
			(clearance 0)
		)
		(min_thickness 0.25)
		(keepout
			(tracks not_allowed)
			(vias allowed)
			(pads allowed)
			(copperpour not_allowed)
			(footprints allowed)
		)
		(placement
			(enabled no)
			(sheetname "")
		)
		(fill yes
			(thermal_gap 0.5)
			(thermal_bridge_width 0.5)
			(island_removal_mode 0)
		)
		(polygon
			(pts
				(arc
					(start 100.219002 -217.064336)
					(mid 99.566222 -217.064336)
					(end 100.219002 -217.064336)
				)
			)
		)
	)
	(zone
		(layers "B.Cu" "In6.Cu" "In11.Cu" "In13.Cu" "In15.Cu")
		(hatch none 0.5)
		(connect_pads
			(clearance 0)
		)
		(min_thickness 0.25)
		(keepout
			(tracks not_allowed)
			(vias allowed)
			(pads allowed)
			(copperpour not_allowed)
			(footprints allowed)
		)
		(placement
			(enabled no)
			(sheetname "")
		)
		(fill yes
			(thermal_gap 0.5)
			(thermal_bridge_width 0.5)
			(island_removal_mode 0)
		)
		(polygon
			(pts
				(arc
					(start 173.122336 -305.266598)
					(mid 172.469556 -305.266598)
					(end 173.122336 -305.266598)
				)
			)
		)
	)
	(zone
		(layers "B.Cu" "In6.Cu" "In11.Cu" "In13.Cu" "In15.Cu")
		(hatch none 0.5)
		(connect_pads
			(clearance 0)
		)
		(min_thickness 0.25)
		(keepout
			(tracks not_allowed)
			(vias allowed)
			(pads allowed)
			(copperpour not_allowed)
			(footprints allowed)
		)
		(placement
			(enabled no)
			(sheetname "")
		)
		(fill yes
			(thermal_gap 0.5)
			(thermal_bridge_width 0.5)
			(island_removal_mode 0)
		)
		(polygon
			(pts
				(arc
					(start 295.230804 -226.216718)
					(mid 294.578024 -226.216718)
					(end 295.230804 -226.216718)
				)
			)
		)
	)
	(zone
		(layers "B.Cu" "In6.Cu" "In11.Cu" "In13.Cu" "In15.Cu")
		(hatch none 0.5)
		(connect_pads
			(clearance 0)
		)
		(min_thickness 0.25)
		(keepout
			(tracks not_allowed)
			(vias allowed)
			(pads allowed)
			(copperpour not_allowed)
			(footprints allowed)
		)
		(placement
			(enabled no)
			(sheetname "")
		)
		(fill yes
			(thermal_gap 0.5)
			(thermal_bridge_width 0.5)
			(island_removal_mode 0)
		)
		(polygon
			(pts
				(arc
					(start 339.810852 -262.872474)
					(mid 339.158072 -262.872474)
					(end 339.810852 -262.872474)
				)
			)
		)
	)
	(zone
		(layers "B.Cu" "In6.Cu" "In11.Cu" "In13.Cu" "In15.Cu")
		(hatch none 0.5)
		(connect_pads
			(clearance 0)
		)
		(min_thickness 0.25)
		(keepout
			(tracks not_allowed)
			(vias allowed)
			(pads allowed)
			(copperpour not_allowed)
			(footprints allowed)
		)
		(placement
			(enabled no)
			(sheetname "")
		)
		(fill yes
			(thermal_gap 0.5)
			(thermal_bridge_width 0.5)
			(island_removal_mode 0)
		)
		(polygon
			(pts
				(arc
					(start 295.230804 -228.766624)
					(mid 294.578024 -228.766624)
					(end 295.230804 -228.766624)
				)
			)
		)
	)
	(zone
		(layers "B.Cu" "In6.Cu" "In11.Cu" "In13.Cu" "In15.Cu")
		(hatch none 0.5)
		(connect_pads
			(clearance 0)
		)
		(min_thickness 0.25)
		(keepout
			(tracks not_allowed)
			(vias allowed)
			(pads allowed)
			(copperpour not_allowed)
			(footprints allowed)
		)
		(placement
			(enabled no)
			(sheetname "")
		)
		(fill yes
			(thermal_gap 0.5)
			(thermal_bridge_width 0.5)
			(island_removal_mode 0)
		)
		(polygon
			(pts
				(arc
					(start 128.993138 -288.103056)
					(mid 128.340358 -288.103056)
					(end 128.993138 -288.103056)
				)
			)
		)
	)
	(zone
		(layers "B.Cu" "In6.Cu" "In11.Cu" "In13.Cu" "In15.Cu")
		(hatch none 0.5)
		(connect_pads
			(clearance 0)
		)
		(min_thickness 0.25)
		(keepout
			(tracks not_allowed)
			(vias allowed)
			(pads allowed)
			(copperpour not_allowed)
			(footprints allowed)
		)
		(placement
			(enabled no)
			(sheetname "")
		)
		(fill yes
			(thermal_gap 0.5)
			(thermal_bridge_width 0.5)
			(island_removal_mode 0)
		)
		(polygon
			(pts
				(arc
					(start 436.150004 -233.86669)
					(mid 435.497224 -233.86669)
					(end 436.150004 -233.86669)
				)
			)
		)
	)
	(zone
		(layers "B.Cu" "In6.Cu" "In11.Cu" "In13.Cu" "In15.Cu")
		(hatch none 0.5)
		(connect_pads
			(clearance 0)
		)
		(min_thickness 0.25)
		(keepout
			(tracks not_allowed)
			(vias allowed)
			(pads allowed)
			(copperpour not_allowed)
			(footprints allowed)
		)
		(placement
			(enabled no)
			(sheetname "")
		)
		(fill yes
			(thermal_gap 0.5)
			(thermal_bridge_width 0.5)
			(island_removal_mode 0)
		)
		(polygon
			(pts
				(arc
					(start 36.303204 -293.366698)
					(mid 35.650424 -293.366698)
					(end 36.303204 -293.366698)
				)
			)
		)
	)
	(zone
		(layers "B.Cu" "In6.Cu" "In11.Cu" "In13.Cu" "In15.Cu")
		(hatch none 0.5)
		(connect_pads
			(clearance 0)
		)
		(min_thickness 0.25)
		(keepout
			(tracks not_allowed)
			(vias allowed)
			(pads allowed)
			(copperpour not_allowed)
			(footprints allowed)
		)
		(placement
			(enabled no)
			(sheetname "")
		)
		(fill yes
			(thermal_gap 0.5)
			(thermal_bridge_width 0.5)
			(island_removal_mode 0)
		)
		(polygon
			(pts
				(arc
					(start 105.857802 -217.064336)
					(mid 105.205022 -217.064336)
					(end 105.857802 -217.064336)
				)
			)
		)
	)
	(zone
		(layers "B.Cu" "In6.Cu" "In11.Cu" "In13.Cu" "In15.Cu")
		(hatch none 0.5)
		(connect_pads
			(clearance 0)
		)
		(min_thickness 0.25)
		(keepout
			(tracks not_allowed)
			(vias allowed)
			(pads allowed)
			(copperpour not_allowed)
			(footprints allowed)
		)
		(placement
			(enabled no)
			(sheetname "")
		)
		(fill yes
			(thermal_gap 0.5)
			(thermal_bridge_width 0.5)
			(island_removal_mode 0)
		)
		(polygon
			(pts
				(arc
					(start 280.143204 -235.566712)
					(mid 279.490424 -235.566712)
					(end 280.143204 -235.566712)
				)
			)
		)
	)
	(zone
		(layers "B.Cu" "In6.Cu" "In11.Cu" "In13.Cu" "In15.Cu")
		(hatch none 0.5)
		(connect_pads
			(clearance 0)
		)
		(min_thickness 0.25)
		(keepout
			(tracks not_allowed)
			(vias allowed)
			(pads allowed)
			(copperpour not_allowed)
			(footprints allowed)
		)
		(placement
			(enabled no)
			(sheetname "")
		)
		(fill yes
			(thermal_gap 0.5)
			(thermal_bridge_width 0.5)
			(island_removal_mode 0)
		)
		(polygon
			(pts
				(arc
					(start 378.342652 -274.266914)
					(mid 377.689872 -274.266914)
					(end 378.342652 -274.266914)
				)
			)
		)
	)
	(zone
		(layers "B.Cu" "In6.Cu" "In11.Cu" "In13.Cu" "In15.Cu")
		(hatch none 0.5)
		(connect_pads
			(clearance 0)
		)
		(min_thickness 0.25)
		(keepout
			(tracks not_allowed)
			(vias allowed)
			(pads allowed)
			(copperpour not_allowed)
			(footprints allowed)
		)
		(placement
			(enabled no)
			(sheetname "")
		)
		(fill yes
			(thermal_gap 0.5)
			(thermal_bridge_width 0.5)
			(island_removal_mode 0)
		)
		(polygon
			(pts
				(arc
					(start 36.303204 -309.51678)
					(mid 35.650424 -309.51678)
					(end 36.303204 -309.51678)
				)
			)
		)
	)
	(zone
		(layers "B.Cu" "In6.Cu" "In11.Cu" "In13.Cu" "In15.Cu")
		(hatch none 0.5)
		(connect_pads
			(clearance 0)
		)
		(min_thickness 0.25)
		(keepout
			(tracks not_allowed)
			(vias allowed)
			(pads allowed)
			(copperpour not_allowed)
			(footprints allowed)
		)
		(placement
			(enabled no)
			(sheetname "")
		)
		(fill yes
			(thermal_gap 0.5)
			(thermal_bridge_width 0.5)
			(island_removal_mode 0)
		)
		(polygon
			(pts
				(arc
					(start 93.640402 -231.714548)
					(mid 92.987622 -231.714548)
					(end 93.640402 -231.714548)
				)
			)
		)
	)
	(zone
		(layers "B.Cu" "In6.Cu" "In11.Cu" "In13.Cu" "In15.Cu")
		(hatch none 0.5)
		(connect_pads
			(clearance 0)
		)
		(min_thickness 0.25)
		(keepout
			(tracks not_allowed)
			(vias allowed)
			(pads allowed)
			(copperpour not_allowed)
			(footprints allowed)
		)
		(placement
			(enabled no)
			(sheetname "")
		)
		(fill yes
			(thermal_gap 0.5)
			(thermal_bridge_width 0.5)
			(island_removal_mode 0)
		)
		(polygon
			(pts
				(arc
					(start 340.281006 -257.175254)
					(mid 339.628226 -257.175254)
					(end 340.281006 -257.175254)
				)
			)
		)
	)
	(zone
		(layers "B.Cu" "In6.Cu" "In11.Cu" "In13.Cu" "In15.Cu")
		(hatch none 0.5)
		(connect_pads
			(clearance 0)
		)
		(min_thickness 0.25)
		(keepout
			(tracks not_allowed)
			(vias allowed)
			(pads allowed)
			(copperpour not_allowed)
			(footprints allowed)
		)
		(placement
			(enabled no)
			(sheetname "")
		)
		(fill yes
			(thermal_gap 0.5)
			(thermal_bridge_width 0.5)
			(island_removal_mode 0)
		)
		(polygon
			(pts
				(arc
					(start 125.703838 -288.917126)
					(mid 125.051058 -288.917126)
					(end 125.703838 -288.917126)
				)
			)
		)
	)
	(zone
		(layers "B.Cu" "In6.Cu" "In11.Cu" "In13.Cu" "In15.Cu")
		(hatch none 0.5)
		(connect_pads
			(clearance 0)
		)
		(min_thickness 0.25)
		(keepout
			(tracks not_allowed)
			(vias allowed)
			(pads allowed)
			(copperpour not_allowed)
			(footprints allowed)
		)
		(placement
			(enabled no)
			(sheetname "")
		)
		(fill yes
			(thermal_gap 0.5)
			(thermal_bridge_width 0.5)
			(island_removal_mode 0)
		)
		(polygon
			(pts
				(arc
					(start 425.162472 -306.116736)
					(mid 424.509692 -306.116736)
					(end 425.162472 -306.116736)
				)
			)
		)
	)
	(zone
		(layers "B.Cu" "In6.Cu" "In11.Cu" "In13.Cu" "In15.Cu")
		(hatch none 0.5)
		(connect_pads
			(clearance 0)
		)
		(min_thickness 0.25)
		(keepout
			(tracks not_allowed)
			(vias allowed)
			(pads allowed)
			(copperpour not_allowed)
			(footprints allowed)
		)
		(placement
			(enabled no)
			(sheetname "")
		)
		(fill yes
			(thermal_gap 0.5)
			(thermal_bridge_width 0.5)
			(island_removal_mode 0)
		)
		(polygon
			(pts
				(arc
					(start 51.390804 -231.316784)
					(mid 50.738024 -231.316784)
					(end 51.390804 -231.316784)
				)
			)
		)
	)
	(zone
		(layers "B.Cu" "In6.Cu" "In11.Cu" "In13.Cu" "In15.Cu")
		(hatch none 0.5)
		(connect_pads
			(clearance 0)
		)
		(min_thickness 0.25)
		(keepout
			(tracks not_allowed)
			(vias allowed)
			(pads allowed)
			(copperpour not_allowed)
			(footprints allowed)
		)
		(placement
			(enabled no)
			(sheetname "")
		)
		(fill yes
			(thermal_gap 0.5)
			(thermal_bridge_width 0.5)
			(island_removal_mode 0)
		)
		(polygon
			(pts
				(arc
					(start 436.150004 -316.316614)
					(mid 435.497224 -316.316614)
					(end 436.150004 -316.316614)
				)
			)
		)
	)
	(zone
		(layers "B.Cu" "In6.Cu" "In11.Cu" "In13.Cu" "In15.Cu")
		(hatch none 0.5)
		(connect_pads
			(clearance 0)
		)
		(min_thickness 0.25)
		(keepout
			(tracks not_allowed)
			(vias allowed)
			(pads allowed)
			(copperpour not_allowed)
			(footprints allowed)
		)
		(placement
			(enabled no)
			(sheetname "")
		)
		(fill yes
			(thermal_gap 0.5)
			(thermal_bridge_width 0.5)
			(island_removal_mode 0)
		)
		(polygon
			(pts
				(arc
					(start 425.162472 -227.91674)
					(mid 424.509692 -227.91674)
					(end 425.162472 -227.91674)
				)
			)
		)
	)
	(zone
		(layers "B.Cu" "In6.Cu" "In11.Cu" "In13.Cu" "In15.Cu")
		(hatch none 0.5)
		(connect_pads
			(clearance 0)
		)
		(min_thickness 0.25)
		(keepout
			(tracks not_allowed)
			(vias allowed)
			(pads allowed)
			(copperpour not_allowed)
			(footprints allowed)
		)
		(placement
			(enabled no)
			(sheetname "")
		)
		(fill yes
			(thermal_gap 0.5)
			(thermal_bridge_width 0.5)
			(island_removal_mode 0)
		)
		(polygon
			(pts
				(arc
					(start 129.932938 -265.314176)
					(mid 129.280158 -265.314176)
					(end 129.932938 -265.314176)
				)
			)
		)
	)
	(zone
		(layers "B.Cu" "In6.Cu" "In11.Cu" "In13.Cu" "In15.Cu")
		(hatch none 0.5)
		(connect_pads
			(clearance 0)
		)
		(min_thickness 0.25)
		(keepout
			(tracks not_allowed)
			(vias allowed)
			(pads allowed)
			(copperpour not_allowed)
			(footprints allowed)
		)
		(placement
			(enabled no)
			(sheetname "")
		)
		(fill yes
			(thermal_gap 0.5)
			(thermal_bridge_width 0.5)
			(island_removal_mode 0)
		)
		(polygon
			(pts
				(arc
					(start 380.11227 -217.064336)
					(mid 379.45949 -217.064336)
					(end 380.11227 -217.064336)
				)
			)
		)
	)
	(zone
		(layers "B.Cu" "In6.Cu" "In11.Cu" "In13.Cu" "In15.Cu")
		(hatch none 0.5)
		(connect_pads
			(clearance 0)
		)
		(min_thickness 0.25)
		(keepout
			(tracks not_allowed)
			(vias allowed)
			(pads allowed)
			(copperpour not_allowed)
			(footprints allowed)
		)
		(placement
			(enabled no)
			(sheetname "")
		)
		(fill yes
			(thermal_gap 0.5)
			(thermal_bridge_width 0.5)
			(island_removal_mode 0)
		)
		(polygon
			(pts
				(arc
					(start 133.229858 -18.144744)
					(mid 132.526278 -18.144744)
					(end 133.229858 -18.144744)
				)
			)
		)
	)
	(zone
		(layers "B.Cu" "In6.Cu" "In11.Cu" "In13.Cu" "In15.Cu")
		(hatch none 0.5)
		(connect_pads
			(clearance 0)
		)
		(min_thickness 0.25)
		(keepout
			(tracks not_allowed)
			(vias allowed)
			(pads allowed)
			(copperpour not_allowed)
			(footprints allowed)
		)
		(placement
			(enabled no)
			(sheetname "")
		)
		(fill yes
			(thermal_gap 0.5)
			(thermal_bridge_width 0.5)
			(island_removal_mode 0)
		)
		(polygon
			(pts
				(arc
					(start 97.039938 -288.103056)
					(mid 96.387158 -288.103056)
					(end 97.039938 -288.103056)
				)
			)
		)
	)
	(zone
		(layers "B.Cu" "In6.Cu" "In11.Cu" "In13.Cu" "In15.Cu")
		(hatch none 0.5)
		(connect_pads
			(clearance 0)
		)
		(min_thickness 0.25)
		(keepout
			(tracks not_allowed)
			(vias allowed)
			(pads allowed)
			(copperpour not_allowed)
			(footprints allowed)
		)
		(placement
			(enabled no)
			(sheetname "")
		)
		(fill yes
			(thermal_gap 0.5)
			(thermal_bridge_width 0.5)
			(island_removal_mode 0)
		)
		(polygon
			(pts
				(arc
					(start 436.150004 -238.116618)
					(mid 435.497224 -238.116618)
					(end 436.150004 -238.116618)
				)
			)
		)
	)
	(zone
		(layers "B.Cu" "In6.Cu" "In11.Cu" "In13.Cu" "In15.Cu")
		(hatch none 0.5)
		(connect_pads
			(clearance 0)
		)
		(min_thickness 0.25)
		(keepout
			(tracks not_allowed)
			(vias allowed)
			(pads allowed)
			(copperpour not_allowed)
			(footprints allowed)
		)
		(placement
			(enabled no)
			(sheetname "")
		)
		(fill yes
			(thermal_gap 0.5)
			(thermal_bridge_width 0.5)
			(island_removal_mode 0)
		)
		(polygon
			(pts
				(arc
					(start 421.062404 -226.216718)
					(mid 420.409624 -226.216718)
					(end 421.062404 -226.216718)
				)
			)
		)
	)
	(zone
		(layers "B.Cu" "In6.Cu" "In11.Cu" "In13.Cu" "In15.Cu")
		(hatch none 0.5)
		(connect_pads
			(clearance 0)
		)
		(min_thickness 0.25)
		(keepout
			(tracks not_allowed)
			(vias allowed)
			(pads allowed)
			(copperpour not_allowed)
			(footprints allowed)
		)
		(placement
			(enabled no)
			(sheetname "")
		)
		(fill yes
			(thermal_gap 0.5)
			(thermal_bridge_width 0.5)
			(island_removal_mode 0)
		)
		(polygon
			(pts
				(arc
					(start 341.58047 -234.970066)
					(mid 340.92769 -234.970066)
					(end 341.58047 -234.970066)
				)
			)
		)
	)
	(zone
		(layers "B.Cu" "In6.Cu" "In11.Cu" "In13.Cu" "In15.Cu")
		(hatch none 0.5)
		(connect_pads
			(clearance 0)
		)
		(min_thickness 0.25)
		(keepout
			(tracks not_allowed)
			(vias allowed)
			(pads allowed)
			(copperpour not_allowed)
			(footprints allowed)
		)
		(placement
			(enabled no)
			(sheetname "")
		)
		(fill yes
			(thermal_gap 0.5)
			(thermal_bridge_width 0.5)
			(island_removal_mode 0)
		)
		(polygon
			(pts
				(arc
					(start 373.53367 -218.692222)
					(mid 372.88089 -218.692222)
					(end 373.53367 -218.692222)
				)
			)
		)
	)
	(zone
		(layers "B.Cu" "In6.Cu" "In11.Cu" "In13.Cu" "In15.Cu")
		(hatch none 0.5)
		(connect_pads
			(clearance 0)
		)
		(min_thickness 0.25)
		(keepout
			(tracks not_allowed)
			(vias allowed)
			(pads allowed)
			(copperpour not_allowed)
			(footprints allowed)
		)
		(placement
			(enabled no)
			(sheetname "")
		)
		(fill yes
			(thermal_gap 0.5)
			(thermal_bridge_width 0.5)
			(island_removal_mode 0)
		)
		(polygon
			(pts
				(arc
					(start 346.389706 -288.917126)
					(mid 345.736926 -288.917126)
					(end 346.389706 -288.917126)
				)
			)
		)
	)
	(zone
		(layers "B.Cu" "In6.Cu" "In11.Cu" "In13.Cu" "In15.Cu")
		(hatch none 0.5)
		(connect_pads
			(clearance 0)
		)
		(min_thickness 0.25)
		(keepout
			(tracks not_allowed)
			(vias allowed)
			(pads allowed)
			(copperpour not_allowed)
			(footprints allowed)
		)
		(placement
			(enabled no)
			(sheetname "")
		)
		(fill yes
			(thermal_gap 0.5)
			(thermal_bridge_width 0.5)
			(island_removal_mode 0)
		)
		(polygon
			(pts
				(arc
					(start 376.35307 -247.992138)
					(mid 375.70029 -247.992138)
					(end 376.35307 -247.992138)
				)
			)
		)
	)
	(zone
		(layers "B.Cu" "In6.Cu" "In11.Cu" "In13.Cu" "In15.Cu")
		(hatch none 0.5)
		(connect_pads
			(clearance 0)
		)
		(min_thickness 0.25)
		(keepout
			(tracks not_allowed)
			(vias allowed)
			(pads allowed)
			(copperpour not_allowed)
			(footprints allowed)
		)
		(placement
			(enabled no)
			(sheetname "")
		)
		(fill yes
			(thermal_gap 0.5)
			(thermal_bridge_width 0.5)
			(island_removal_mode 0)
		)
		(polygon
			(pts
				(arc
					(start 284.243272 -206.666592)
					(mid 283.590492 -206.666592)
					(end 284.243272 -206.666592)
				)
			)
		)
	)
	(zone
		(layers "B.Cu" "In6.Cu" "In11.Cu" "In13.Cu" "In15.Cu")
		(hatch none 0.5)
		(connect_pads
			(clearance 0)
		)
		(min_thickness 0.25)
		(keepout
			(tracks not_allowed)
			(vias allowed)
			(pads allowed)
			(copperpour not_allowed)
			(footprints allowed)
		)
		(placement
			(enabled no)
			(sheetname "")
		)
		(fill yes
			(thermal_gap 0.5)
			(thermal_bridge_width 0.5)
			(island_removal_mode 0)
		)
		(polygon
			(pts
				(arc
					(start 130.762756 -240.667286)
					(mid 130.109976 -240.667286)
					(end 130.762756 -240.667286)
				)
			)
		)
	)
	(zone
		(layers "B.Cu" "In6.Cu" "In11.Cu" "In13.Cu" "In15.Cu")
		(hatch none 0.5)
		(connect_pads
			(clearance 0)
		)
		(min_thickness 0.25)
		(keepout
			(tracks not_allowed)
			(vias allowed)
			(pads allowed)
			(copperpour not_allowed)
			(footprints allowed)
		)
		(placement
			(enabled no)
			(sheetname "")
		)
		(fill yes
			(thermal_gap 0.5)
			(thermal_bridge_width 0.5)
			(island_removal_mode 0)
		)
		(polygon
			(pts
				(arc
					(start 243.469414 -57.699402)
					(mid 242.765834 -57.699402)
					(end 243.469414 -57.699402)
				)
			)
		)
	)
	(zone
		(layers "B.Cu" "In6.Cu" "In11.Cu" "In13.Cu" "In15.Cu")
		(hatch none 0.5)
		(connect_pads
			(clearance 0)
		)
		(min_thickness 0.25)
		(keepout
			(tracks not_allowed)
			(vias allowed)
			(pads allowed)
			(copperpour not_allowed)
			(footprints allowed)
		)
		(placement
			(enabled no)
			(sheetname "")
		)
		(fill yes
			(thermal_gap 0.5)
			(thermal_bridge_width 0.5)
			(island_removal_mode 0)
		)
		(polygon
			(pts
				(arc
					(start 85.652102 -224.389442)
					(mid 84.999322 -224.389442)
					(end 85.652102 -224.389442)
				)
			)
		)
	)
	(zone
		(layers "B.Cu" "In6.Cu" "In11.Cu" "In13.Cu" "In15.Cu")
		(hatch none 0.5)
		(connect_pads
			(clearance 0)
		)
		(min_thickness 0.25)
		(keepout
			(tracks not_allowed)
			(vias allowed)
			(pads allowed)
			(copperpour not_allowed)
			(footprints allowed)
		)
		(placement
			(enabled no)
			(sheetname "")
		)
		(fill yes
			(thermal_gap 0.5)
			(thermal_bridge_width 0.5)
			(island_removal_mode 0)
		)
		(polygon
			(pts
				(arc
					(start 113.846356 -217.878406)
					(mid 113.193576 -217.878406)
					(end 113.846356 -217.878406)
				)
			)
		)
	)
	(zone
		(layers "B.Cu" "In6.Cu" "In11.Cu" "In13.Cu" "In15.Cu")
		(hatch none 0.5)
		(connect_pads
			(clearance 0)
		)
		(min_thickness 0.25)
		(keepout
			(tracks not_allowed)
			(vias allowed)
			(pads allowed)
			(copperpour not_allowed)
			(footprints allowed)
		)
		(placement
			(enabled no)
			(sheetname "")
		)
		(fill yes
			(thermal_gap 0.5)
			(thermal_bridge_width 0.5)
			(island_removal_mode 0)
		)
		(polygon
			(pts
				(arc
					(start 284.243272 -261.916672)
					(mid 283.590492 -261.916672)
					(end 284.243272 -261.916672)
				)
			)
		)
	)
	(zone
		(layers "B.Cu" "In6.Cu" "In11.Cu" "In13.Cu" "In15.Cu")
		(hatch none 0.5)
		(connect_pads
			(clearance 0)
		)
		(min_thickness 0.25)
		(keepout
			(tracks not_allowed)
			(vias allowed)
			(pads allowed)
			(copperpour not_allowed)
			(footprints allowed)
		)
		(placement
			(enabled no)
			(sheetname "")
		)
		(fill yes
			(thermal_gap 0.5)
			(thermal_bridge_width 0.5)
			(island_removal_mode 0)
		)
		(polygon
			(pts
				(arc
					(start 47.290736 -198.166736)
					(mid 46.637956 -198.166736)
					(end 47.290736 -198.166736)
				)
			)
		)
	)
	(zone
		(layers "B.Cu" "In6.Cu" "In11.Cu" "In13.Cu" "In15.Cu")
		(hatch none 0.5)
		(connect_pads
			(clearance 0)
		)
		(min_thickness 0.25)
		(keepout
			(tracks not_allowed)
			(vias allowed)
			(pads allowed)
			(copperpour not_allowed)
			(footprints allowed)
		)
		(placement
			(enabled no)
			(sheetname "")
		)
		(fill yes
			(thermal_gap 0.5)
			(thermal_bridge_width 0.5)
			(island_removal_mode 0)
		)
		(polygon
			(pts
				(arc
					(start 97.979738 -255.547622)
					(mid 97.326958 -255.547622)
					(end 97.979738 -255.547622)
				)
			)
		)
	)
	(zone
		(layers "B.Cu" "In6.Cu" "In11.Cu" "In13.Cu" "In15.Cu")
		(hatch none 0.5)
		(connect_pads
			(clearance 0)
		)
		(min_thickness 0.25)
		(keepout
			(tracks not_allowed)
			(vias allowed)
			(pads allowed)
			(copperpour not_allowed)
			(footprints allowed)
		)
		(placement
			(enabled no)
			(sheetname "")
		)
		(fill yes
			(thermal_gap 0.5)
			(thermal_bridge_width 0.5)
			(island_removal_mode 0)
		)
		(polygon
			(pts
				(arc
					(start 132.642356 -237.411514)
					(mid 131.989576 -237.411514)
					(end 132.642356 -237.411514)
				)
			)
		)
	)
	(zone
		(layers "B.Cu" "In6.Cu" "In11.Cu" "In13.Cu" "In15.Cu")
		(hatch none 0.5)
		(connect_pads
			(clearance 0)
		)
		(min_thickness 0.25)
		(keepout
			(tracks not_allowed)
			(vias allowed)
			(pads allowed)
			(copperpour not_allowed)
			(footprints allowed)
		)
		(placement
			(enabled no)
			(sheetname "")
		)
		(fill yes
			(thermal_gap 0.5)
			(thermal_bridge_width 0.5)
			(island_removal_mode 0)
		)
		(polygon
			(pts
				(arc
					(start 188.209936 -266.1666)
					(mid 187.557156 -266.1666)
					(end 188.209936 -266.1666)
				)
			)
		)
	)
	(zone
		(layers "B.Cu" "In6.Cu" "In11.Cu" "In13.Cu" "In15.Cu")
		(hatch none 0.5)
		(connect_pads
			(clearance 0)
		)
		(min_thickness 0.25)
		(keepout
			(tracks not_allowed)
			(vias allowed)
			(pads allowed)
			(copperpour not_allowed)
			(footprints allowed)
		)
		(placement
			(enabled no)
			(sheetname "")
		)
		(fill yes
			(thermal_gap 0.5)
			(thermal_bridge_width 0.5)
			(island_removal_mode 0)
		)
		(polygon
			(pts
				(arc
					(start 129.352802 -226.831144)
					(mid 128.700022 -226.831144)
					(end 129.352802 -226.831144)
				)
			)
		)
	)
	(zone
		(layers "B.Cu" "In6.Cu" "In11.Cu" "In13.Cu" "In15.Cu")
		(hatch none 0.5)
		(connect_pads
			(clearance 0)
		)
		(min_thickness 0.25)
		(keepout
			(tracks not_allowed)
			(vias allowed)
			(pads allowed)
			(copperpour not_allowed)
			(footprints allowed)
		)
		(placement
			(enabled no)
			(sheetname "")
		)
		(fill yes
			(thermal_gap 0.5)
			(thermal_bridge_width 0.5)
			(island_removal_mode 0)
		)
		(polygon
			(pts
				(arc
					(start 92.700602 -233.34218)
					(mid 92.047822 -233.34218)
					(end 92.700602 -233.34218)
				)
			)
		)
	)
	(zone
		(layers "B.Cu" "In6.Cu" "In11.Cu" "In13.Cu" "In15.Cu")
		(hatch none 0.5)
		(connect_pads
			(clearance 0)
		)
		(min_thickness 0.25)
		(keepout
			(tracks not_allowed)
			(vias allowed)
			(pads allowed)
			(copperpour not_allowed)
			(footprints allowed)
		)
		(placement
			(enabled no)
			(sheetname "")
		)
		(fill yes
			(thermal_gap 0.5)
			(thermal_bridge_width 0.5)
			(island_removal_mode 0)
		)
		(polygon
			(pts
				(arc
					(start 118.545356 -217.878406)
					(mid 117.892576 -217.878406)
					(end 118.545356 -217.878406)
				)
			)
		)
	)
	(zone
		(layers "B.Cu" "In6.Cu" "In11.Cu" "In13.Cu" "In15.Cu")
		(hatch none 0.5)
		(connect_pads
			(clearance 0)
		)
		(min_thickness 0.25)
		(keepout
			(tracks not_allowed)
			(vias allowed)
			(pads allowed)
			(copperpour not_allowed)
			(footprints allowed)
		)
		(placement
			(enabled no)
			(sheetname "")
		)
		(fill yes
			(thermal_gap 0.5)
			(thermal_bridge_width 0.5)
			(island_removal_mode 0)
		)
		(polygon
			(pts
				(arc
					(start 177.222404 -283.166566)
					(mid 176.569624 -283.166566)
					(end 177.222404 -283.166566)
				)
			)
		)
	)
	(zone
		(layers "B.Cu" "In6.Cu" "In11.Cu" "In13.Cu" "In15.Cu")
		(hatch none 0.5)
		(connect_pads
			(clearance 0)
		)
		(min_thickness 0.25)
		(keepout
			(tracks not_allowed)
			(vias allowed)
			(pads allowed)
			(copperpour not_allowed)
			(footprints allowed)
		)
		(placement
			(enabled no)
			(sheetname "")
		)
		(fill yes
			(thermal_gap 0.5)
			(thermal_bridge_width 0.5)
			(island_removal_mode 0)
		)
		(polygon
			(pts
				(arc
					(start 376.463306 -288.917126)
					(mid 375.810526 -288.917126)
					(end 376.463306 -288.917126)
				)
			)
		)
	)
	(zone
		(layers "B.Cu" "In6.Cu" "In11.Cu" "In13.Cu" "In15.Cu")
		(hatch none 0.5)
		(connect_pads
			(clearance 0)
		)
		(min_thickness 0.25)
		(keepout
			(tracks not_allowed)
			(vias allowed)
			(pads allowed)
			(copperpour not_allowed)
			(footprints allowed)
		)
		(placement
			(enabled no)
			(sheetname "")
		)
		(fill yes
			(thermal_gap 0.5)
			(thermal_bridge_width 0.5)
			(island_removal_mode 0)
		)
		(polygon
			(pts
				(arc
					(start 262.589772 5.031994)
					(mid 261.886192 5.031994)
					(end 262.589772 5.031994)
				)
			)
		)
	)
	(zone
		(layers "B.Cu" "In6.Cu" "In11.Cu" "In13.Cu" "In15.Cu")
		(hatch none 0.5)
		(connect_pads
			(clearance 0)
		)
		(min_thickness 0.25)
		(keepout
			(tracks not_allowed)
			(vias allowed)
			(pads allowed)
			(copperpour not_allowed)
			(footprints allowed)
		)
		(placement
			(enabled no)
			(sheetname "")
		)
		(fill yes
			(thermal_gap 0.5)
			(thermal_bridge_width 0.5)
			(island_removal_mode 0)
		)
		(polygon
			(pts
				(arc
					(start 284.243272 -248.31675)
					(mid 283.590492 -248.31675)
					(end 284.243272 -248.31675)
				)
			)
		)
	)
	(zone
		(layers "B.Cu" "In6.Cu" "In11.Cu" "In13.Cu" "In15.Cu")
		(hatch none 0.5)
		(connect_pads
			(clearance 0)
		)
		(min_thickness 0.25)
		(keepout
			(tracks not_allowed)
			(vias allowed)
			(pads allowed)
			(copperpour not_allowed)
			(footprints allowed)
		)
		(placement
			(enabled no)
			(sheetname "")
		)
		(fill yes
			(thermal_gap 0.5)
			(thermal_bridge_width 0.5)
			(island_removal_mode 0)
		)
		(polygon
			(pts
				(arc
					(start 192.310004 -250.016772)
					(mid 191.657224 -250.016772)
					(end 192.310004 -250.016772)
				)
			)
		)
	)
	(zone
		(layers "B.Cu" "In6.Cu" "In11.Cu" "In13.Cu" "In15.Cu")
		(hatch none 0.5)
		(connect_pads
			(clearance 0)
		)
		(min_thickness 0.25)
		(keepout
			(tracks not_allowed)
			(vias allowed)
			(pads allowed)
			(copperpour not_allowed)
			(footprints allowed)
		)
		(placement
			(enabled no)
			(sheetname "")
		)
		(fill yes
			(thermal_gap 0.5)
			(thermal_bridge_width 0.5)
			(island_removal_mode 0)
		)
		(polygon
			(pts
				(arc
					(start 192.310004 -290.816538)
					(mid 191.657224 -290.816538)
					(end 192.310004 -290.816538)
				)
			)
		)
	)
	(zone
		(layers "B.Cu" "In6.Cu" "In11.Cu" "In13.Cu" "In15.Cu")
		(hatch none 0.5)
		(connect_pads
			(clearance 0)
		)
		(min_thickness 0.25)
		(keepout
			(tracks not_allowed)
			(vias allowed)
			(pads allowed)
			(copperpour not_allowed)
			(footprints allowed)
		)
		(placement
			(enabled no)
			(sheetname "")
		)
		(fill yes
			(thermal_gap 0.5)
			(thermal_bridge_width 0.5)
			(island_removal_mode 0)
		)
		(polygon
			(pts
				(arc
					(start 340.64067 -241.481102)
					(mid 339.98789 -241.481102)
					(end 340.64067 -241.481102)
				)
			)
		)
	)
	(zone
		(layers "B.Cu" "In6.Cu" "In11.Cu" "In13.Cu" "In15.Cu")
		(hatch none 0.5)
		(connect_pads
			(clearance 0)
		)
		(min_thickness 0.25)
		(keepout
			(tracks not_allowed)
			(vias allowed)
			(pads allowed)
			(copperpour not_allowed)
			(footprints allowed)
		)
		(placement
			(enabled no)
			(sheetname "")
		)
		(fill yes
			(thermal_gap 0.5)
			(thermal_bridge_width 0.5)
			(island_removal_mode 0)
		)
		(polygon
			(pts
				(arc
					(start 173.122336 -299.316648)
					(mid 172.469556 -299.316648)
					(end 173.122336 -299.316648)
				)
			)
		)
	)
	(zone
		(layers "B.Cu" "In6.Cu" "In11.Cu" "In13.Cu" "In15.Cu")
		(hatch none 0.5)
		(connect_pads
			(clearance 0)
		)
		(min_thickness 0.25)
		(keepout
			(tracks not_allowed)
			(vias allowed)
			(pads allowed)
			(copperpour not_allowed)
			(footprints allowed)
		)
		(placement
			(enabled no)
			(sheetname "")
		)
		(fill yes
			(thermal_gap 0.5)
			(thermal_bridge_width 0.5)
			(island_removal_mode 0)
		)
		(polygon
			(pts
				(arc
					(start 130.872738 -270.19758)
					(mid 130.219958 -270.19758)
					(end 130.872738 -270.19758)
				)
			)
		)
	)
	(zone
		(layers "B.Cu" "In6.Cu" "In11.Cu" "In13.Cu" "In15.Cu")
		(hatch none 0.5)
		(connect_pads
			(clearance 0)
		)
		(min_thickness 0.25)
		(keepout
			(tracks not_allowed)
			(vias allowed)
			(pads allowed)
			(copperpour not_allowed)
			(footprints allowed)
		)
		(placement
			(enabled no)
			(sheetname "")
		)
		(fill yes
			(thermal_gap 0.5)
			(thermal_bridge_width 0.5)
			(island_removal_mode 0)
		)
		(polygon
			(pts
				(arc
					(start 192.310004 -212.616796)
					(mid 191.657224 -212.616796)
					(end 192.310004 -212.616796)
				)
			)
		)
	)
	(zone
		(layers "B.Cu" "In6.Cu" "In11.Cu" "In13.Cu" "In15.Cu")
		(hatch none 0.5)
		(connect_pads
			(clearance 0)
		)
		(min_thickness 0.25)
		(keepout
			(tracks not_allowed)
			(vias allowed)
			(pads allowed)
			(copperpour not_allowed)
			(footprints allowed)
		)
		(placement
			(enabled no)
			(sheetname "")
		)
		(fill yes
			(thermal_gap 0.5)
			(thermal_bridge_width 0.5)
			(island_removal_mode 0)
		)
		(polygon
			(pts
				(arc
					(start 129.352802 -218.692222)
					(mid 128.700022 -218.692222)
					(end 129.352802 -218.692222)
				)
			)
		)
	)
	(zone
		(layers "B.Cu" "In6.Cu" "In11.Cu" "In13.Cu" "In15.Cu")
		(hatch none 0.5)
		(connect_pads
			(clearance 0)
		)
		(min_thickness 0.25)
		(keepout
			(tracks not_allowed)
			(vias allowed)
			(pads allowed)
			(copperpour not_allowed)
			(footprints allowed)
		)
		(placement
			(enabled no)
			(sheetname "")
		)
		(fill yes
			(thermal_gap 0.5)
			(thermal_bridge_width 0.5)
			(island_removal_mode 0)
		)
		(polygon
			(pts
				(arc
					(start 341.58047 -230.086662)
					(mid 340.92769 -230.086662)
					(end 341.58047 -230.086662)
				)
			)
		)
	)
	(zone
		(layers "B.Cu" "In6.Cu" "In11.Cu" "In13.Cu" "In15.Cu")
		(hatch none 0.5)
		(connect_pads
			(clearance 0)
		)
		(min_thickness 0.25)
		(keepout
			(tracks not_allowed)
			(vias allowed)
			(pads allowed)
			(copperpour not_allowed)
			(footprints allowed)
		)
		(placement
			(enabled no)
			(sheetname "")
		)
		(fill yes
			(thermal_gap 0.5)
			(thermal_bridge_width 0.5)
			(island_removal_mode 0)
		)
		(polygon
			(pts
				(arc
					(start 132.282184 -274.266914)
					(mid 131.629404 -274.266914)
					(end 132.282184 -274.266914)
				)
			)
		)
	)
	(zone
		(layers "B.Cu" "In6.Cu" "In11.Cu" "In13.Cu" "In15.Cu")
		(hatch none 0.5)
		(connect_pads
			(clearance 0)
		)
		(min_thickness 0.25)
		(keepout
			(tracks not_allowed)
			(vias allowed)
			(pads allowed)
			(copperpour not_allowed)
			(footprints allowed)
		)
		(placement
			(enabled no)
			(sheetname "")
		)
		(fill yes
			(thermal_gap 0.5)
			(thermal_bridge_width 0.5)
			(island_removal_mode 0)
		)
		(polygon
			(pts
				(arc
					(start 32.203136 -247.466612)
					(mid 31.550356 -247.466612)
					(end 32.203136 -247.466612)
				)
			)
		)
	)
	(zone
		(layers "B.Cu" "In6.Cu" "In11.Cu" "In13.Cu" "In15.Cu")
		(hatch none 0.5)
		(connect_pads
			(clearance 0)
		)
		(min_thickness 0.25)
		(keepout
			(tracks not_allowed)
			(vias allowed)
			(pads allowed)
			(copperpour not_allowed)
			(footprints allowed)
		)
		(placement
			(enabled no)
			(sheetname "")
		)
		(fill yes
			(thermal_gap 0.5)
			(thermal_bridge_width 0.5)
			(island_removal_mode 0)
		)
		(polygon
			(pts
				(arc
					(start 128.993138 -257.175254)
					(mid 128.340358 -257.175254)
					(end 128.993138 -257.175254)
				)
			)
		)
	)
	(zone
		(layers "B.Cu" "In6.Cu" "In11.Cu" "In13.Cu" "In15.Cu")
		(hatch none 0.5)
		(connect_pads
			(clearance 0)
		)
		(min_thickness 0.25)
		(keepout
			(tracks not_allowed)
			(vias allowed)
			(pads allowed)
			(copperpour not_allowed)
			(footprints allowed)
		)
		(placement
			(enabled no)
			(sheetname "")
		)
		(fill yes
			(thermal_gap 0.5)
			(thermal_bridge_width 0.5)
			(island_removal_mode 0)
		)
		(polygon
			(pts
				(arc
					(start 173.122336 -280.61666)
					(mid 172.469556 -280.61666)
					(end 173.122336 -280.61666)
				)
			)
		)
	)
	(zone
		(layers "B.Cu" "In6.Cu" "In11.Cu" "In13.Cu" "In15.Cu")
		(hatch none 0.5)
		(connect_pads
			(clearance 0)
		)
		(min_thickness 0.25)
		(keepout
			(tracks not_allowed)
			(vias allowed)
			(pads allowed)
			(copperpour not_allowed)
			(footprints allowed)
		)
		(placement
			(enabled no)
			(sheetname "")
		)
		(fill yes
			(thermal_gap 0.5)
			(thermal_bridge_width 0.5)
			(island_removal_mode 0)
		)
		(polygon
			(pts
				(arc
					(start 379.642624 -229.272846)
					(mid 378.989844 -229.272846)
					(end 379.642624 -229.272846)
				)
			)
		)
	)
	(zone
		(layers "B.Cu" "In6.Cu" "In11.Cu" "In13.Cu" "In15.Cu")
		(hatch none 0.5)
		(connect_pads
			(clearance 0)
		)
		(min_thickness 0.25)
		(keepout
			(tracks not_allowed)
			(vias allowed)
			(pads allowed)
			(copperpour not_allowed)
			(footprints allowed)
		)
		(placement
			(enabled no)
			(sheetname "")
		)
		(fill yes
			(thermal_gap 0.5)
			(thermal_bridge_width 0.5)
			(island_removal_mode 0)
		)
		(polygon
			(pts
				(arc
					(start 32.203136 -213.46668)
					(mid 31.550356 -213.46668)
					(end 32.203136 -213.46668)
				)
			)
		)
	)
	(zone
		(layers "B.Cu" "In6.Cu" "In11.Cu" "In13.Cu" "In15.Cu")
		(hatch none 0.5)
		(connect_pads
			(clearance 0)
		)
		(min_thickness 0.25)
		(keepout
			(tracks not_allowed)
			(vias allowed)
			(pads allowed)
			(copperpour not_allowed)
			(footprints allowed)
		)
		(placement
			(enabled no)
			(sheetname "")
		)
		(fill yes
			(thermal_gap 0.5)
			(thermal_bridge_width 0.5)
			(island_removal_mode 0)
		)
		(polygon
			(pts
				(arc
					(start 333.59217 -226.017328)
					(mid 332.93939 -226.017328)
					(end 333.59217 -226.017328)
				)
			)
		)
	)
	(zone
		(layers "B.Cu" "In6.Cu" "In11.Cu" "In13.Cu" "In15.Cu")
		(hatch none 0.5)
		(connect_pads
			(clearance 0)
		)
		(min_thickness 0.25)
		(keepout
			(tracks not_allowed)
			(vias allowed)
			(pads allowed)
			(copperpour not_allowed)
			(footprints allowed)
		)
		(placement
			(enabled no)
			(sheetname "")
		)
		(fill yes
			(thermal_gap 0.5)
			(thermal_bridge_width 0.5)
			(island_removal_mode 0)
		)
		(polygon
			(pts
				(arc
					(start 340.64067 -233.34218)
					(mid 339.98789 -233.34218)
					(end 340.64067 -233.34218)
				)
			)
		)
	)
	(zone
		(layers "B.Cu" "In6.Cu" "In11.Cu" "In13.Cu" "In15.Cu")
		(hatch none 0.5)
		(connect_pads
			(clearance 0)
		)
		(min_thickness 0.25)
		(keepout
			(tracks not_allowed)
			(vias allowed)
			(pads allowed)
			(copperpour not_allowed)
			(footprints allowed)
		)
		(placement
			(enabled no)
			(sheetname "")
		)
		(fill yes
			(thermal_gap 0.5)
			(thermal_bridge_width 0.5)
			(island_removal_mode 0)
		)
		(polygon
			(pts
				(arc
					(start 192.310004 -309.516526)
					(mid 191.657224 -309.516526)
					(end 192.310004 -309.516526)
				)
			)
		)
	)
	(zone
		(layers "B.Cu" "In6.Cu" "In11.Cu" "In13.Cu" "In15.Cu")
		(hatch none 0.5)
		(connect_pads
			(clearance 0)
		)
		(min_thickness 0.25)
		(keepout
			(tracks not_allowed)
			(vias allowed)
			(pads allowed)
			(copperpour not_allowed)
			(footprints allowed)
		)
		(placement
			(enabled no)
			(sheetname "")
		)
		(fill yes
			(thermal_gap 0.5)
			(thermal_bridge_width 0.5)
			(island_removal_mode 0)
		)
		(polygon
			(pts
				(arc
					(start 92.700602 -241.481102)
					(mid 92.047822 -241.481102)
					(end 92.700602 -241.481102)
				)
			)
		)
	)
	(zone
		(layers "B.Cu" "In6.Cu" "In11.Cu" "In13.Cu" "In15.Cu")
		(hatch none 0.5)
		(connect_pads
			(clearance 0)
		)
		(min_thickness 0.25)
		(keepout
			(tracks not_allowed)
			(vias allowed)
			(pads allowed)
			(copperpour not_allowed)
			(footprints allowed)
		)
		(placement
			(enabled no)
			(sheetname "")
		)
		(fill yes
			(thermal_gap 0.5)
			(thermal_bridge_width 0.5)
			(island_removal_mode 0)
		)
		(polygon
			(pts
				(arc
					(start 94.220538 -263.686544)
					(mid 93.567758 -263.686544)
					(end 94.220538 -263.686544)
				)
			)
		)
	)
	(zone
		(layers "B.Cu" "In6.Cu" "In11.Cu" "In13.Cu" "In15.Cu")
		(hatch none 0.5)
		(connect_pads
			(clearance 0)
		)
		(min_thickness 0.25)
		(keepout
			(tracks not_allowed)
			(vias allowed)
			(pads allowed)
			(copperpour not_allowed)
			(footprints allowed)
		)
		(placement
			(enabled no)
			(sheetname "")
		)
		(fill yes
			(thermal_gap 0.5)
			(thermal_bridge_width 0.5)
			(island_removal_mode 0)
		)
		(polygon
			(pts
				(arc
					(start 97.979484 -289.807142)
					(mid 97.326704 -289.807142)
					(end 97.979484 -289.807142)
				)
			)
		)
	)
	(zone
		(layers "B.Cu" "In6.Cu" "In11.Cu" "In13.Cu" "In15.Cu")
		(hatch none 0.5)
		(connect_pads
			(clearance 0)
		)
		(min_thickness 0.25)
		(keepout
			(tracks not_allowed)
			(vias allowed)
			(pads allowed)
			(copperpour not_allowed)
			(footprints allowed)
		)
		(placement
			(enabled no)
			(sheetname "")
		)
		(fill yes
			(thermal_gap 0.5)
			(thermal_bridge_width 0.5)
			(island_removal_mode 0)
		)
		(polygon
			(pts
				(arc
					(start 188.209936 -249.166634)
					(mid 187.557156 -249.166634)
					(end 188.209936 -249.166634)
				)
			)
		)
	)
	(zone
		(layers "B.Cu" "In6.Cu" "In11.Cu" "In13.Cu" "In15.Cu")
		(hatch none 0.5)
		(connect_pads
			(clearance 0)
		)
		(min_thickness 0.25)
		(keepout
			(tracks not_allowed)
			(vias allowed)
			(pads allowed)
			(copperpour not_allowed)
			(footprints allowed)
		)
		(placement
			(enabled no)
			(sheetname "")
		)
		(fill yes
			(thermal_gap 0.5)
			(thermal_bridge_width 0.5)
			(island_removal_mode 0)
		)
		(polygon
			(pts
				(arc
					(start 299.356272 -306.116736)
					(mid 298.703492 -306.116736)
					(end 299.356272 -306.116736)
				)
			)
		)
	)
	(zone
		(layers "B.Cu" "In6.Cu" "In11.Cu" "In13.Cu" "In15.Cu")
		(hatch none 0.5)
		(connect_pads
			(clearance 0)
		)
		(min_thickness 0.25)
		(keepout
			(tracks not_allowed)
			(vias allowed)
			(pads allowed)
			(copperpour not_allowed)
			(footprints allowed)
		)
		(placement
			(enabled no)
			(sheetname "")
		)
		(fill yes
			(thermal_gap 0.5)
			(thermal_bridge_width 0.5)
			(island_removal_mode 0)
		)
		(polygon
			(pts
				(arc
					(start 347.799152 -289.807142)
					(mid 347.146372 -289.807142)
					(end 347.799152 -289.807142)
				)
			)
		)
	)
	(zone
		(layers "B.Cu" "In6.Cu" "In11.Cu" "In13.Cu" "In15.Cu")
		(hatch none 0.5)
		(connect_pads
			(clearance 0)
		)
		(min_thickness 0.25)
		(keepout
			(tracks not_allowed)
			(vias allowed)
			(pads allowed)
			(copperpour not_allowed)
			(footprints allowed)
		)
		(placement
			(enabled no)
			(sheetname "")
		)
		(fill yes
			(thermal_gap 0.5)
			(thermal_bridge_width 0.5)
			(island_removal_mode 0)
		)
		(polygon
			(pts
				(arc
					(start 440.250072 -289.11677)
					(mid 439.597292 -289.11677)
					(end 440.250072 -289.11677)
				)
			)
		)
	)
	(zone
		(layers "B.Cu" "In6.Cu" "In11.Cu" "In13.Cu" "In15.Cu")
		(hatch none 0.5)
		(connect_pads
			(clearance 0)
		)
		(min_thickness 0.25)
		(keepout
			(tracks not_allowed)
			(vias allowed)
			(pads allowed)
			(copperpour not_allowed)
			(footprints allowed)
		)
		(placement
			(enabled no)
			(sheetname "")
		)
		(fill yes
			(thermal_gap 0.5)
			(thermal_bridge_width 0.5)
			(island_removal_mode 0)
		)
		(polygon
			(pts
				(arc
					(start 192.310004 -315.46673)
					(mid 191.657224 -315.46673)
					(end 192.310004 -315.46673)
				)
			)
		)
	)
	(zone
		(layers "B.Cu" "In6.Cu" "In11.Cu" "In13.Cu" "In15.Cu")
		(hatch none 0.5)
		(connect_pads
			(clearance 0)
		)
		(min_thickness 0.25)
		(keepout
			(tracks not_allowed)
			(vias allowed)
			(pads allowed)
			(copperpour not_allowed)
			(footprints allowed)
		)
		(placement
			(enabled no)
			(sheetname "")
		)
		(fill yes
			(thermal_gap 0.5)
			(thermal_bridge_width 0.5)
			(island_removal_mode 0)
		)
		(polygon
			(pts
				(arc
					(start 93.750384 -275.8948)
					(mid 93.097604 -275.8948)
					(end 93.750384 -275.8948)
				)
			)
		)
	)
	(zone
		(layers "B.Cu" "In6.Cu" "In11.Cu" "In13.Cu" "In15.Cu")
		(hatch none 0.5)
		(connect_pads
			(clearance 0)
		)
		(min_thickness 0.25)
		(keepout
			(tracks not_allowed)
			(vias allowed)
			(pads allowed)
			(copperpour not_allowed)
			(footprints allowed)
		)
		(placement
			(enabled no)
			(sheetname "")
		)
		(fill yes
			(thermal_gap 0.5)
			(thermal_bridge_width 0.5)
			(island_removal_mode 0)
		)
		(polygon
			(pts
				(arc
					(start 352.028506 -288.917126)
					(mid 351.375726 -288.917126)
					(end 352.028506 -288.917126)
				)
			)
		)
	)
	(zone
		(layers "B.Cu" "In6.Cu" "In11.Cu" "In13.Cu" "In15.Cu")
		(hatch none 0.5)
		(connect_pads
			(clearance 0)
		)
		(min_thickness 0.25)
		(keepout
			(tracks not_allowed)
			(vias allowed)
			(pads allowed)
			(copperpour not_allowed)
			(footprints allowed)
		)
		(placement
			(enabled no)
			(sheetname "")
		)
		(fill yes
			(thermal_gap 0.5)
			(thermal_bridge_width 0.5)
			(island_removal_mode 0)
		)
		(polygon
			(pts
				(arc
					(start 121.474738 -288.103056)
					(mid 120.821958 -288.103056)
					(end 121.474738 -288.103056)
				)
			)
		)
	)
	(zone
		(layers "B.Cu" "In6.Cu" "In11.Cu" "In13.Cu" "In15.Cu")
		(hatch none 0.5)
		(connect_pads
			(clearance 0)
		)
		(min_thickness 0.25)
		(keepout
			(tracks not_allowed)
			(vias allowed)
			(pads allowed)
			(copperpour not_allowed)
			(footprints allowed)
		)
		(placement
			(enabled no)
			(sheetname "")
		)
		(fill yes
			(thermal_gap 0.5)
			(thermal_bridge_width 0.5)
			(island_removal_mode 0)
		)
		(polygon
			(pts
				(arc
					(start 377.873006 -260.430772)
					(mid 377.220226 -260.430772)
					(end 377.873006 -260.430772)
				)
			)
		)
	)
	(zone
		(layers "B.Cu" "In6.Cu" "In11.Cu" "In13.Cu" "In15.Cu")
		(hatch none 0.5)
		(connect_pads
			(clearance 0)
		)
		(min_thickness 0.25)
		(keepout
			(tracks not_allowed)
			(vias allowed)
			(pads allowed)
			(copperpour not_allowed)
			(footprints allowed)
		)
		(placement
			(enabled no)
			(sheetname "")
		)
		(fill yes
			(thermal_gap 0.5)
			(thermal_bridge_width 0.5)
			(island_removal_mode 0)
		)
		(polygon
			(pts
				(arc
					(start 440.250072 -237.266734)
					(mid 439.597292 -237.266734)
					(end 440.250072 -237.266734)
				)
			)
		)
	)
	(zone
		(layers "B.Cu" "In6.Cu" "In11.Cu" "In13.Cu" "In15.Cu")
		(hatch none 0.5)
		(connect_pads
			(clearance 0)
		)
		(min_thickness 0.25)
		(keepout
			(tracks not_allowed)
			(vias allowed)
			(pads allowed)
			(copperpour not_allowed)
			(footprints allowed)
		)
		(placement
			(enabled no)
			(sheetname "")
		)
		(fill yes
			(thermal_gap 0.5)
			(thermal_bridge_width 0.5)
			(island_removal_mode 0)
		)
		(polygon
			(pts
				(arc
					(start 127.003556 -217.878406)
					(mid 126.350776 -217.878406)
					(end 127.003556 -217.878406)
				)
			)
		)
	)
	(zone
		(layers "B.Cu" "In6.Cu" "In11.Cu" "In13.Cu" "In15.Cu")
		(hatch none 0.5)
		(connect_pads
			(clearance 0)
		)
		(min_thickness 0.25)
		(keepout
			(tracks not_allowed)
			(vias allowed)
			(pads allowed)
			(copperpour not_allowed)
			(footprints allowed)
		)
		(placement
			(enabled no)
			(sheetname "")
		)
		(fill yes
			(thermal_gap 0.5)
			(thermal_bridge_width 0.5)
			(island_removal_mode 0)
		)
		(polygon
			(pts
				(arc
					(start 131.812538 -270.19758)
					(mid 131.159758 -270.19758)
					(end 131.812538 -270.19758)
				)
			)
		)
	)
	(zone
		(layers "B.Cu" "In6.Cu" "In11.Cu" "In13.Cu" "In15.Cu")
		(hatch none 0.5)
		(connect_pads
			(clearance 0)
		)
		(min_thickness 0.25)
		(keepout
			(tracks not_allowed)
			(vias allowed)
			(pads allowed)
			(copperpour not_allowed)
			(footprints allowed)
		)
		(placement
			(enabled no)
			(sheetname "")
		)
		(fill yes
			(thermal_gap 0.5)
			(thermal_bridge_width 0.5)
			(island_removal_mode 0)
		)
		(polygon
			(pts
				(arc
					(start 96.929956 -217.878406)
					(mid 96.277176 -217.878406)
					(end 96.929956 -217.878406)
				)
			)
		)
	)
	(zone
		(layers "B.Cu" "In6.Cu" "In11.Cu" "In13.Cu" "In15.Cu")
		(hatch none 0.5)
		(connect_pads
			(clearance 0)
		)
		(min_thickness 0.25)
		(keepout
			(tracks not_allowed)
			(vias allowed)
			(pads allowed)
			(copperpour not_allowed)
			(footprints allowed)
		)
		(placement
			(enabled no)
			(sheetname "")
		)
		(fill yes
			(thermal_gap 0.5)
			(thermal_bridge_width 0.5)
			(island_removal_mode 0)
		)
		(polygon
			(pts
				(arc
					(start 94.580202 -230.086662)
					(mid 93.927422 -230.086662)
					(end 94.580202 -230.086662)
				)
			)
		)
	)
	(zone
		(layers "B.Cu" "In6.Cu" "In11.Cu" "In13.Cu" "In15.Cu")
		(hatch none 0.5)
		(connect_pads
			(clearance 0)
		)
		(min_thickness 0.25)
		(keepout
			(tracks not_allowed)
			(vias allowed)
			(pads allowed)
			(copperpour not_allowed)
			(footprints allowed)
		)
		(placement
			(enabled no)
			(sheetname "")
		)
		(fill yes
			(thermal_gap 0.5)
			(thermal_bridge_width 0.5)
			(island_removal_mode 0)
		)
		(polygon
			(pts
				(arc
					(start 177.222404 -285.716726)
					(mid 176.569624 -285.716726)
					(end 177.222404 -285.716726)
				)
			)
		)
	)
	(zone
		(layers "B.Cu" "In6.Cu" "In11.Cu" "In13.Cu" "In15.Cu")
		(hatch none 0.5)
		(connect_pads
			(clearance 0)
		)
		(min_thickness 0.25)
		(keepout
			(tracks not_allowed)
			(vias allowed)
			(pads allowed)
			(copperpour not_allowed)
			(footprints allowed)
		)
		(placement
			(enabled no)
			(sheetname "")
		)
		(fill yes
			(thermal_gap 0.5)
			(thermal_bridge_width 0.5)
			(island_removal_mode 0)
		)
		(polygon
			(pts
				(arc
					(start 192.310004 -244.916706)
					(mid 191.657224 -244.916706)
					(end 192.310004 -244.916706)
				)
			)
		)
	)
	(zone
		(layers "B.Cu" "In6.Cu" "In11.Cu" "In13.Cu" "In15.Cu")
		(hatch none 0.5)
		(connect_pads
			(clearance 0)
		)
		(min_thickness 0.25)
		(keepout
			(tracks not_allowed)
			(vias allowed)
			(pads allowed)
			(copperpour not_allowed)
			(footprints allowed)
		)
		(placement
			(enabled no)
			(sheetname "")
		)
		(fill yes
			(thermal_gap 0.5)
			(thermal_bridge_width 0.5)
			(island_removal_mode 0)
		)
		(polygon
			(pts
				(arc
					(start 99.859084 -289.807142)
					(mid 99.206304 -289.807142)
					(end 99.859084 -289.807142)
				)
			)
		)
	)
	(zone
		(layers "B.Cu" "In6.Cu" "In11.Cu" "In13.Cu" "In15.Cu")
		(hatch none 0.5)
		(connect_pads
			(clearance 0)
		)
		(min_thickness 0.25)
		(keepout
			(tracks not_allowed)
			(vias allowed)
			(pads allowed)
			(copperpour not_allowed)
			(footprints allowed)
		)
		(placement
			(enabled no)
			(sheetname "")
		)
		(fill yes
			(thermal_gap 0.5)
			(thermal_bridge_width 0.5)
			(island_removal_mode 0)
		)
		(polygon
			(pts
				(arc
					(start 346.749624 -217.878406)
					(mid 346.096844 -217.878406)
					(end 346.749624 -217.878406)
				)
			)
		)
	)
	(zone
		(layers "B.Cu" "In6.Cu" "In11.Cu" "In13.Cu" "In15.Cu")
		(hatch none 0.5)
		(connect_pads
			(clearance 0)
		)
		(min_thickness 0.25)
		(keepout
			(tracks not_allowed)
			(vias allowed)
			(pads allowed)
			(copperpour not_allowed)
			(footprints allowed)
		)
		(placement
			(enabled no)
			(sheetname "")
		)
		(fill yes
			(thermal_gap 0.5)
			(thermal_bridge_width 0.5)
			(island_removal_mode 0)
		)
		(polygon
			(pts
				(arc
					(start 94.220538 -257.175254)
					(mid 93.567758 -257.175254)
					(end 94.220538 -257.175254)
				)
			)
		)
	)
	(zone
		(layers "B.Cu" "In6.Cu" "In11.Cu" "In13.Cu" "In15.Cu")
		(hatch none 0.5)
		(connect_pads
			(clearance 0)
		)
		(min_thickness 0.25)
		(keepout
			(tracks not_allowed)
			(vias allowed)
			(pads allowed)
			(copperpour not_allowed)
			(footprints allowed)
		)
		(placement
			(enabled no)
			(sheetname "")
		)
		(fill yes
			(thermal_gap 0.5)
			(thermal_bridge_width 0.5)
			(island_removal_mode 0)
		)
		(polygon
			(pts
				(arc
					(start 47.290736 -202.416664)
					(mid 46.637956 -202.416664)
					(end 47.290736 -202.416664)
				)
			)
		)
	)
	(zone
		(layers "B.Cu" "In6.Cu" "In11.Cu" "In13.Cu" "In15.Cu")
		(hatch none 0.5)
		(connect_pads
			(clearance 0)
		)
		(min_thickness 0.25)
		(keepout
			(tracks not_allowed)
			(vias allowed)
			(pads allowed)
			(copperpour not_allowed)
			(footprints allowed)
		)
		(placement
			(enabled no)
			(sheetname "")
		)
		(fill yes
			(thermal_gap 0.5)
			(thermal_bridge_width 0.5)
			(island_removal_mode 0)
		)
		(polygon
			(pts
				(arc
					(start 299.330872 -231.316784)
					(mid 298.678092 -231.316784)
					(end 299.330872 -231.316784)
				)
			)
		)
	)
	(zone
		(layers "B.Cu" "In6.Cu" "In11.Cu" "In13.Cu" "In15.Cu")
		(hatch none 0.5)
		(connect_pads
			(clearance 0)
		)
		(min_thickness 0.25)
		(keepout
			(tracks not_allowed)
			(vias allowed)
			(pads allowed)
			(copperpour not_allowed)
			(footprints allowed)
		)
		(placement
			(enabled no)
			(sheetname "")
		)
		(fill yes
			(thermal_gap 0.5)
			(thermal_bridge_width 0.5)
			(island_removal_mode 0)
		)
		(polygon
			(pts
				(arc
					(start 436.150004 -211.766658)
					(mid 435.497224 -211.766658)
					(end 436.150004 -211.766658)
				)
			)
		)
	)
	(zone
		(layers "B.Cu" "In6.Cu" "In11.Cu" "In13.Cu" "In15.Cu")
		(hatch none 0.5)
		(connect_pads
			(clearance 0)
		)
		(min_thickness 0.25)
		(keepout
			(tracks not_allowed)
			(vias allowed)
			(pads allowed)
			(copperpour not_allowed)
			(footprints allowed)
		)
		(placement
			(enabled no)
			(sheetname "")
		)
		(fill yes
			(thermal_gap 0.5)
			(thermal_bridge_width 0.5)
			(island_removal_mode 0)
		)
		(polygon
			(pts
				(arc
					(start 36.303204 -209.216752)
					(mid 35.650424 -209.216752)
					(end 36.303204 -209.216752)
				)
			)
		)
	)
	(zone
		(layers "B.Cu" "In6.Cu" "In11.Cu" "In13.Cu" "In15.Cu")
		(hatch none 0.5)
		(connect_pads
			(clearance 0)
		)
		(min_thickness 0.25)
		(keepout
			(tracks not_allowed)
			(vias allowed)
			(pads allowed)
			(copperpour not_allowed)
			(footprints allowed)
		)
		(placement
			(enabled no)
			(sheetname "")
		)
		(fill yes
			(thermal_gap 0.5)
			(thermal_bridge_width 0.5)
			(island_removal_mode 0)
		)
		(polygon
			(pts
				(arc
					(start 280.143204 -266.1666)
					(mid 279.490424 -266.1666)
					(end 280.143204 -266.1666)
				)
			)
		)
	)
	(zone
		(layers "B.Cu" "In6.Cu" "In11.Cu" "In13.Cu" "In15.Cu")
		(hatch none 0.5)
		(connect_pads
			(clearance 0)
		)
		(min_thickness 0.25)
		(keepout
			(tracks not_allowed)
			(vias allowed)
			(pads allowed)
			(copperpour not_allowed)
			(footprints allowed)
		)
		(placement
			(enabled no)
			(sheetname "")
		)
		(fill yes
			(thermal_gap 0.5)
			(thermal_bridge_width 0.5)
			(island_removal_mode 0)
		)
		(polygon
			(pts
				(arc
					(start 91.870784 -257.98907)
					(mid 91.218004 -257.98907)
					(end 91.870784 -257.98907)
				)
			)
		)
	)
	(zone
		(layers "B.Cu" "In6.Cu" "In11.Cu" "In13.Cu" "In15.Cu")
		(hatch none 0.5)
		(connect_pads
			(clearance 0)
		)
		(min_thickness 0.25)
		(keepout
			(tracks not_allowed)
			(vias allowed)
			(pads allowed)
			(copperpour not_allowed)
			(footprints allowed)
		)
		(placement
			(enabled no)
			(sheetname "")
		)
		(fill yes
			(thermal_gap 0.5)
			(thermal_bridge_width 0.5)
			(island_removal_mode 0)
		)
		(polygon
			(pts
				(arc
					(start 371.764306 -288.917126)
					(mid 371.111526 -288.917126)
					(end 371.764306 -288.917126)
				)
			)
		)
	)
	(zone
		(layers "B.Cu" "In6.Cu" "In11.Cu" "In13.Cu" "In15.Cu")
		(hatch none 0.5)
		(connect_pads
			(clearance 0)
		)
		(min_thickness 0.25)
		(keepout
			(tracks not_allowed)
			(vias allowed)
			(pads allowed)
			(copperpour not_allowed)
			(footprints allowed)
		)
		(placement
			(enabled no)
			(sheetname "")
		)
		(fill yes
			(thermal_gap 0.5)
			(thermal_bridge_width 0.5)
			(island_removal_mode 0)
		)
		(polygon
			(pts
				(arc
					(start 295.230804 -198.166736)
					(mid 294.578024 -198.166736)
					(end 295.230804 -198.166736)
				)
			)
		)
	)
	(zone
		(layers "B.Cu" "In6.Cu" "In11.Cu" "In13.Cu" "In15.Cu")
		(hatch none 0.5)
		(connect_pads
			(clearance 0)
		)
		(min_thickness 0.25)
		(keepout
			(tracks not_allowed)
			(vias allowed)
			(pads allowed)
			(copperpour not_allowed)
			(footprints allowed)
		)
		(placement
			(enabled no)
			(sheetname "")
		)
		(fill yes
			(thermal_gap 0.5)
			(thermal_bridge_width 0.5)
			(island_removal_mode 0)
		)
		(polygon
			(pts
				(arc
					(start 90.351356 -217.878406)
					(mid 89.698576 -217.878406)
					(end 90.351356 -217.878406)
				)
			)
		)
	)
	(zone
		(layers "B.Cu" "In6.Cu" "In11.Cu" "In13.Cu" "In15.Cu")
		(hatch none 0.5)
		(connect_pads
			(clearance 0)
		)
		(min_thickness 0.25)
		(keepout
			(tracks not_allowed)
			(vias allowed)
			(pads allowed)
			(copperpour not_allowed)
			(footprints allowed)
		)
		(placement
			(enabled no)
			(sheetname "")
		)
		(fill yes
			(thermal_gap 0.5)
			(thermal_bridge_width 0.5)
			(island_removal_mode 0)
		)
		(polygon
			(pts
				(arc
					(start 100.799138 -288.103056)
					(mid 100.146358 -288.103056)
					(end 100.799138 -288.103056)
				)
			)
		)
	)
	(zone
		(layers "B.Cu" "In6.Cu" "In11.Cu" "In13.Cu" "In15.Cu")
		(hatch none 0.5)
		(connect_pads
			(clearance 0)
		)
		(min_thickness 0.25)
		(keepout
			(tracks not_allowed)
			(vias allowed)
			(pads allowed)
			(copperpour not_allowed)
			(footprints allowed)
		)
		(placement
			(enabled no)
			(sheetname "")
		)
		(fill yes
			(thermal_gap 0.5)
			(thermal_bridge_width 0.5)
			(island_removal_mode 0)
		)
		(polygon
			(pts
				(arc
					(start 425.162472 -300.166532)
					(mid 424.509692 -300.166532)
					(end 425.162472 -300.166532)
				)
			)
		)
	)
	(zone
		(layers "B.Cu" "In6.Cu" "In11.Cu" "In13.Cu" "In15.Cu")
		(hatch none 0.5)
		(connect_pads
			(clearance 0)
		)
		(min_thickness 0.25)
		(keepout
			(tracks not_allowed)
			(vias allowed)
			(pads allowed)
			(copperpour not_allowed)
			(footprints allowed)
		)
		(placement
			(enabled no)
			(sheetname "")
		)
		(fill yes
			(thermal_gap 0.5)
			(thermal_bridge_width 0.5)
			(island_removal_mode 0)
		)
		(polygon
			(pts
				(arc
					(start 280.143204 -211.766658)
					(mid 279.490424 -211.766658)
					(end 280.143204 -211.766658)
				)
			)
		)
	)
	(zone
		(layers "B.Cu" "In6.Cu" "In11.Cu" "In13.Cu" "In15.Cu")
		(hatch none 0.5)
		(connect_pads
			(clearance 0)
		)
		(min_thickness 0.25)
		(keepout
			(tracks not_allowed)
			(vias allowed)
			(pads allowed)
			(copperpour not_allowed)
			(footprints allowed)
		)
		(placement
			(enabled no)
			(sheetname "")
		)
		(fill yes
			(thermal_gap 0.5)
			(thermal_bridge_width 0.5)
			(island_removal_mode 0)
		)
		(polygon
			(pts
				(arc
					(start 94.690184 -272.639282)
					(mid 94.037404 -272.639282)
					(end 94.690184 -272.639282)
				)
			)
		)
	)
	(zone
		(layers "B.Cu" "In6.Cu" "In11.Cu" "In13.Cu" "In15.Cu")
		(hatch none 0.5)
		(connect_pads
			(clearance 0)
		)
		(min_thickness 0.25)
		(keepout
			(tracks not_allowed)
			(vias allowed)
			(pads allowed)
			(copperpour not_allowed)
			(footprints allowed)
		)
		(placement
			(enabled no)
			(sheetname "")
		)
		(fill yes
			(thermal_gap 0.5)
			(thermal_bridge_width 0.5)
			(island_removal_mode 0)
		)
		(polygon
			(pts
				(arc
					(start 299.330872 -197.316598)
					(mid 298.678092 -197.316598)
					(end 299.330872 -197.316598)
				)
			)
		)
	)
	(zone
		(layers "B.Cu" "In6.Cu" "In11.Cu" "In13.Cu" "In15.Cu")
		(hatch none 0.5)
		(connect_pads
			(clearance 0)
		)
		(min_thickness 0.25)
		(keepout
			(tracks not_allowed)
			(vias allowed)
			(pads allowed)
			(copperpour not_allowed)
			(footprints allowed)
		)
		(placement
			(enabled no)
			(sheetname "")
		)
		(fill yes
			(thermal_gap 0.5)
			(thermal_bridge_width 0.5)
			(island_removal_mode 0)
		)
		(polygon
			(pts
				(arc
					(start 192.310004 -248.31675)
					(mid 191.657224 -248.31675)
					(end 192.310004 -248.31675)
				)
			)
		)
	)
	(zone
		(layers "B.Cu" "In6.Cu" "In11.Cu" "In13.Cu" "In15.Cu")
		(hatch none 0.5)
		(connect_pads
			(clearance 0)
		)
		(min_thickness 0.25)
		(keepout
			(tracks not_allowed)
			(vias allowed)
			(pads allowed)
			(copperpour not_allowed)
			(footprints allowed)
		)
		(placement
			(enabled no)
			(sheetname "")
		)
		(fill yes
			(thermal_gap 0.5)
			(thermal_bridge_width 0.5)
			(island_removal_mode 0)
		)
		(polygon
			(pts
				(arc
					(start 131.812538 -268.569694)
					(mid 131.159758 -268.569694)
					(end 131.812538 -268.569694)
				)
			)
		)
	)
	(zone
		(layers "B.Cu" "In6.Cu" "In11.Cu" "In13.Cu" "In15.Cu")
		(hatch none 0.5)
		(connect_pads
			(clearance 0)
		)
		(min_thickness 0.25)
		(keepout
			(tracks not_allowed)
			(vias allowed)
			(pads allowed)
			(copperpour not_allowed)
			(footprints allowed)
		)
		(placement
			(enabled no)
			(sheetname "")
		)
		(fill yes
			(thermal_gap 0.5)
			(thermal_bridge_width 0.5)
			(island_removal_mode 0)
		)
		(polygon
			(pts
				(arc
					(start 340.64067 -230.086662)
					(mid 339.98789 -230.086662)
					(end 340.64067 -230.086662)
				)
			)
		)
	)
	(zone
		(layers "B.Cu" "In6.Cu" "In11.Cu" "In13.Cu" "In15.Cu")
		(hatch none 0.5)
		(connect_pads
			(clearance 0)
		)
		(min_thickness 0.25)
		(keepout
			(tracks not_allowed)
			(vias allowed)
			(pads allowed)
			(copperpour not_allowed)
			(footprints allowed)
		)
		(placement
			(enabled no)
			(sheetname "")
		)
		(fill yes
			(thermal_gap 0.5)
			(thermal_bridge_width 0.5)
			(island_removal_mode 0)
		)
		(polygon
			(pts
				(arc
					(start 32.203136 -316.316614)
					(mid 31.550356 -316.316614)
					(end 32.203136 -316.316614)
				)
			)
		)
	)
	(zone
		(layers "B.Cu" "In6.Cu" "In11.Cu" "In13.Cu" "In15.Cu")
		(hatch none 0.5)
		(connect_pads
			(clearance 0)
		)
		(min_thickness 0.25)
		(keepout
			(tracks not_allowed)
			(vias allowed)
			(pads allowed)
			(copperpour not_allowed)
			(footprints allowed)
		)
		(placement
			(enabled no)
			(sheetname "")
		)
		(fill yes
			(thermal_gap 0.5)
			(thermal_bridge_width 0.5)
			(island_removal_mode 0)
		)
		(polygon
			(pts
				(arc
					(start 93.640402 -241.481102)
					(mid 92.987622 -241.481102)
					(end 93.640402 -241.481102)
				)
			)
		)
	)
	(zone
		(layers "B.Cu" "In6.Cu" "In11.Cu" "In13.Cu" "In15.Cu")
		(hatch none 0.5)
		(connect_pads
			(clearance 0)
		)
		(min_thickness 0.25)
		(keepout
			(tracks not_allowed)
			(vias allowed)
			(pads allowed)
			(copperpour not_allowed)
			(footprints allowed)
		)
		(placement
			(enabled no)
			(sheetname "")
		)
		(fill yes
			(thermal_gap 0.5)
			(thermal_bridge_width 0.5)
			(island_removal_mode 0)
		)
		(polygon
			(pts
				(arc
					(start 379.642624 -235.783882)
					(mid 378.989844 -235.783882)
					(end 379.642624 -235.783882)
				)
			)
		)
	)
	(zone
		(layers "B.Cu" "In6.Cu" "In11.Cu" "In13.Cu" "In15.Cu")
		(hatch none 0.5)
		(connect_pads
			(clearance 0)
		)
		(min_thickness 0.25)
		(keepout
			(tracks not_allowed)
			(vias allowed)
			(pads allowed)
			(copperpour not_allowed)
			(footprints allowed)
		)
		(placement
			(enabled no)
			(sheetname "")
		)
		(fill yes
			(thermal_gap 0.5)
			(thermal_bridge_width 0.5)
			(island_removal_mode 0)
		)
		(polygon
			(pts
				(arc
					(start 363.666024 -217.878406)
					(mid 363.013244 -217.878406)
					(end 363.666024 -217.878406)
				)
			)
		)
	)
	(zone
		(layers "B.Cu" "In6.Cu" "In11.Cu" "In13.Cu" "In15.Cu")
		(hatch none 0.5)
		(connect_pads
			(clearance 0)
		)
		(min_thickness 0.25)
		(keepout
			(tracks not_allowed)
			(vias allowed)
			(pads allowed)
			(copperpour not_allowed)
			(footprints allowed)
		)
		(placement
			(enabled no)
			(sheetname "")
		)
		(fill yes
			(thermal_gap 0.5)
			(thermal_bridge_width 0.5)
			(island_removal_mode 0)
		)
		(polygon
			(pts
				(arc
					(start 93.750384 -272.639282)
					(mid 93.097604 -272.639282)
					(end 93.750384 -272.639282)
				)
			)
		)
	)
	(zone
		(layers "B.Cu" "In6.Cu" "In11.Cu" "In13.Cu" "In15.Cu")
		(hatch none 0.5)
		(connect_pads
			(clearance 0)
		)
		(min_thickness 0.25)
		(keepout
			(tracks not_allowed)
			(vias allowed)
			(pads allowed)
			(copperpour not_allowed)
			(footprints allowed)
		)
		(placement
			(enabled no)
			(sheetname "")
		)
		(fill yes
			(thermal_gap 0.5)
			(thermal_bridge_width 0.5)
			(island_removal_mode 0)
		)
		(polygon
			(pts
				(arc
					(start 96.099884 -289.807142)
					(mid 95.447104 -289.807142)
					(end 96.099884 -289.807142)
				)
			)
		)
	)
	(zone
		(layers "B.Cu" "In6.Cu" "In11.Cu" "In13.Cu" "In15.Cu")
		(hatch none 0.5)
		(connect_pads
			(clearance 0)
		)
		(min_thickness 0.25)
		(keepout
			(tracks not_allowed)
			(vias allowed)
			(pads allowed)
			(copperpour not_allowed)
			(footprints allowed)
		)
		(placement
			(enabled no)
			(sheetname "")
		)
		(fill yes
			(thermal_gap 0.5)
			(thermal_bridge_width 0.5)
			(island_removal_mode 0)
		)
		(polygon
			(pts
				(arc
					(start 340.750652 -256.361438)
					(mid 340.097872 -256.361438)
					(end 340.750652 -256.361438)
				)
			)
		)
	)
	(zone
		(layers "B.Cu" "In6.Cu" "In11.Cu" "In13.Cu" "In15.Cu")
		(hatch none 0.5)
		(connect_pads
			(clearance 0)
		)
		(min_thickness 0.25)
		(keepout
			(tracks not_allowed)
			(vias allowed)
			(pads allowed)
			(copperpour not_allowed)
			(footprints allowed)
		)
		(placement
			(enabled no)
			(sheetname "")
		)
		(fill yes
			(thermal_gap 0.5)
			(thermal_bridge_width 0.5)
			(island_removal_mode 0)
		)
		(polygon
			(pts
				(arc
					(start 124.184156 -217.878406)
					(mid 123.531376 -217.878406)
					(end 124.184156 -217.878406)
				)
			)
		)
	)
	(zone
		(layers "B.Cu" "In6.Cu" "In11.Cu" "In13.Cu" "In15.Cu")
		(hatch none 0.5)
		(connect_pads
			(clearance 0)
		)
		(min_thickness 0.25)
		(keepout
			(tracks not_allowed)
			(vias allowed)
			(pads allowed)
			(copperpour not_allowed)
			(footprints allowed)
		)
		(placement
			(enabled no)
			(sheetname "")
		)
		(fill yes
			(thermal_gap 0.5)
			(thermal_bridge_width 0.5)
			(island_removal_mode 0)
		)
		(polygon
			(pts
				(arc
					(start 380.582424 -247.178322)
					(mid 379.929644 -247.178322)
					(end 380.582424 -247.178322)
				)
			)
		)
	)
	(zone
		(layers "B.Cu" "In6.Cu" "In11.Cu" "In13.Cu" "In15.Cu")
		(hatch none 0.5)
		(connect_pads
			(clearance 0)
		)
		(min_thickness 0.25)
		(keepout
			(tracks not_allowed)
			(vias allowed)
			(pads allowed)
			(copperpour not_allowed)
			(footprints allowed)
		)
		(placement
			(enabled no)
			(sheetname "")
		)
		(fill yes
			(thermal_gap 0.5)
			(thermal_bridge_width 0.5)
			(island_removal_mode 0)
		)
		(polygon
			(pts
				(arc
					(start 378.342652 -269.38351)
					(mid 377.689872 -269.38351)
					(end 378.342652 -269.38351)
				)
			)
		)
	)
	(zone
		(layers "B.Cu" "In6.Cu" "In11.Cu" "In13.Cu" "In15.Cu")
		(hatch none 0.5)
		(connect_pads
			(clearance 0)
		)
		(min_thickness 0.25)
		(keepout
			(tracks not_allowed)
			(vias allowed)
			(pads allowed)
			(copperpour not_allowed)
			(footprints allowed)
		)
		(placement
			(enabled no)
			(sheetname "")
		)
		(fill yes
			(thermal_gap 0.5)
			(thermal_bridge_width 0.5)
			(island_removal_mode 0)
		)
		(polygon
			(pts
				(arc
					(start 425.162472 -281.466544)
					(mid 424.509692 -281.466544)
					(end 425.162472 -281.466544)
				)
			)
		)
	)
	(zone
		(layers "B.Cu" "In6.Cu" "In11.Cu" "In13.Cu" "In15.Cu")
		(hatch none 0.5)
		(connect_pads
			(clearance 0)
		)
		(min_thickness 0.25)
		(keepout
			(tracks not_allowed)
			(vias allowed)
			(pads allowed)
			(copperpour not_allowed)
			(footprints allowed)
		)
		(placement
			(enabled no)
			(sheetname "")
		)
		(fill yes
			(thermal_gap 0.5)
			(thermal_bridge_width 0.5)
			(island_removal_mode 0)
		)
		(polygon
			(pts
				(arc
					(start 370.824506 -288.917126)
					(mid 370.171726 -288.917126)
					(end 370.824506 -288.917126)
				)
			)
		)
	)
	(zone
		(layers "B.Cu" "In6.Cu" "In11.Cu" "In13.Cu" "In15.Cu")
		(hatch none 0.5)
		(connect_pads
			(clearance 0)
		)
		(min_thickness 0.25)
		(keepout
			(tracks not_allowed)
			(vias allowed)
			(pads allowed)
			(copperpour not_allowed)
			(footprints allowed)
		)
		(placement
			(enabled no)
			(sheetname "")
		)
		(fill yes
			(thermal_gap 0.5)
			(thermal_bridge_width 0.5)
			(island_removal_mode 0)
		)
		(polygon
			(pts
				(arc
					(start 367.89487 -218.692222)
					(mid 367.24209 -218.692222)
					(end 367.89487 -218.692222)
				)
			)
		)
	)
	(zone
		(layers "B.Cu" "In6.Cu" "In11.Cu" "In13.Cu" "In15.Cu")
		(hatch none 0.5)
		(connect_pads
			(clearance 0)
		)
		(min_thickness 0.25)
		(keepout
			(tracks not_allowed)
			(vias allowed)
			(pads allowed)
			(copperpour not_allowed)
			(footprints allowed)
		)
		(placement
			(enabled no)
			(sheetname "")
		)
		(fill yes
			(thermal_gap 0.5)
			(thermal_bridge_width 0.5)
			(island_removal_mode 0)
		)
		(polygon
			(pts
				(arc
					(start 96.100138 -255.547622)
					(mid 95.447358 -255.547622)
					(end 96.100138 -255.547622)
				)
			)
		)
	)
	(zone
		(layers "B.Cu" "In6.Cu" "In11.Cu" "In13.Cu" "In15.Cu")
		(hatch none 0.5)
		(connect_pads
			(clearance 0)
		)
		(min_thickness 0.25)
		(keepout
			(tracks not_allowed)
			(vias allowed)
			(pads allowed)
			(copperpour not_allowed)
			(footprints allowed)
		)
		(placement
			(enabled no)
			(sheetname "")
		)
		(fill yes
			(thermal_gap 0.5)
			(thermal_bridge_width 0.5)
			(island_removal_mode 0)
		)
		(polygon
			(pts
				(arc
					(start 349.678752 -289.807142)
					(mid 349.025972 -289.807142)
					(end 349.678752 -289.807142)
				)
			)
		)
	)
	(zone
		(layers "B.Cu" "In6.Cu" "In11.Cu" "In13.Cu" "In15.Cu")
		(hatch none 0.5)
		(connect_pads
			(clearance 0)
		)
		(min_thickness 0.25)
		(keepout
			(tracks not_allowed)
			(vias allowed)
			(pads allowed)
			(copperpour not_allowed)
			(footprints allowed)
		)
		(placement
			(enabled no)
			(sheetname "")
		)
		(fill yes
			(thermal_gap 0.5)
			(thermal_bridge_width 0.5)
			(island_removal_mode 0)
		)
		(polygon
			(pts
				(arc
					(start 93.750384 -269.38351)
					(mid 93.097604 -269.38351)
					(end 93.750384 -269.38351)
				)
			)
		)
	)
	(zone
		(layers "B.Cu" "In6.Cu" "In11.Cu" "In13.Cu" "In15.Cu")
		(hatch none 0.5)
		(connect_pads
			(clearance 0)
		)
		(min_thickness 0.25)
		(keepout
			(tracks not_allowed)
			(vias allowed)
			(pads allowed)
			(copperpour not_allowed)
			(footprints allowed)
		)
		(placement
			(enabled no)
			(sheetname "")
		)
		(fill yes
			(thermal_gap 0.5)
			(thermal_bridge_width 0.5)
			(island_removal_mode 0)
		)
		(polygon
			(pts
				(arc
					(start 425.162472 -203.266802)
					(mid 424.509692 -203.266802)
					(end 425.162472 -203.266802)
				)
			)
		)
	)
	(zone
		(layers "B.Cu" "In6.Cu" "In11.Cu" "In13.Cu" "In15.Cu")
		(hatch none 0.5)
		(connect_pads
			(clearance 0)
		)
		(min_thickness 0.25)
		(keepout
			(tracks not_allowed)
			(vias allowed)
			(pads allowed)
			(copperpour not_allowed)
			(footprints allowed)
		)
		(placement
			(enabled no)
			(sheetname "")
		)
		(fill yes
			(thermal_gap 0.5)
			(thermal_bridge_width 0.5)
			(island_removal_mode 0)
		)
		(polygon
			(pts
				(arc
					(start 339.810852 -277.522432)
					(mid 339.158072 -277.522432)
					(end 339.810852 -277.522432)
				)
			)
		)
	)
	(zone
		(layers "B.Cu" "In6.Cu" "In11.Cu" "In13.Cu" "In15.Cu")
		(hatch none 0.5)
		(connect_pads
			(clearance 0)
		)
		(min_thickness 0.25)
		(keepout
			(tracks not_allowed)
			(vias allowed)
			(pads allowed)
			(copperpour not_allowed)
			(footprints allowed)
		)
		(placement
			(enabled no)
			(sheetname "")
		)
		(fill yes
			(thermal_gap 0.5)
			(thermal_bridge_width 0.5)
			(island_removal_mode 0)
		)
		(polygon
			(pts
				(arc
					(start 369.414806 -288.103056)
					(mid 368.762026 -288.103056)
					(end 369.414806 -288.103056)
				)
			)
		)
	)
	(zone
		(layers "B.Cu" "In6.Cu" "In11.Cu" "In13.Cu" "In15.Cu")
		(hatch none 0.5)
		(connect_pads
			(clearance 0)
		)
		(min_thickness 0.25)
		(keepout
			(tracks not_allowed)
			(vias allowed)
			(pads allowed)
			(copperpour not_allowed)
			(footprints allowed)
		)
		(placement
			(enabled no)
			(sheetname "")
		)
		(fill yes
			(thermal_gap 0.5)
			(thermal_bridge_width 0.5)
			(island_removal_mode 0)
		)
		(polygon
			(pts
				(arc
					(start 173.122336 -282.316682)
					(mid 172.469556 -282.316682)
					(end 173.122336 -282.316682)
				)
			)
		)
	)
	(zone
		(layers "B.Cu" "In6.Cu" "In11.Cu" "In13.Cu" "In15.Cu")
		(hatch none 0.5)
		(connect_pads
			(clearance 0)
		)
		(min_thickness 0.25)
		(keepout
			(tracks not_allowed)
			(vias allowed)
			(pads allowed)
			(copperpour not_allowed)
			(footprints allowed)
		)
		(placement
			(enabled no)
			(sheetname "")
		)
		(fill yes
			(thermal_gap 0.5)
			(thermal_bridge_width 0.5)
			(island_removal_mode 0)
		)
		(polygon
			(pts
				(arc
					(start 378.702824 -242.294918)
					(mid 378.050044 -242.294918)
					(end 378.702824 -242.294918)
				)
			)
		)
	)
	(zone
		(layers "B.Cu" "In6.Cu" "In11.Cu" "In13.Cu" "In15.Cu")
		(hatch none 0.5)
		(connect_pads
			(clearance 0)
		)
		(min_thickness 0.25)
		(keepout
			(tracks not_allowed)
			(vias allowed)
			(pads allowed)
			(copperpour not_allowed)
			(footprints allowed)
		)
		(placement
			(enabled no)
			(sheetname "")
		)
		(fill yes
			(thermal_gap 0.5)
			(thermal_bridge_width 0.5)
			(island_removal_mode 0)
		)
		(polygon
			(pts
				(arc
					(start 440.250072 -307.816758)
					(mid 439.597292 -307.816758)
					(end 440.250072 -307.816758)
				)
			)
		)
	)
	(zone
		(layers "B.Cu" "In6.Cu" "In11.Cu" "In13.Cu" "In15.Cu")
		(hatch none 0.5)
		(connect_pads
			(clearance 0)
		)
		(min_thickness 0.25)
		(keepout
			(tracks not_allowed)
			(vias allowed)
			(pads allowed)
			(copperpour not_allowed)
			(footprints allowed)
		)
		(placement
			(enabled no)
			(sheetname "")
		)
		(fill yes
			(thermal_gap 0.5)
			(thermal_bridge_width 0.5)
			(island_removal_mode 0)
		)
		(polygon
			(pts
				(arc
					(start 447.793872 -244.916706)
					(mid 447.141092 -244.916706)
					(end 447.793872 -244.916706)
				)
			)
		)
	)
	(zone
		(layers "B.Cu" "In6.Cu" "In11.Cu" "In13.Cu" "In15.Cu")
		(hatch none 0.5)
		(connect_pads
			(clearance 0)
		)
		(min_thickness 0.25)
		(keepout
			(tracks not_allowed)
			(vias allowed)
			(pads allowed)
			(copperpour not_allowed)
			(footprints allowed)
		)
		(placement
			(enabled no)
			(sheetname "")
		)
		(fill yes
			(thermal_gap 0.5)
			(thermal_bridge_width 0.5)
			(island_removal_mode 0)
		)
		(polygon
			(pts
				(arc
					(start 92.700602 -236.597952)
					(mid 92.047822 -236.597952)
					(end 92.700602 -236.597952)
				)
			)
		)
	)
	(zone
		(layers "B.Cu" "In6.Cu" "In11.Cu" "In13.Cu" "In15.Cu")
		(hatch none 0.5)
		(connect_pads
			(clearance 0)
		)
		(min_thickness 0.25)
		(keepout
			(tracks not_allowed)
			(vias allowed)
			(pads allowed)
			(copperpour not_allowed)
			(footprints allowed)
		)
		(placement
			(enabled no)
			(sheetname "")
		)
		(fill yes
			(thermal_gap 0.5)
			(thermal_bridge_width 0.5)
			(island_removal_mode 0)
		)
		(polygon
			(pts
				(arc
					(start 381.05207 -218.692222)
					(mid 380.39929 -218.692222)
					(end 381.05207 -218.692222)
				)
			)
		)
	)
	(zone
		(layers "B.Cu" "In6.Cu" "In11.Cu" "In13.Cu" "In15.Cu")
		(hatch none 0.5)
		(connect_pads
			(clearance 0)
		)
		(min_thickness 0.25)
		(keepout
			(tracks not_allowed)
			(vias allowed)
			(pads allowed)
			(copperpour not_allowed)
			(footprints allowed)
		)
		(placement
			(enabled no)
			(sheetname "")
		)
		(fill yes
			(thermal_gap 0.5)
			(thermal_bridge_width 0.5)
			(island_removal_mode 0)
		)
		(polygon
			(pts
				(arc
					(start 93.750384 -267.755878)
					(mid 93.097604 -267.755878)
					(end 93.750384 -267.755878)
				)
			)
		)
	)
	(zone
		(layers "B.Cu" "In6.Cu" "In11.Cu" "In13.Cu" "In15.Cu")
		(hatch none 0.5)
		(connect_pads
			(clearance 0)
		)
		(min_thickness 0.25)
		(keepout
			(tracks not_allowed)
			(vias allowed)
			(pads allowed)
			(copperpour not_allowed)
			(footprints allowed)
		)
		(placement
			(enabled no)
			(sheetname "")
		)
		(fill yes
			(thermal_gap 0.5)
			(thermal_bridge_width 0.5)
			(island_removal_mode 0)
		)
		(polygon
			(pts
				(arc
					(start 173.122336 -286.56661)
					(mid 172.469556 -286.56661)
					(end 173.122336 -286.56661)
				)
			)
		)
	)
	(zone
		(layers "B.Cu" "In6.Cu" "In11.Cu" "In13.Cu" "In15.Cu")
		(hatch none 0.5)
		(connect_pads
			(clearance 0)
		)
		(min_thickness 0.25)
		(keepout
			(tracks not_allowed)
			(vias allowed)
			(pads allowed)
			(copperpour not_allowed)
			(footprints allowed)
		)
		(placement
			(enabled no)
			(sheetname "")
		)
		(fill yes
			(thermal_gap 0.5)
			(thermal_bridge_width 0.5)
			(island_removal_mode 0)
		)
		(polygon
			(pts
				(arc
					(start 368.365024 -217.878406)
					(mid 367.712244 -217.878406)
					(end 368.365024 -217.878406)
				)
			)
		)
	)
	(zone
		(layers "B.Cu" "In6.Cu" "In11.Cu" "In13.Cu" "In15.Cu")
		(hatch none 0.5)
		(connect_pads
			(clearance 0)
		)
		(min_thickness 0.25)
		(keepout
			(tracks not_allowed)
			(vias allowed)
			(pads allowed)
			(copperpour not_allowed)
			(footprints allowed)
		)
		(placement
			(enabled no)
			(sheetname "")
		)
		(fill yes
			(thermal_gap 0.5)
			(thermal_bridge_width 0.5)
			(island_removal_mode 0)
		)
		(polygon
			(pts
				(arc
					(start 368.944906 -288.917126)
					(mid 368.292126 -288.917126)
					(end 368.944906 -288.917126)
				)
			)
		)
	)
	(zone
		(layers "B.Cu" "In6.Cu" "In11.Cu" "In13.Cu" "In15.Cu")
		(hatch none 0.5)
		(connect_pads
			(clearance 0)
		)
		(min_thickness 0.25)
		(keepout
			(tracks not_allowed)
			(vias allowed)
			(pads allowed)
			(copperpour not_allowed)
			(footprints allowed)
		)
		(placement
			(enabled no)
			(sheetname "")
		)
		(fill yes
			(thermal_gap 0.5)
			(thermal_bridge_width 0.5)
			(island_removal_mode 0)
		)
		(polygon
			(pts
				(arc
					(start 299.330872 -287.416748)
					(mid 298.678092 -287.416748)
					(end 299.330872 -287.416748)
				)
			)
		)
	)
	(zone
		(layers "B.Cu" "In6.Cu" "In11.Cu" "In13.Cu" "In15.Cu")
		(hatch none 0.5)
		(connect_pads
			(clearance 0)
		)
		(min_thickness 0.25)
		(keepout
			(tracks not_allowed)
			(vias allowed)
			(pads allowed)
			(copperpour not_allowed)
			(footprints allowed)
		)
		(placement
			(enabled no)
			(sheetname "")
		)
		(fill yes
			(thermal_gap 0.5)
			(thermal_bridge_width 0.5)
			(island_removal_mode 0)
		)
		(polygon
			(pts
				(arc
					(start 92.340938 -266.941808)
					(mid 91.688158 -266.941808)
					(end 92.340938 -266.941808)
				)
			)
		)
	)
	(zone
		(layers "B.Cu" "In6.Cu" "In11.Cu" "In13.Cu" "In15.Cu")
		(hatch none 0.5)
		(connect_pads
			(clearance 0)
		)
		(min_thickness 0.25)
		(keepout
			(tracks not_allowed)
			(vias allowed)
			(pads allowed)
			(copperpour not_allowed)
			(footprints allowed)
		)
		(placement
			(enabled no)
			(sheetname "")
		)
		(fill yes
			(thermal_gap 0.5)
			(thermal_bridge_width 0.5)
			(island_removal_mode 0)
		)
		(polygon
			(pts
				(arc
					(start 92.340938 -268.569694)
					(mid 91.688158 -268.569694)
					(end 92.340938 -268.569694)
				)
			)
		)
	)
	(zone
		(layers "B.Cu" "In6.Cu" "In11.Cu" "In13.Cu" "In15.Cu")
		(hatch none 0.5)
		(connect_pads
			(clearance 0)
		)
		(min_thickness 0.25)
		(keepout
			(tracks not_allowed)
			(vias allowed)
			(pads allowed)
			(copperpour not_allowed)
			(footprints allowed)
		)
		(placement
			(enabled no)
			(sheetname "")
		)
		(fill yes
			(thermal_gap 0.5)
			(thermal_bridge_width 0.5)
			(island_removal_mode 0)
		)
		(polygon
			(pts
				(arc
					(start 340.64067 -243.108988)
					(mid 339.98789 -243.108988)
					(end 340.64067 -243.108988)
				)
			)
		)
	)
	(zone
		(layers "B.Cu" "In6.Cu" "In11.Cu" "In13.Cu" "In15.Cu")
		(hatch none 0.5)
		(connect_pads
			(clearance 0)
		)
		(min_thickness 0.25)
		(keepout
			(tracks not_allowed)
			(vias allowed)
			(pads allowed)
			(copperpour not_allowed)
			(footprints allowed)
		)
		(placement
			(enabled no)
			(sheetname "")
		)
		(fill yes
			(thermal_gap 0.5)
			(thermal_bridge_width 0.5)
			(island_removal_mode 0)
		)
		(polygon
			(pts
				(arc
					(start 243.469414 -58.563002)
					(mid 242.765834 -58.563002)
					(end 243.469414 -58.563002)
				)
			)
		)
	)
	(zone
		(layers "B.Cu" "In6.Cu" "In11.Cu" "In13.Cu" "In15.Cu")
		(hatch none 0.5)
		(connect_pads
			(clearance 0)
		)
		(min_thickness 0.25)
		(keepout
			(tracks not_allowed)
			(vias allowed)
			(pads allowed)
			(copperpour not_allowed)
			(footprints allowed)
		)
		(placement
			(enabled no)
			(sheetname "")
		)
		(fill yes
			(thermal_gap 0.5)
			(thermal_bridge_width 0.5)
			(island_removal_mode 0)
		)
		(polygon
			(pts
				(arc
					(start 380.11227 -226.831144)
					(mid 379.45949 -226.831144)
					(end 380.11227 -226.831144)
				)
			)
		)
	)
	(zone
		(layers "B.Cu" "In6.Cu" "In11.Cu" "In13.Cu" "In15.Cu")
		(hatch none 0.5)
		(connect_pads
			(clearance 0)
		)
		(min_thickness 0.25)
		(keepout
			(tracks not_allowed)
			(vias allowed)
			(pads allowed)
			(copperpour not_allowed)
			(footprints allowed)
		)
		(placement
			(enabled no)
			(sheetname "")
		)
		(fill yes
			(thermal_gap 0.5)
			(thermal_bridge_width 0.5)
			(island_removal_mode 0)
		)
		(polygon
			(pts
				(arc
					(start 132.172202 -246.364506)
					(mid 131.519422 -246.364506)
					(end 132.172202 -246.364506)
				)
			)
		)
	)
	(zone
		(layers "B.Cu" "In6.Cu" "In11.Cu" "In13.Cu" "In15.Cu")
		(hatch none 0.5)
		(connect_pads
			(clearance 0)
		)
		(min_thickness 0.25)
		(keepout
			(tracks not_allowed)
			(vias allowed)
			(pads allowed)
			(copperpour not_allowed)
			(footprints allowed)
		)
		(placement
			(enabled no)
			(sheetname "")
		)
		(fill yes
			(thermal_gap 0.5)
			(thermal_bridge_width 0.5)
			(island_removal_mode 0)
		)
		(polygon
			(pts
				(arc
					(start 91.400884 -288.103056)
					(mid 90.748104 -288.103056)
					(end 91.400884 -288.103056)
				)
			)
		)
	)
	(zone
		(layers "B.Cu" "In6.Cu" "In11.Cu" "In13.Cu" "In15.Cu")
		(hatch none 0.5)
		(connect_pads
			(clearance 0)
		)
		(min_thickness 0.25)
		(keepout
			(tracks not_allowed)
			(vias allowed)
			(pads allowed)
			(copperpour not_allowed)
			(footprints allowed)
		)
		(placement
			(enabled no)
			(sheetname "")
		)
		(fill yes
			(thermal_gap 0.5)
			(thermal_bridge_width 0.5)
			(island_removal_mode 0)
		)
		(polygon
			(pts
				(arc
					(start 379.642624 -248.806208)
					(mid 378.989844 -248.806208)
					(end 379.642624 -248.806208)
				)
			)
		)
	)
	(zone
		(layers "B.Cu" "In6.Cu" "In11.Cu" "In13.Cu" "In15.Cu")
		(hatch none 0.5)
		(connect_pads
			(clearance 0)
		)
		(min_thickness 0.25)
		(keepout
			(tracks not_allowed)
			(vias allowed)
			(pads allowed)
			(copperpour not_allowed)
			(footprints allowed)
		)
		(placement
			(enabled no)
			(sheetname "")
		)
		(fill yes
			(thermal_gap 0.5)
			(thermal_bridge_width 0.5)
			(island_removal_mode 0)
		)
		(polygon
			(pts
				(arc
					(start 380.222252 -274.266914)
					(mid 379.569472 -274.266914)
					(end 380.222252 -274.266914)
				)
			)
		)
	)
	(zone
		(layers "B.Cu" "In6.Cu" "In11.Cu" "In13.Cu" "In15.Cu")
		(hatch none 0.5)
		(connect_pads
			(clearance 0)
		)
		(min_thickness 0.25)
		(keepout
			(tracks not_allowed)
			(vias allowed)
			(pads allowed)
			(copperpour not_allowed)
			(footprints allowed)
		)
		(placement
			(enabled no)
			(sheetname "")
		)
		(fill yes
			(thermal_gap 0.5)
			(thermal_bridge_width 0.5)
			(island_removal_mode 0)
		)
		(polygon
			(pts
				(arc
					(start 284.243272 -265.316716)
					(mid 283.590492 -265.316716)
					(end 284.243272 -265.316716)
				)
			)
		)
	)
	(zone
		(layers "B.Cu" "In6.Cu" "In11.Cu" "In13.Cu" "In15.Cu")
		(hatch none 0.5)
		(connect_pads
			(clearance 0)
		)
		(min_thickness 0.25)
		(keepout
			(tracks not_allowed)
			(vias allowed)
			(pads allowed)
			(copperpour not_allowed)
			(footprints allowed)
		)
		(placement
			(enabled no)
			(sheetname "")
		)
		(fill yes
			(thermal_gap 0.5)
			(thermal_bridge_width 0.5)
			(island_removal_mode 0)
		)
		(polygon
			(pts
				(arc
					(start 47.290736 -196.466714)
					(mid 46.637956 -196.466714)
					(end 47.290736 -196.466714)
				)
			)
		)
	)
	(zone
		(layers "B.Cu" "In6.Cu" "In11.Cu" "In13.Cu" "In15.Cu")
		(hatch none 0.5)
		(connect_pads
			(clearance 0)
		)
		(min_thickness 0.25)
		(keepout
			(tracks not_allowed)
			(vias allowed)
			(pads allowed)
			(copperpour not_allowed)
			(footprints allowed)
		)
		(placement
			(enabled no)
			(sheetname "")
		)
		(fill yes
			(thermal_gap 0.5)
			(thermal_bridge_width 0.5)
			(island_removal_mode 0)
		)
		(polygon
			(pts
				(arc
					(start 341.690452 -259.616956)
					(mid 341.037672 -259.616956)
					(end 341.690452 -259.616956)
				)
			)
		)
	)
	(zone
		(layers "B.Cu" "In6.Cu" "In11.Cu" "In13.Cu" "In15.Cu")
		(hatch none 0.5)
		(connect_pads
			(clearance 0)
		)
		(min_thickness 0.25)
		(keepout
			(tracks not_allowed)
			(vias allowed)
			(pads allowed)
			(copperpour not_allowed)
			(footprints allowed)
		)
		(placement
			(enabled no)
			(sheetname "")
		)
		(fill yes
			(thermal_gap 0.5)
			(thermal_bridge_width 0.5)
			(island_removal_mode 0)
		)
		(polygon
			(pts
				(arc
					(start 36.303204 -312.066686)
					(mid 35.650424 -312.066686)
					(end 36.303204 -312.066686)
				)
			)
		)
	)
	(zone
		(layers "B.Cu" "In6.Cu" "In11.Cu" "In13.Cu" "In15.Cu")
		(hatch none 0.5)
		(connect_pads
			(clearance 0)
		)
		(min_thickness 0.25)
		(keepout
			(tracks not_allowed)
			(vias allowed)
			(pads allowed)
			(copperpour not_allowed)
			(footprints allowed)
		)
		(placement
			(enabled no)
			(sheetname "")
		)
		(fill yes
			(thermal_gap 0.5)
			(thermal_bridge_width 0.5)
			(island_removal_mode 0)
		)
		(polygon
			(pts
				(arc
					(start 371.294406 -288.103056)
					(mid 370.641626 -288.103056)
					(end 371.294406 -288.103056)
				)
			)
		)
	)
	(zone
		(layers "B.Cu" "In6.Cu" "In11.Cu" "In13.Cu" "In15.Cu")
		(hatch none 0.5)
		(connect_pads
			(clearance 0)
		)
		(min_thickness 0.25)
		(keepout
			(tracks not_allowed)
			(vias allowed)
			(pads allowed)
			(copperpour not_allowed)
			(footprints allowed)
		)
		(placement
			(enabled no)
			(sheetname "")
		)
		(fill yes
			(thermal_gap 0.5)
			(thermal_bridge_width 0.5)
			(island_removal_mode 0)
		)
		(polygon
			(pts
				(arc
					(start 28.759404 -260.21665)
					(mid 28.106624 -260.21665)
					(end 28.759404 -260.21665)
				)
			)
		)
	)
	(zone
		(layers "B.Cu" "In6.Cu" "In11.Cu" "In13.Cu" "In15.Cu")
		(hatch none 0.5)
		(connect_pads
			(clearance 0)
		)
		(min_thickness 0.25)
		(keepout
			(tracks not_allowed)
			(vias allowed)
			(pads allowed)
			(copperpour not_allowed)
			(footprints allowed)
		)
		(placement
			(enabled no)
			(sheetname "")
		)
		(fill yes
			(thermal_gap 0.5)
			(thermal_bridge_width 0.5)
			(island_removal_mode 0)
		)
		(polygon
			(pts
				(arc
					(start 381.162306 -288.917126)
					(mid 380.509526 -288.917126)
					(end 381.162306 -288.917126)
				)
			)
		)
	)
	(zone
		(layers "B.Cu" "In6.Cu" "In11.Cu" "In13.Cu" "In15.Cu")
		(hatch none 0.5)
		(connect_pads
			(clearance 0)
		)
		(min_thickness 0.25)
		(keepout
			(tracks not_allowed)
			(vias allowed)
			(pads allowed)
			(copperpour not_allowed)
			(footprints allowed)
		)
		(placement
			(enabled no)
			(sheetname "")
		)
		(fill yes
			(thermal_gap 0.5)
			(thermal_bridge_width 0.5)
			(island_removal_mode 0)
		)
		(polygon
			(pts
				(arc
					(start 425.162472 -284.016704)
					(mid 424.509692 -284.016704)
					(end 425.162472 -284.016704)
				)
			)
		)
	)
	(zone
		(layers "B.Cu" "In6.Cu" "In11.Cu" "In13.Cu" "In15.Cu")
		(hatch none 0.5)
		(connect_pads
			(clearance 0)
		)
		(min_thickness 0.25)
		(keepout
			(tracks not_allowed)
			(vias allowed)
			(pads allowed)
			(copperpour not_allowed)
			(footprints allowed)
		)
		(placement
			(enabled no)
			(sheetname "")
		)
		(fill yes
			(thermal_gap 0.5)
			(thermal_bridge_width 0.5)
			(island_removal_mode 0)
		)
		(polygon
			(pts
				(arc
					(start 421.062404 -227.91674)
					(mid 420.409624 -227.91674)
					(end 421.062404 -227.91674)
				)
			)
		)
	)
	(zone
		(layers "B.Cu" "In6.Cu" "In11.Cu" "In13.Cu" "In15.Cu")
		(hatch none 0.5)
		(connect_pads
			(clearance 0)
		)
		(min_thickness 0.25)
		(keepout
			(tracks not_allowed)
			(vias allowed)
			(pads allowed)
			(copperpour not_allowed)
			(footprints allowed)
		)
		(placement
			(enabled no)
			(sheetname "")
		)
		(fill yes
			(thermal_gap 0.5)
			(thermal_bridge_width 0.5)
			(island_removal_mode 0)
		)
		(polygon
			(pts
				(arc
					(start 440.250072 -259.366766)
					(mid 439.597292 -259.366766)
					(end 440.250072 -259.366766)
				)
			)
		)
	)
	(zone
		(layers "B.Cu" "In6.Cu" "In11.Cu" "In13.Cu" "In15.Cu")
		(hatch none 0.5)
		(connect_pads
			(clearance 0)
		)
		(min_thickness 0.25)
		(keepout
			(tracks not_allowed)
			(vias allowed)
			(pads allowed)
			(copperpour not_allowed)
			(footprints allowed)
		)
		(placement
			(enabled no)
			(sheetname "")
		)
		(fill yes
			(thermal_gap 0.5)
			(thermal_bridge_width 0.5)
			(island_removal_mode 0)
		)
		(polygon
			(pts
				(arc
					(start 130.762756 -239.0394)
					(mid 130.109976 -239.0394)
					(end 130.762756 -239.0394)
				)
			)
		)
	)
	(zone
		(layers "B.Cu" "In6.Cu" "In11.Cu" "In13.Cu" "In15.Cu")
		(hatch none 0.5)
		(connect_pads
			(clearance 0)
		)
		(min_thickness 0.25)
		(keepout
			(tracks not_allowed)
			(vias allowed)
			(pads allowed)
			(copperpour not_allowed)
			(footprints allowed)
		)
		(placement
			(enabled no)
			(sheetname "")
		)
		(fill yes
			(thermal_gap 0.5)
			(thermal_bridge_width 0.5)
			(island_removal_mode 0)
		)
		(polygon
			(pts
				(arc
					(start 378.23267 -233.34218)
					(mid 377.57989 -233.34218)
					(end 378.23267 -233.34218)
				)
			)
		)
	)
	(zone
		(layers "B.Cu" "In6.Cu" "In11.Cu" "In13.Cu" "In15.Cu")
		(hatch none 0.5)
		(connect_pads
			(clearance 0)
		)
		(min_thickness 0.25)
		(keepout
			(tracks not_allowed)
			(vias allowed)
			(pads allowed)
			(copperpour not_allowed)
			(footprints allowed)
		)
		(placement
			(enabled no)
			(sheetname "")
		)
		(fill yes
			(thermal_gap 0.5)
			(thermal_bridge_width 0.5)
			(island_removal_mode 0)
		)
		(polygon
			(pts
				(arc
					(start 440.250072 -313.766708)
					(mid 439.597292 -313.766708)
					(end 440.250072 -313.766708)
				)
			)
		)
	)
	(zone
		(layers "B.Cu" "In6.Cu" "In11.Cu" "In13.Cu" "In15.Cu")
		(hatch none 0.5)
		(connect_pads
			(clearance 0)
		)
		(min_thickness 0.25)
		(keepout
			(tracks not_allowed)
			(vias allowed)
			(pads allowed)
			(copperpour not_allowed)
			(footprints allowed)
		)
		(placement
			(enabled no)
			(sheetname "")
		)
		(fill yes
			(thermal_gap 0.5)
			(thermal_bridge_width 0.5)
			(island_removal_mode 0)
		)
		(polygon
			(pts
				(arc
					(start 36.303204 -265.316716)
					(mid 35.650424 -265.316716)
					(end 36.303204 -265.316716)
				)
			)
		)
	)
	(zone
		(layers "B.Cu" "In6.Cu" "In11.Cu" "In13.Cu" "In15.Cu")
		(hatch none 0.5)
		(connect_pads
			(clearance 0)
		)
		(min_thickness 0.25)
		(keepout
			(tracks not_allowed)
			(vias allowed)
			(pads allowed)
			(copperpour not_allowed)
			(footprints allowed)
		)
		(placement
			(enabled no)
			(sheetname "")
		)
		(fill yes
			(thermal_gap 0.5)
			(thermal_bridge_width 0.5)
			(island_removal_mode 0)
		)
		(polygon
			(pts
				(arc
					(start 24.659336 -267.866622)
					(mid 24.006556 -267.866622)
					(end 24.659336 -267.866622)
				)
			)
		)
	)
	(zone
		(layers "B.Cu" "In6.Cu" "In11.Cu" "In13.Cu" "In15.Cu")
		(hatch none 0.5)
		(connect_pads
			(clearance 0)
		)
		(min_thickness 0.25)
		(keepout
			(tracks not_allowed)
			(vias allowed)
			(pads allowed)
			(copperpour not_allowed)
			(footprints allowed)
		)
		(placement
			(enabled no)
			(sheetname "")
		)
		(fill yes
			(thermal_gap 0.5)
			(thermal_bridge_width 0.5)
			(island_removal_mode 0)
		)
		(polygon
			(pts
				(arc
					(start 344.040206 -255.547622)
					(mid 343.387426 -255.547622)
					(end 344.040206 -255.547622)
				)
			)
		)
	)
	(zone
		(layers "B.Cu" "In6.Cu" "In11.Cu" "In13.Cu" "In15.Cu")
		(hatch none 0.5)
		(connect_pads
			(clearance 0)
		)
		(min_thickness 0.25)
		(keepout
			(tracks not_allowed)
			(vias allowed)
			(pads allowed)
			(copperpour not_allowed)
			(footprints allowed)
		)
		(placement
			(enabled no)
			(sheetname "")
		)
		(fill yes
			(thermal_gap 0.5)
			(thermal_bridge_width 0.5)
			(island_removal_mode 0)
		)
		(polygon
			(pts
				(arc
					(start 92.700602 -234.970066)
					(mid 92.047822 -234.970066)
					(end 92.700602 -234.970066)
				)
			)
		)
	)
	(zone
		(layers "B.Cu" "In6.Cu" "In11.Cu" "In13.Cu" "In15.Cu")
		(hatch none 0.5)
		(connect_pads
			(clearance 0)
		)
		(min_thickness 0.25)
		(keepout
			(tracks not_allowed)
			(vias allowed)
			(pads allowed)
			(copperpour not_allowed)
			(footprints allowed)
		)
		(placement
			(enabled no)
			(sheetname "")
		)
		(fill yes
			(thermal_gap 0.5)
			(thermal_bridge_width 0.5)
			(island_removal_mode 0)
		)
		(polygon
			(pts
				(arc
					(start 344.870024 -217.878406)
					(mid 344.217244 -217.878406)
					(end 344.870024 -217.878406)
				)
			)
		)
	)
	(zone
		(layers "B.Cu" "In6.Cu" "In11.Cu" "In13.Cu" "In15.Cu")
		(hatch none 0.5)
		(connect_pads
			(clearance 0)
		)
		(min_thickness 0.25)
		(keepout
			(tracks not_allowed)
			(vias allowed)
			(pads allowed)
			(copperpour not_allowed)
			(footprints allowed)
		)
		(placement
			(enabled no)
			(sheetname "")
		)
		(fill yes
			(thermal_gap 0.5)
			(thermal_bridge_width 0.5)
			(island_removal_mode 0)
		)
		(polygon
			(pts
				(arc
					(start 51.390804 -285.716726)
					(mid 50.738024 -285.716726)
					(end 51.390804 -285.716726)
				)
			)
		)
	)
	(zone
		(layers "B.Cu" "In6.Cu" "In11.Cu" "In13.Cu" "In15.Cu")
		(hatch none 0.5)
		(connect_pads
			(clearance 0)
		)
		(min_thickness 0.25)
		(keepout
			(tracks not_allowed)
			(vias allowed)
			(pads allowed)
			(copperpour not_allowed)
			(footprints allowed)
		)
		(placement
			(enabled no)
			(sheetname "")
		)
		(fill yes
			(thermal_gap 0.5)
			(thermal_bridge_width 0.5)
			(island_removal_mode 0)
		)
		(polygon
			(pts
				(arc
					(start 440.250072 -244.916706)
					(mid 439.597292 -244.916706)
					(end 440.250072 -244.916706)
				)
			)
		)
	)
	(zone
		(layers "B.Cu" "In6.Cu" "In11.Cu" "In13.Cu" "In15.Cu")
		(hatch none 0.5)
		(connect_pads
			(clearance 0)
		)
		(min_thickness 0.25)
		(keepout
			(tracks not_allowed)
			(vias allowed)
			(pads allowed)
			(copperpour not_allowed)
			(footprints allowed)
		)
		(placement
			(enabled no)
			(sheetname "")
		)
		(fill yes
			(thermal_gap 0.5)
			(thermal_bridge_width 0.5)
			(island_removal_mode 0)
		)
		(polygon
			(pts
				(arc
					(start 130.872738 -276.708616)
					(mid 130.219958 -276.708616)
					(end 130.872738 -276.708616)
				)
			)
		)
	)
	(zone
		(layers "B.Cu" "In6.Cu" "In11.Cu" "In13.Cu" "In15.Cu")
		(hatch none 0.5)
		(connect_pads
			(clearance 0)
		)
		(min_thickness 0.25)
		(keepout
			(tracks not_allowed)
			(vias allowed)
			(pads allowed)
			(copperpour not_allowed)
			(footprints allowed)
		)
		(placement
			(enabled no)
			(sheetname "")
		)
		(fill yes
			(thermal_gap 0.5)
			(thermal_bridge_width 0.5)
			(island_removal_mode 0)
		)
		(polygon
			(pts
				(arc
					(start 132.172202 -226.831144)
					(mid 131.519422 -226.831144)
					(end 132.172202 -226.831144)
				)
			)
		)
	)
	(zone
		(layers "B.Cu" "In6.Cu" "In11.Cu" "In13.Cu" "In15.Cu")
		(hatch none 0.5)
		(connect_pads
			(clearance 0)
		)
		(min_thickness 0.25)
		(keepout
			(tracks not_allowed)
			(vias allowed)
			(pads allowed)
			(copperpour not_allowed)
			(footprints allowed)
		)
		(placement
			(enabled no)
			(sheetname "")
		)
		(fill yes
			(thermal_gap 0.5)
			(thermal_bridge_width 0.5)
			(island_removal_mode 0)
		)
		(polygon
			(pts
				(arc
					(start 51.390804 -223.666558)
					(mid 50.738024 -223.666558)
					(end 51.390804 -223.666558)
				)
			)
		)
	)
	(zone
		(layers "B.Cu" "In6.Cu" "In11.Cu" "In13.Cu" "In15.Cu")
		(hatch none 0.5)
		(connect_pads
			(clearance 0)
		)
		(min_thickness 0.25)
		(keepout
			(tracks not_allowed)
			(vias allowed)
			(pads allowed)
			(copperpour not_allowed)
			(footprints allowed)
		)
		(placement
			(enabled no)
			(sheetname "")
		)
		(fill yes
			(thermal_gap 0.5)
			(thermal_bridge_width 0.5)
			(island_removal_mode 0)
		)
		(polygon
			(pts
				(arc
					(start 342.630252 -254.733552)
					(mid 341.977472 -254.733552)
					(end 342.630252 -254.733552)
				)
			)
		)
	)
	(zone
		(layers "B.Cu" "In6.Cu" "In11.Cu" "In13.Cu" "In15.Cu")
		(hatch none 0.5)
		(connect_pads
			(clearance 0)
		)
		(min_thickness 0.25)
		(keepout
			(tracks not_allowed)
			(vias allowed)
			(pads allowed)
			(copperpour not_allowed)
			(footprints allowed)
		)
		(placement
			(enabled no)
			(sheetname "")
		)
		(fill yes
			(thermal_gap 0.5)
			(thermal_bridge_width 0.5)
			(island_removal_mode 0)
		)
		(polygon
			(pts
				(arc
					(start 379.642624 -232.528364)
					(mid 378.989844 -232.528364)
					(end 379.642624 -232.528364)
				)
			)
		)
	)
	(zone
		(layers "B.Cu" "In6.Cu" "In11.Cu" "In13.Cu" "In15.Cu")
		(hatch none 0.5)
		(connect_pads
			(clearance 0)
		)
		(min_thickness 0.25)
		(keepout
			(tracks not_allowed)
			(vias allowed)
			(pads allowed)
			(copperpour not_allowed)
			(footprints allowed)
		)
		(placement
			(enabled no)
			(sheetname "")
		)
		(fill yes
			(thermal_gap 0.5)
			(thermal_bridge_width 0.5)
			(island_removal_mode 0)
		)
		(polygon
			(pts
				(arc
					(start 381.631952 -289.807142)
					(mid 380.979172 -289.807142)
					(end 381.631952 -289.807142)
				)
			)
		)
	)
	(zone
		(layers "B.Cu" "In6.Cu" "In11.Cu" "In13.Cu" "In15.Cu")
		(hatch none 0.5)
		(connect_pads
			(clearance 0)
		)
		(min_thickness 0.25)
		(keepout
			(tracks not_allowed)
			(vias allowed)
			(pads allowed)
			(copperpour not_allowed)
			(footprints allowed)
		)
		(placement
			(enabled no)
			(sheetname "")
		)
		(fill yes
			(thermal_gap 0.5)
			(thermal_bridge_width 0.5)
			(island_removal_mode 0)
		)
		(polygon
			(pts
				(arc
					(start 188.209936 -264.466578)
					(mid 187.557156 -264.466578)
					(end 188.209936 -264.466578)
				)
			)
		)
	)
	(zone
		(layers "B.Cu" "In6.Cu" "In11.Cu" "In13.Cu" "In15.Cu")
		(hatch none 0.5)
		(connect_pads
			(clearance 0)
		)
		(min_thickness 0.25)
		(keepout
			(tracks not_allowed)
			(vias allowed)
			(pads allowed)
			(copperpour not_allowed)
			(footprints allowed)
		)
		(placement
			(enabled no)
			(sheetname "")
		)
		(fill yes
			(thermal_gap 0.5)
			(thermal_bridge_width 0.5)
			(island_removal_mode 0)
		)
		(polygon
			(pts
				(arc
					(start 32.203136 -249.166634)
					(mid 31.550356 -249.166634)
					(end 32.203136 -249.166634)
				)
			)
		)
	)
	(zone
		(layers "B.Cu" "In6.Cu" "In11.Cu" "In13.Cu" "In15.Cu")
		(hatch none 0.5)
		(connect_pads
			(clearance 0)
		)
		(min_thickness 0.25)
		(keepout
			(tracks not_allowed)
			(vias allowed)
			(pads allowed)
			(copperpour not_allowed)
			(footprints allowed)
		)
		(placement
			(enabled no)
			(sheetname "")
		)
		(fill yes
			(thermal_gap 0.5)
			(thermal_bridge_width 0.5)
			(island_removal_mode 0)
		)
		(polygon
			(pts
				(arc
					(start 374.583452 -257.98907)
					(mid 373.930672 -257.98907)
					(end 374.583452 -257.98907)
				)
			)
		)
	)
	(zone
		(layers "B.Cu" "In6.Cu" "In11.Cu" "In13.Cu" "In15.Cu")
		(hatch none 0.5)
		(connect_pads
			(clearance 0)
		)
		(min_thickness 0.25)
		(keepout
			(tracks not_allowed)
			(vias allowed)
			(pads allowed)
			(copperpour not_allowed)
			(footprints allowed)
		)
		(placement
			(enabled no)
			(sheetname "")
		)
		(fill yes
			(thermal_gap 0.5)
			(thermal_bridge_width 0.5)
			(island_removal_mode 0)
		)
		(polygon
			(pts
				(arc
					(start 92.810584 -256.361438)
					(mid 92.157804 -256.361438)
					(end 92.810584 -256.361438)
				)
			)
		)
	)
	(zone
		(layers "B.Cu" "In6.Cu" "In11.Cu" "In13.Cu" "In15.Cu")
		(hatch none 0.5)
		(connect_pads
			(clearance 0)
		)
		(min_thickness 0.25)
		(keepout
			(tracks not_allowed)
			(vias allowed)
			(pads allowed)
			(copperpour not_allowed)
			(footprints allowed)
		)
		(placement
			(enabled no)
			(sheetname "")
		)
		(fill yes
			(thermal_gap 0.5)
			(thermal_bridge_width 0.5)
			(island_removal_mode 0)
		)
		(polygon
			(pts
				(arc
					(start 377.763024 -217.878406)
					(mid 377.110244 -217.878406)
					(end 377.763024 -217.878406)
				)
			)
		)
	)
	(zone
		(layers "B.Cu" "In6.Cu" "In11.Cu" "In13.Cu" "In15.Cu")
		(hatch none 0.5)
		(connect_pads
			(clearance 0)
		)
		(min_thickness 0.25)
		(keepout
			(tracks not_allowed)
			(vias allowed)
			(pads allowed)
			(copperpour not_allowed)
			(footprints allowed)
		)
		(placement
			(enabled no)
			(sheetname "")
		)
		(fill yes
			(thermal_gap 0.5)
			(thermal_bridge_width 0.5)
			(island_removal_mode 0)
		)
		(polygon
			(pts
				(arc
					(start 92.230956 -243.922804)
					(mid 91.578176 -243.922804)
					(end 92.230956 -243.922804)
				)
			)
		)
	)
	(zone
		(layers "B.Cu" "In6.Cu" "In11.Cu" "In13.Cu" "In15.Cu")
		(hatch none 0.5)
		(connect_pads
			(clearance 0)
		)
		(min_thickness 0.25)
		(keepout
			(tracks not_allowed)
			(vias allowed)
			(pads allowed)
			(copperpour not_allowed)
			(footprints allowed)
		)
		(placement
			(enabled no)
			(sheetname "")
		)
		(fill yes
			(thermal_gap 0.5)
			(thermal_bridge_width 0.5)
			(island_removal_mode 0)
		)
		(polygon
			(pts
				(arc
					(start 299.330872 -227.91674)
					(mid 298.678092 -227.91674)
					(end 299.330872 -227.91674)
				)
			)
		)
	)
	(zone
		(layers "B.Cu" "In6.Cu" "In11.Cu" "In13.Cu" "In15.Cu")
		(hatch none 0.5)
		(connect_pads
			(clearance 0)
		)
		(min_thickness 0.25)
		(keepout
			(tracks not_allowed)
			(vias allowed)
			(pads allowed)
			(copperpour not_allowed)
			(footprints allowed)
		)
		(placement
			(enabled no)
			(sheetname "")
		)
		(fill yes
			(thermal_gap 0.5)
			(thermal_bridge_width 0.5)
			(island_removal_mode 0)
		)
		(polygon
			(pts
				(arc
					(start 15.96517 -21.493988)
					(mid 15.26159 -21.493988)
					(end 15.96517 -21.493988)
				)
			)
		)
	)
	(zone
		(layers "B.Cu" "In6.Cu" "In11.Cu" "In13.Cu" "In15.Cu")
		(hatch none 0.5)
		(connect_pads
			(clearance 0)
		)
		(min_thickness 0.25)
		(keepout
			(tracks not_allowed)
			(vias allowed)
			(pads allowed)
			(copperpour not_allowed)
			(footprints allowed)
		)
		(placement
			(enabled no)
			(sheetname "")
		)
		(fill yes
			(thermal_gap 0.5)
			(thermal_bridge_width 0.5)
			(island_removal_mode 0)
		)
		(polygon
			(pts
				(arc
					(start 94.110556 -217.878406)
					(mid 93.457776 -217.878406)
					(end 94.110556 -217.878406)
				)
			)
		)
	)
	(zone
		(layers "B.Cu" "In6.Cu" "In11.Cu" "In13.Cu" "In15.Cu")
		(hatch none 0.5)
		(connect_pads
			(clearance 0)
		)
		(min_thickness 0.25)
		(keepout
			(tracks not_allowed)
			(vias allowed)
			(pads allowed)
			(copperpour not_allowed)
			(footprints allowed)
		)
		(placement
			(enabled no)
			(sheetname "")
		)
		(fill yes
			(thermal_gap 0.5)
			(thermal_bridge_width 0.5)
			(island_removal_mode 0)
		)
		(polygon
			(pts
				(arc
					(start 132.752338 -260.430772)
					(mid 132.099558 -260.430772)
					(end 132.752338 -260.430772)
				)
			)
		)
	)
	(zone
		(layers "B.Cu" "In6.Cu" "In11.Cu" "In13.Cu" "In15.Cu")
		(hatch none 0.5)
		(connect_pads
			(clearance 0)
		)
		(min_thickness 0.25)
		(keepout
			(tracks not_allowed)
			(vias allowed)
			(pads allowed)
			(copperpour not_allowed)
			(footprints allowed)
		)
		(placement
			(enabled no)
			(sheetname "")
		)
		(fill yes
			(thermal_gap 0.5)
			(thermal_bridge_width 0.5)
			(island_removal_mode 0)
		)
		(polygon
			(pts
				(arc
					(start 94.110556 -234.15625)
					(mid 93.457776 -234.15625)
					(end 94.110556 -234.15625)
				)
			)
		)
	)
	(zone
		(layers "B.Cu" "In6.Cu" "In11.Cu" "In13.Cu" "In15.Cu")
		(hatch none 0.5)
		(connect_pads
			(clearance 0)
		)
		(min_thickness 0.25)
		(keepout
			(tracks not_allowed)
			(vias allowed)
			(pads allowed)
			(copperpour not_allowed)
			(footprints allowed)
		)
		(placement
			(enabled no)
			(sheetname "")
		)
		(fill yes
			(thermal_gap 0.5)
			(thermal_bridge_width 0.5)
			(island_removal_mode 0)
		)
		(polygon
			(pts
				(arc
					(start 23.465282 -384.946398)
					(mid 22.761702 -384.946398)
					(end 23.465282 -384.946398)
				)
			)
		)
	)
	(zone
		(layers "B.Cu" "In6.Cu" "In11.Cu" "In13.Cu" "In15.Cu")
		(hatch none 0.5)
		(connect_pads
			(clearance 0)
		)
		(min_thickness 0.25)
		(keepout
			(tracks not_allowed)
			(vias allowed)
			(pads allowed)
			(copperpour not_allowed)
			(footprints allowed)
		)
		(placement
			(enabled no)
			(sheetname "")
		)
		(fill yes
			(thermal_gap 0.5)
			(thermal_bridge_width 0.5)
			(island_removal_mode 0)
		)
		(polygon
			(pts
				(arc
					(start 51.416204 -304.416714)
					(mid 50.763424 -304.416714)
					(end 51.416204 -304.416714)
				)
			)
		)
	)
	(zone
		(layers "B.Cu" "In6.Cu" "In11.Cu" "In13.Cu" "In15.Cu")
		(hatch none 0.5)
		(connect_pads
			(clearance 0)
		)
		(min_thickness 0.25)
		(keepout
			(tracks not_allowed)
			(vias allowed)
			(pads allowed)
			(copperpour not_allowed)
			(footprints allowed)
		)
		(placement
			(enabled no)
			(sheetname "")
		)
		(fill yes
			(thermal_gap 0.5)
			(thermal_bridge_width 0.5)
			(island_removal_mode 0)
		)
		(polygon
			(pts
				(arc
					(start 92.700602 -217.064336)
					(mid 92.047822 -217.064336)
					(end 92.700602 -217.064336)
				)
			)
		)
	)
	(zone
		(layers "B.Cu" "In6.Cu" "In11.Cu" "In13.Cu" "In15.Cu")
		(hatch none 0.5)
		(connect_pads
			(clearance 0)
		)
		(min_thickness 0.25)
		(keepout
			(tracks not_allowed)
			(vias allowed)
			(pads allowed)
			(copperpour not_allowed)
			(footprints allowed)
		)
		(placement
			(enabled no)
			(sheetname "")
		)
		(fill yes
			(thermal_gap 0.5)
			(thermal_bridge_width 0.5)
			(island_removal_mode 0)
		)
		(polygon
			(pts
				(arc
					(start 380.222252 -259.616956)
					(mid 379.569472 -259.616956)
					(end 380.222252 -259.616956)
				)
			)
		)
	)
	(zone
		(layers "B.Cu" "In6.Cu" "In11.Cu" "In13.Cu" "In15.Cu")
		(hatch none 0.5)
		(connect_pads
			(clearance 0)
		)
		(min_thickness 0.25)
		(keepout
			(tracks not_allowed)
			(vias allowed)
			(pads allowed)
			(copperpour not_allowed)
			(footprints allowed)
		)
		(placement
			(enabled no)
			(sheetname "")
		)
		(fill yes
			(thermal_gap 0.5)
			(thermal_bridge_width 0.5)
			(island_removal_mode 0)
		)
		(polygon
			(pts
				(arc
					(start 280.143204 -245.76659)
					(mid 279.490424 -245.76659)
					(end 280.143204 -245.76659)
				)
			)
		)
	)
	(zone
		(layers "B.Cu" "In6.Cu" "In11.Cu" "In13.Cu" "In15.Cu")
		(hatch none 0.5)
		(connect_pads
			(clearance 0)
		)
		(min_thickness 0.25)
		(keepout
			(tracks not_allowed)
			(vias allowed)
			(pads allowed)
			(copperpour not_allowed)
			(footprints allowed)
		)
		(placement
			(enabled no)
			(sheetname "")
		)
		(fill yes
			(thermal_gap 0.5)
			(thermal_bridge_width 0.5)
			(island_removal_mode 0)
		)
		(polygon
			(pts
				(arc
					(start 32.203136 -233.86669)
					(mid 31.550356 -233.86669)
					(end 32.203136 -233.86669)
				)
			)
		)
	)
	(zone
		(layers "B.Cu" "In6.Cu" "In11.Cu" "In13.Cu" "In15.Cu")
		(hatch none 0.5)
		(connect_pads
			(clearance 0)
		)
		(min_thickness 0.25)
		(keepout
			(tracks not_allowed)
			(vias allowed)
			(pads allowed)
			(copperpour not_allowed)
			(footprints allowed)
		)
		(placement
			(enabled no)
			(sheetname "")
		)
		(fill yes
			(thermal_gap 0.5)
			(thermal_bridge_width 0.5)
			(island_removal_mode 0)
		)
		(polygon
			(pts
				(arc
					(start 295.230804 -200.716642)
					(mid 294.578024 -200.716642)
					(end 295.230804 -200.716642)
				)
			)
		)
	)
	(zone
		(layers "B.Cu" "In6.Cu" "In11.Cu" "In13.Cu" "In15.Cu")
		(hatch none 0.5)
		(connect_pads
			(clearance 0)
		)
		(min_thickness 0.25)
		(keepout
			(tracks not_allowed)
			(vias allowed)
			(pads allowed)
			(copperpour not_allowed)
			(footprints allowed)
		)
		(placement
			(enabled no)
			(sheetname "")
		)
		(fill yes
			(thermal_gap 0.5)
			(thermal_bridge_width 0.5)
			(island_removal_mode 0)
		)
		(polygon
			(pts
				(arc
					(start 436.150004 -312.066686)
					(mid 435.497224 -312.066686)
					(end 436.150004 -312.066686)
				)
			)
		)
	)
	(zone
		(layers "B.Cu" "In6.Cu" "In11.Cu" "In13.Cu" "In15.Cu")
		(hatch none 0.5)
		(connect_pads
			(clearance 0)
		)
		(min_thickness 0.25)
		(keepout
			(tracks not_allowed)
			(vias allowed)
			(pads allowed)
			(copperpour not_allowed)
			(footprints allowed)
		)
		(placement
			(enabled no)
			(sheetname "")
		)
		(fill yes
			(thermal_gap 0.5)
			(thermal_bridge_width 0.5)
			(island_removal_mode 0)
		)
		(polygon
			(pts
				(arc
					(start 341.690452 -269.38351)
					(mid 341.037672 -269.38351)
					(end 341.690452 -269.38351)
				)
			)
		)
	)
	(zone
		(layers "B.Cu" "In6.Cu" "In11.Cu" "In13.Cu" "In15.Cu")
		(hatch none 0.5)
		(connect_pads
			(clearance 0)
		)
		(min_thickness 0.25)
		(keepout
			(tracks not_allowed)
			(vias allowed)
			(pads allowed)
			(copperpour not_allowed)
			(footprints allowed)
		)
		(placement
			(enabled no)
			(sheetname "")
		)
		(fill yes
			(thermal_gap 0.5)
			(thermal_bridge_width 0.5)
			(island_removal_mode 0)
		)
		(polygon
			(pts
				(arc
					(start 378.812806 -262.058658)
					(mid 378.160026 -262.058658)
					(end 378.812806 -262.058658)
				)
			)
		)
	)
	(zone
		(layers "B.Cu" "In6.Cu" "In11.Cu" "In13.Cu" "In15.Cu")
		(hatch none 0.5)
		(connect_pads
			(clearance 0)
		)
		(min_thickness 0.25)
		(keepout
			(tracks not_allowed)
			(vias allowed)
			(pads allowed)
			(copperpour not_allowed)
			(footprints allowed)
		)
		(placement
			(enabled no)
			(sheetname "")
		)
		(fill yes
			(thermal_gap 0.5)
			(thermal_bridge_width 0.5)
			(island_removal_mode 0)
		)
		(polygon
			(pts
				(arc
					(start 378.342906 -288.917126)
					(mid 377.690126 -288.917126)
					(end 378.342906 -288.917126)
				)
			)
		)
	)
	(zone
		(layers "B.Cu" "In6.Cu" "In11.Cu" "In13.Cu" "In15.Cu")
		(hatch none 0.5)
		(connect_pads
			(clearance 0)
		)
		(min_thickness 0.25)
		(keepout
			(tracks not_allowed)
			(vias allowed)
			(pads allowed)
			(copperpour not_allowed)
			(footprints allowed)
		)
		(placement
			(enabled no)
			(sheetname "")
		)
		(fill yes
			(thermal_gap 0.5)
			(thermal_bridge_width 0.5)
			(island_removal_mode 0)
		)
		(polygon
			(pts
				(arc
					(start 36.303204 -204.96657)
					(mid 35.650424 -204.96657)
					(end 36.303204 -204.96657)
				)
			)
		)
	)
	(zone
		(layers "B.Cu" "In6.Cu" "In11.Cu" "In13.Cu" "In15.Cu")
		(hatch none 0.5)
		(connect_pads
			(clearance 0)
		)
		(min_thickness 0.25)
		(keepout
			(tracks not_allowed)
			(vias allowed)
			(pads allowed)
			(copperpour not_allowed)
			(footprints allowed)
		)
		(placement
			(enabled no)
			(sheetname "")
		)
		(fill yes
			(thermal_gap 0.5)
			(thermal_bridge_width 0.5)
			(island_removal_mode 0)
		)
		(polygon
			(pts
				(arc
					(start 47.290736 -230.466646)
					(mid 46.637956 -230.466646)
					(end 47.290736 -230.466646)
				)
			)
		)
	)
	(zone
		(layers "B.Cu" "In6.Cu" "In11.Cu" "In13.Cu" "In15.Cu")
		(hatch none 0.5)
		(connect_pads
			(clearance 0)
		)
		(min_thickness 0.25)
		(keepout
			(tracks not_allowed)
			(vias allowed)
			(pads allowed)
			(copperpour not_allowed)
			(footprints allowed)
		)
		(placement
			(enabled no)
			(sheetname "")
		)
		(fill yes
			(thermal_gap 0.5)
			(thermal_bridge_width 0.5)
			(island_removal_mode 0)
		)
		(polygon
			(pts
				(arc
					(start 93.640402 -236.597952)
					(mid 92.987622 -236.597952)
					(end 93.640402 -236.597952)
				)
			)
		)
	)
	(zone
		(layers "B.Cu" "In6.Cu" "In11.Cu" "In13.Cu" "In15.Cu")
		(hatch none 0.5)
		(connect_pads
			(clearance 0)
		)
		(min_thickness 0.25)
		(keepout
			(tracks not_allowed)
			(vias allowed)
			(pads allowed)
			(copperpour not_allowed)
			(footprints allowed)
		)
		(placement
			(enabled no)
			(sheetname "")
		)
		(fill yes
			(thermal_gap 0.5)
			(thermal_bridge_width 0.5)
			(island_removal_mode 0)
		)
		(polygon
			(pts
				(arc
					(start 173.122336 -288.266632)
					(mid 172.469556 -288.266632)
					(end 173.122336 -288.266632)
				)
			)
		)
	)
	(zone
		(layers "B.Cu" "In6.Cu" "In11.Cu" "In13.Cu" "In15.Cu")
		(hatch none 0.5)
		(connect_pads
			(clearance 0)
		)
		(min_thickness 0.25)
		(keepout
			(tracks not_allowed)
			(vias allowed)
			(pads allowed)
			(copperpour not_allowed)
			(footprints allowed)
		)
		(placement
			(enabled no)
			(sheetname "")
		)
		(fill yes
			(thermal_gap 0.5)
			(thermal_bridge_width 0.5)
			(island_removal_mode 0)
		)
		(polygon
			(pts
				(arc
					(start 342.160606 -258.80314)
					(mid 341.507826 -258.80314)
					(end 342.160606 -258.80314)
				)
			)
		)
	)
	(zone
		(layers "B.Cu" "In6.Cu" "In11.Cu" "In13.Cu" "In15.Cu")
		(hatch none 0.5)
		(connect_pads
			(clearance 0)
		)
		(min_thickness 0.25)
		(keepout
			(tracks not_allowed)
			(vias allowed)
			(pads allowed)
			(copperpour not_allowed)
			(footprints allowed)
		)
		(placement
			(enabled no)
			(sheetname "")
		)
		(fill yes
			(thermal_gap 0.5)
			(thermal_bridge_width 0.5)
			(island_removal_mode 0)
		)
		(polygon
			(pts
				(arc
					(start 94.110556 -243.922804)
					(mid 93.457776 -243.922804)
					(end 94.110556 -243.922804)
				)
			)
		)
	)
	(zone
		(layers "B.Cu" "In6.Cu" "In11.Cu" "In13.Cu" "In15.Cu")
		(hatch none 0.5)
		(connect_pads
			(clearance 0)
		)
		(min_thickness 0.25)
		(keepout
			(tracks not_allowed)
			(vias allowed)
			(pads allowed)
			(copperpour not_allowed)
			(footprints allowed)
		)
		(placement
			(enabled no)
			(sheetname "")
		)
		(fill yes
			(thermal_gap 0.5)
			(thermal_bridge_width 0.5)
			(island_removal_mode 0)
		)
		(polygon
			(pts
				(arc
					(start 32.203136 -237.266734)
					(mid 31.550356 -237.266734)
					(end 32.203136 -237.266734)
				)
			)
		)
	)
	(zone
		(layers "B.Cu" "In6.Cu" "In11.Cu" "In13.Cu" "In15.Cu")
		(hatch none 0.5)
		(connect_pads
			(clearance 0)
		)
		(min_thickness 0.25)
		(keepout
			(tracks not_allowed)
			(vias allowed)
			(pads allowed)
			(copperpour not_allowed)
			(footprints allowed)
		)
		(placement
			(enabled no)
			(sheetname "")
		)
		(fill yes
			(thermal_gap 0.5)
			(thermal_bridge_width 0.5)
			(island_removal_mode 0)
		)
		(polygon
			(pts
				(arc
					(start 130.762756 -245.55069)
					(mid 130.109976 -245.55069)
					(end 130.762756 -245.55069)
				)
			)
		)
	)
	(zone
		(layers "B.Cu" "In6.Cu" "In11.Cu" "In13.Cu" "In15.Cu")
		(hatch none 0.5)
		(connect_pads
			(clearance 0)
		)
		(min_thickness 0.25)
		(keepout
			(tracks not_allowed)
			(vias allowed)
			(pads allowed)
			(copperpour not_allowed)
			(footprints allowed)
		)
		(placement
			(enabled no)
			(sheetname "")
		)
		(fill yes
			(thermal_gap 0.5)
			(thermal_bridge_width 0.5)
			(island_removal_mode 0)
		)
		(polygon
			(pts
				(arc
					(start 91.760802 -218.692222)
					(mid 91.108022 -218.692222)
					(end 91.760802 -218.692222)
				)
			)
		)
	)
	(zone
		(layers "B.Cu" "In6.Cu" "In11.Cu" "In13.Cu" "In15.Cu")
		(hatch none 0.5)
		(connect_pads
			(clearance 0)
		)
		(min_thickness 0.25)
		(keepout
			(tracks not_allowed)
			(vias allowed)
			(pads allowed)
			(copperpour not_allowed)
			(footprints allowed)
		)
		(placement
			(enabled no)
			(sheetname "")
		)
		(fill yes
			(thermal_gap 0.5)
			(thermal_bridge_width 0.5)
			(island_removal_mode 0)
		)
		(polygon
			(pts
				(arc
					(start 188.209936 -267.866622)
					(mid 187.557156 -267.866622)
					(end 188.209936 -267.866622)
				)
			)
		)
	)
	(zone
		(layers "B.Cu" "In6.Cu" "In11.Cu" "In13.Cu" "In15.Cu")
		(hatch none 0.5)
		(connect_pads
			(clearance 0)
		)
		(min_thickness 0.25)
		(keepout
			(tracks not_allowed)
			(vias allowed)
			(pads allowed)
			(copperpour not_allowed)
			(footprints allowed)
		)
		(placement
			(enabled no)
			(sheetname "")
		)
		(fill yes
			(thermal_gap 0.5)
			(thermal_bridge_width 0.5)
			(island_removal_mode 0)
		)
		(polygon
			(pts
				(arc
					(start 280.143204 -294.216582)
					(mid 279.490424 -294.216582)
					(end 280.143204 -294.216582)
				)
			)
		)
	)
	(zone
		(layers "B.Cu" "In6.Cu" "In11.Cu" "In13.Cu" "In15.Cu")
		(hatch none 0.5)
		(connect_pads
			(clearance 0)
		)
		(min_thickness 0.25)
		(keepout
			(tracks not_allowed)
			(vias allowed)
			(pads allowed)
			(copperpour not_allowed)
			(footprints allowed)
		)
		(placement
			(enabled no)
			(sheetname "")
		)
		(fill yes
			(thermal_gap 0.5)
			(thermal_bridge_width 0.5)
			(island_removal_mode 0)
		)
		(polygon
			(pts
				(arc
					(start 280.143204 -252.566678)
					(mid 279.490424 -252.566678)
					(end 280.143204 -252.566678)
				)
			)
		)
	)
	(zone
		(layers "B.Cu" "In6.Cu" "In11.Cu" "In13.Cu" "In15.Cu")
		(hatch none 0.5)
		(connect_pads
			(clearance 0)
		)
		(min_thickness 0.25)
		(keepout
			(tracks not_allowed)
			(vias allowed)
			(pads allowed)
			(copperpour not_allowed)
			(footprints allowed)
		)
		(placement
			(enabled no)
			(sheetname "")
		)
		(fill yes
			(thermal_gap 0.5)
			(thermal_bridge_width 0.5)
			(island_removal_mode 0)
		)
		(polygon
			(pts
				(arc
					(start 425.162472 -285.716726)
					(mid 424.509692 -285.716726)
					(end 425.162472 -285.716726)
				)
			)
		)
	)
	(zone
		(layers "B.Cu" "In6.Cu" "In11.Cu" "In13.Cu" "In15.Cu")
		(hatch none 0.5)
		(connect_pads
			(clearance 0)
		)
		(min_thickness 0.25)
		(keepout
			(tracks not_allowed)
			(vias allowed)
			(pads allowed)
			(copperpour not_allowed)
			(footprints allowed)
		)
		(placement
			(enabled no)
			(sheetname "")
		)
		(fill yes
			(thermal_gap 0.5)
			(thermal_bridge_width 0.5)
			(island_removal_mode 0)
		)
		(polygon
			(pts
				(arc
					(start 131.702556 -229.272846)
					(mid 131.049776 -229.272846)
					(end 131.702556 -229.272846)
				)
			)
		)
	)
	(zone
		(layers "B.Cu" "In6.Cu" "In11.Cu" "In13.Cu" "In15.Cu")
		(hatch none 0.5)
		(connect_pads
			(clearance 0)
		)
		(min_thickness 0.25)
		(keepout
			(tracks not_allowed)
			(vias allowed)
			(pads allowed)
			(copperpour not_allowed)
			(footprints allowed)
		)
		(placement
			(enabled no)
			(sheetname "")
		)
		(fill yes
			(thermal_gap 0.5)
			(thermal_bridge_width 0.5)
			(island_removal_mode 0)
		)
		(polygon
			(pts
				(arc
					(start 380.692406 -270.19758)
					(mid 380.039626 -270.19758)
					(end 380.692406 -270.19758)
				)
			)
		)
	)
	(zone
		(layers "B.Cu" "In6.Cu" "In11.Cu" "In13.Cu" "In15.Cu")
		(hatch none 0.5)
		(connect_pads
			(clearance 0)
		)
		(min_thickness 0.25)
		(keepout
			(tracks not_allowed)
			(vias allowed)
			(pads allowed)
			(copperpour not_allowed)
			(footprints allowed)
		)
		(placement
			(enabled no)
			(sheetname "")
		)
		(fill yes
			(thermal_gap 0.5)
			(thermal_bridge_width 0.5)
			(island_removal_mode 0)
		)
		(polygon
			(pts
				(arc
					(start 95.520002 -218.692222)
					(mid 94.867222 -218.692222)
					(end 95.520002 -218.692222)
				)
			)
		)
	)
	(zone
		(layers "B.Cu" "In6.Cu" "In11.Cu" "In13.Cu" "In15.Cu")
		(hatch none 0.5)
		(connect_pads
			(clearance 0)
		)
		(min_thickness 0.25)
		(keepout
			(tracks not_allowed)
			(vias allowed)
			(pads allowed)
			(copperpour not_allowed)
			(footprints allowed)
		)
		(placement
			(enabled no)
			(sheetname "")
		)
		(fill yes
			(thermal_gap 0.5)
			(thermal_bridge_width 0.5)
			(island_removal_mode 0)
		)
		(polygon
			(pts
				(arc
					(start 132.366258 -18.144744)
					(mid 131.662678 -18.144744)
					(end 132.366258 -18.144744)
				)
			)
		)
	)
	(zone
		(layers "B.Cu" "In6.Cu" "In11.Cu" "In13.Cu" "In15.Cu")
		(hatch none 0.5)
		(connect_pads
			(clearance 0)
		)
		(min_thickness 0.25)
		(keepout
			(tracks not_allowed)
			(vias allowed)
			(pads allowed)
			(copperpour not_allowed)
			(footprints allowed)
		)
		(placement
			(enabled no)
			(sheetname "")
		)
		(fill yes
			(thermal_gap 0.5)
			(thermal_bridge_width 0.5)
			(island_removal_mode 0)
		)
		(polygon
			(pts
				(arc
					(start 32.203136 -308.666642)
					(mid 31.550356 -308.666642)
					(end 32.203136 -308.666642)
				)
			)
		)
	)
	(zone
		(layers "B.Cu" "In6.Cu" "In11.Cu" "In13.Cu" "In15.Cu")
		(hatch none 0.5)
		(connect_pads
			(clearance 0)
		)
		(min_thickness 0.25)
		(keepout
			(tracks not_allowed)
			(vias allowed)
			(pads allowed)
			(copperpour not_allowed)
			(footprints allowed)
		)
		(placement
			(enabled no)
			(sheetname "")
		)
		(fill yes
			(thermal_gap 0.5)
			(thermal_bridge_width 0.5)
			(island_removal_mode 0)
		)
		(polygon
			(pts
				(arc
					(start 299.330872 -229.616762)
					(mid 298.678092 -229.616762)
					(end 299.330872 -229.616762)
				)
			)
		)
	)
	(zone
		(layers "B.Cu" "In6.Cu" "In11.Cu" "In13.Cu" "In15.Cu")
		(hatch none 0.5)
		(connect_pads
			(clearance 0)
		)
		(min_thickness 0.25)
		(keepout
			(tracks not_allowed)
			(vias allowed)
			(pads allowed)
			(copperpour not_allowed)
			(footprints allowed)
		)
		(placement
			(enabled no)
			(sheetname "")
		)
		(fill yes
			(thermal_gap 0.5)
			(thermal_bridge_width 0.5)
			(island_removal_mode 0)
		)
		(polygon
			(pts
				(arc
					(start 378.812806 -260.430772)
					(mid 378.160026 -260.430772)
					(end 378.812806 -260.430772)
				)
			)
		)
	)
	(zone
		(layers "B.Cu" "In6.Cu" "In11.Cu" "In13.Cu" "In15.Cu")
		(hatch none 0.5)
		(connect_pads
			(clearance 0)
		)
		(min_thickness 0.25)
		(keepout
			(tracks not_allowed)
			(vias allowed)
			(pads allowed)
			(copperpour not_allowed)
			(footprints allowed)
		)
		(placement
			(enabled no)
			(sheetname "")
		)
		(fill yes
			(thermal_gap 0.5)
			(thermal_bridge_width 0.5)
			(island_removal_mode 0)
		)
		(polygon
			(pts
				(arc
					(start 129.822956 -232.528364)
					(mid 129.170176 -232.528364)
					(end 129.822956 -232.528364)
				)
			)
		)
	)
	(zone
		(layers "B.Cu" "In6.Cu" "In11.Cu" "In13.Cu" "In15.Cu")
		(hatch none 0.5)
		(connect_pads
			(clearance 0)
		)
		(min_thickness 0.25)
		(keepout
			(tracks not_allowed)
			(vias allowed)
			(pads allowed)
			(copperpour not_allowed)
			(footprints allowed)
		)
		(placement
			(enabled no)
			(sheetname "")
		)
		(fill yes
			(thermal_gap 0.5)
			(thermal_bridge_width 0.5)
			(island_removal_mode 0)
		)
		(polygon
			(pts
				(arc
					(start 373.064024 -217.878406)
					(mid 372.411244 -217.878406)
					(end 373.064024 -217.878406)
				)
			)
		)
	)
	(zone
		(layers "B.Cu" "In6.Cu" "In11.Cu" "In13.Cu" "In15.Cu")
		(hatch none 0.5)
		(connect_pads
			(clearance 0)
		)
		(min_thickness 0.25)
		(keepout
			(tracks not_allowed)
			(vias allowed)
			(pads allowed)
			(copperpour not_allowed)
			(footprints allowed)
		)
		(placement
			(enabled no)
			(sheetname "")
		)
		(fill yes
			(thermal_gap 0.5)
			(thermal_bridge_width 0.5)
			(island_removal_mode 0)
		)
		(polygon
			(pts
				(arc
					(start 36.303204 -259.366766)
					(mid 35.650424 -259.366766)
					(end 36.303204 -259.366766)
				)
			)
		)
	)
	(zone
		(layers "B.Cu" "In6.Cu" "In11.Cu" "In13.Cu" "In15.Cu")
		(hatch none 0.5)
		(connect_pads
			(clearance 0)
		)
		(min_thickness 0.25)
		(keepout
			(tracks not_allowed)
			(vias allowed)
			(pads allowed)
			(copperpour not_allowed)
			(footprints allowed)
		)
		(placement
			(enabled no)
			(sheetname "")
		)
		(fill yes
			(thermal_gap 0.5)
			(thermal_bridge_width 0.5)
			(island_removal_mode 0)
		)
		(polygon
			(pts
				(arc
					(start 380.222506 -288.917126)
					(mid 379.569726 -288.917126)
					(end 380.222506 -288.917126)
				)
			)
		)
	)
	(zone
		(layers "B.Cu" "In6.Cu" "In11.Cu" "In13.Cu" "In15.Cu")
		(hatch none 0.5)
		(connect_pads
			(clearance 0)
		)
		(min_thickness 0.25)
		(keepout
			(tracks not_allowed)
			(vias allowed)
			(pads allowed)
			(copperpour not_allowed)
			(footprints allowed)
		)
		(placement
			(enabled no)
			(sheetname "")
		)
		(fill yes
			(thermal_gap 0.5)
			(thermal_bridge_width 0.5)
			(island_removal_mode 0)
		)
		(polygon
			(pts
				(arc
					(start 94.220538 -276.708616)
					(mid 93.567758 -276.708616)
					(end 94.220538 -276.708616)
				)
			)
		)
	)
	(zone
		(layers "B.Cu" "In6.Cu" "In11.Cu" "In13.Cu" "In15.Cu")
		(hatch none 0.5)
		(connect_pads
			(clearance 0)
		)
		(min_thickness 0.25)
		(keepout
			(tracks not_allowed)
			(vias allowed)
			(pads allowed)
			(copperpour not_allowed)
			(footprints allowed)
		)
		(placement
			(enabled no)
			(sheetname "")
		)
		(fill yes
			(thermal_gap 0.5)
			(thermal_bridge_width 0.5)
			(island_removal_mode 0)
		)
		(polygon
			(pts
				(arc
					(start 344.510106 -288.917126)
					(mid 343.857326 -288.917126)
					(end 344.510106 -288.917126)
				)
			)
		)
	)
	(zone
		(layers "B.Cu" "In6.Cu" "In11.Cu" "In13.Cu" "In15.Cu")
		(hatch none 0.5)
		(connect_pads
			(clearance 0)
		)
		(min_thickness 0.25)
		(keepout
			(tracks not_allowed)
			(vias allowed)
			(pads allowed)
			(copperpour not_allowed)
			(footprints allowed)
		)
		(placement
			(enabled no)
			(sheetname "")
		)
		(fill yes
			(thermal_gap 0.5)
			(thermal_bridge_width 0.5)
			(island_removal_mode 0)
		)
		(polygon
			(pts
				(arc
					(start 357.087424 -217.878406)
					(mid 356.434644 -217.878406)
					(end 357.087424 -217.878406)
				)
			)
		)
	)
	(zone
		(layers "B.Cu" "In6.Cu" "In11.Cu" "In13.Cu" "In15.Cu")
		(hatch none 0.5)
		(connect_pads
			(clearance 0)
		)
		(min_thickness 0.25)
		(keepout
			(tracks not_allowed)
			(vias allowed)
			(pads allowed)
			(copperpour not_allowed)
			(footprints allowed)
		)
		(placement
			(enabled no)
			(sheetname "")
		)
		(fill yes
			(thermal_gap 0.5)
			(thermal_bridge_width 0.5)
			(island_removal_mode 0)
		)
		(polygon
			(pts
				(arc
					(start 131.812538 -276.708616)
					(mid 131.159758 -276.708616)
					(end 131.812538 -276.708616)
				)
			)
		)
	)
	(zone
		(layers "B.Cu" "In6.Cu" "In11.Cu" "In13.Cu" "In15.Cu")
		(hatch none 0.5)
		(connect_pads
			(clearance 0)
		)
		(min_thickness 0.25)
		(keepout
			(tracks not_allowed)
			(vias allowed)
			(pads allowed)
			(copperpour not_allowed)
			(footprints allowed)
		)
		(placement
			(enabled no)
			(sheetname "")
		)
		(fill yes
			(thermal_gap 0.5)
			(thermal_bridge_width 0.5)
			(island_removal_mode 0)
		)
		(polygon
			(pts
				(arc
					(start 130.872738 -273.453098)
					(mid 130.219958 -273.453098)
					(end 130.872738 -273.453098)
				)
			)
		)
	)
	(zone
		(layers "B.Cu" "In6.Cu" "In11.Cu" "In13.Cu" "In15.Cu")
		(hatch none 0.5)
		(connect_pads
			(clearance 0)
		)
		(min_thickness 0.25)
		(keepout
			(tracks not_allowed)
			(vias allowed)
			(pads allowed)
			(copperpour not_allowed)
			(footprints allowed)
		)
		(placement
			(enabled no)
			(sheetname "")
		)
		(fill yes
			(thermal_gap 0.5)
			(thermal_bridge_width 0.5)
			(island_removal_mode 0)
		)
		(polygon
			(pts
				(arc
					(start 421.062404 -280.61666)
					(mid 420.409624 -280.61666)
					(end 421.062404 -280.61666)
				)
			)
		)
	)
	(zone
		(layers "B.Cu" "In6.Cu" "In11.Cu" "In13.Cu" "In15.Cu")
		(hatch none 0.5)
		(connect_pads
			(clearance 0)
		)
		(min_thickness 0.25)
		(keepout
			(tracks not_allowed)
			(vias allowed)
			(pads allowed)
			(copperpour not_allowed)
			(footprints allowed)
		)
		(placement
			(enabled no)
			(sheetname "")
		)
		(fill yes
			(thermal_gap 0.5)
			(thermal_bridge_width 0.5)
			(island_removal_mode 0)
		)
		(polygon
			(pts
				(arc
					(start 112.906556 -217.878406)
					(mid 112.253776 -217.878406)
					(end 112.906556 -217.878406)
				)
			)
		)
	)
	(zone
		(layers "B.Cu" "In6.Cu" "In11.Cu" "In13.Cu" "In15.Cu")
		(hatch none 0.5)
		(connect_pads
			(clearance 0)
		)
		(min_thickness 0.25)
		(keepout
			(tracks not_allowed)
			(vias allowed)
			(pads allowed)
			(copperpour not_allowed)
			(footprints allowed)
		)
		(placement
			(enabled no)
			(sheetname "")
		)
		(fill yes
			(thermal_gap 0.5)
			(thermal_bridge_width 0.5)
			(island_removal_mode 0)
		)
		(polygon
			(pts
				(arc
					(start 377.29287 -218.692222)
					(mid 376.64009 -218.692222)
					(end 377.29287 -218.692222)
				)
			)
		)
	)
	(zone
		(layers "B.Cu" "In6.Cu" "In11.Cu" "In13.Cu" "In15.Cu")
		(hatch none 0.5)
		(connect_pads
			(clearance 0)
		)
		(min_thickness 0.25)
		(keepout
			(tracks not_allowed)
			(vias allowed)
			(pads allowed)
			(copperpour not_allowed)
			(footprints allowed)
		)
		(placement
			(enabled no)
			(sheetname "")
		)
		(fill yes
			(thermal_gap 0.5)
			(thermal_bridge_width 0.5)
			(island_removal_mode 0)
		)
		(polygon
			(pts
				(arc
					(start 102.208838 -288.917126)
					(mid 101.556058 -288.917126)
					(end 102.208838 -288.917126)
				)
			)
		)
	)
	(zone
		(layers "B.Cu" "In6.Cu" "In11.Cu" "In13.Cu" "In15.Cu")
		(hatch none 0.5)
		(connect_pads
			(clearance 0)
		)
		(min_thickness 0.25)
		(keepout
			(tracks not_allowed)
			(vias allowed)
			(pads allowed)
			(copperpour not_allowed)
			(footprints allowed)
		)
		(placement
			(enabled no)
			(sheetname "")
		)
		(fill yes
			(thermal_gap 0.5)
			(thermal_bridge_width 0.5)
			(island_removal_mode 0)
		)
		(polygon
			(pts
				(arc
					(start 99.279202 -218.692222)
					(mid 98.626422 -218.692222)
					(end 99.279202 -218.692222)
				)
			)
		)
	)
	(zone
		(layers "B.Cu" "In6.Cu" "In11.Cu" "In13.Cu" "In15.Cu")
		(hatch none 0.5)
		(connect_pads
			(clearance 0)
		)
		(min_thickness 0.25)
		(keepout
			(tracks not_allowed)
			(vias allowed)
			(pads allowed)
			(copperpour not_allowed)
			(footprints allowed)
		)
		(placement
			(enabled no)
			(sheetname "")
		)
		(fill yes
			(thermal_gap 0.5)
			(thermal_bridge_width 0.5)
			(island_removal_mode 0)
		)
		(polygon
			(pts
				(arc
					(start 440.250072 -206.666592)
					(mid 439.597292 -206.666592)
					(end 440.250072 -206.666592)
				)
			)
		)
	)
	(zone
		(layers "B.Cu" "In6.Cu" "In11.Cu" "In13.Cu" "In15.Cu")
		(hatch none 0.5)
		(connect_pads
			(clearance 0)
		)
		(min_thickness 0.25)
		(keepout
			(tracks not_allowed)
			(vias allowed)
			(pads allowed)
			(copperpour not_allowed)
			(footprints allowed)
		)
		(placement
			(enabled no)
			(sheetname "")
		)
		(fill yes
			(thermal_gap 0.5)
			(thermal_bridge_width 0.5)
			(island_removal_mode 0)
		)
		(polygon
			(pts
				(arc
					(start 129.932938 -260.430772)
					(mid 129.280158 -260.430772)
					(end 129.932938 -260.430772)
				)
			)
		)
	)
	(zone
		(layers "B.Cu" "In6.Cu" "In11.Cu" "In13.Cu" "In15.Cu")
		(hatch none 0.5)
		(connect_pads
			(clearance 0)
		)
		(min_thickness 0.25)
		(keepout
			(tracks not_allowed)
			(vias allowed)
			(pads allowed)
			(copperpour not_allowed)
			(footprints allowed)
		)
		(placement
			(enabled no)
			(sheetname "")
		)
		(fill yes
			(thermal_gap 0.5)
			(thermal_bridge_width 0.5)
			(island_removal_mode 0)
		)
		(polygon
			(pts
				(arc
					(start 440.224672 -246.616728)
					(mid 439.571892 -246.616728)
					(end 440.224672 -246.616728)
				)
			)
		)
	)
	(zone
		(layers "B.Cu" "In6.Cu" "In11.Cu" "In13.Cu" "In15.Cu")
		(hatch none 0.5)
		(connect_pads
			(clearance 0)
		)
		(min_thickness 0.25)
		(keepout
			(tracks not_allowed)
			(vias allowed)
			(pads allowed)
			(copperpour not_allowed)
			(footprints allowed)
		)
		(placement
			(enabled no)
			(sheetname "")
		)
		(fill yes
			(thermal_gap 0.5)
			(thermal_bridge_width 0.5)
			(island_removal_mode 0)
		)
		(polygon
			(pts
				(arc
					(start 362.256324 -218.692222)
					(mid 361.603544 -218.692222)
					(end 362.256324 -218.692222)
				)
			)
		)
	)
	(zone
		(layers "B.Cu" "In6.Cu" "In11.Cu" "In13.Cu" "In15.Cu")
		(hatch none 0.5)
		(connect_pads
			(clearance 0)
		)
		(min_thickness 0.25)
		(keepout
			(tracks not_allowed)
			(vias allowed)
			(pads allowed)
			(copperpour not_allowed)
			(footprints allowed)
		)
		(placement
			(enabled no)
			(sheetname "")
		)
		(fill yes
			(thermal_gap 0.5)
			(thermal_bridge_width 0.5)
			(island_removal_mode 0)
		)
		(polygon
			(pts
				(arc
					(start 421.062404 -301.01667)
					(mid 420.409624 -301.01667)
					(end 421.062404 -301.01667)
				)
			)
		)
	)
	(zone
		(layers "B.Cu" "In6.Cu" "In11.Cu" "In13.Cu" "In15.Cu")
		(hatch none 0.5)
		(connect_pads
			(clearance 0)
		)
		(min_thickness 0.25)
		(keepout
			(tracks not_allowed)
			(vias allowed)
			(pads allowed)
			(copperpour not_allowed)
			(footprints allowed)
		)
		(placement
			(enabled no)
			(sheetname "")
		)
		(fill yes
			(thermal_gap 0.5)
			(thermal_bridge_width 0.5)
			(island_removal_mode 0)
		)
		(polygon
			(pts
				(arc
					(start 116.195602 -218.692222)
					(mid 115.542822 -218.692222)
					(end 116.195602 -218.692222)
				)
			)
		)
	)
	(zone
		(layers "B.Cu" "In6.Cu" "In11.Cu" "In13.Cu" "In15.Cu")
		(hatch none 0.5)
		(connect_pads
			(clearance 0)
		)
		(min_thickness 0.25)
		(keepout
			(tracks not_allowed)
			(vias allowed)
			(pads allowed)
			(copperpour not_allowed)
			(footprints allowed)
		)
		(placement
			(enabled no)
			(sheetname "")
		)
		(fill yes
			(thermal_gap 0.5)
			(thermal_bridge_width 0.5)
			(island_removal_mode 0)
		)
		(polygon
			(pts
				(arc
					(start 188.209936 -233.86669)
					(mid 187.557156 -233.86669)
					(end 188.209936 -233.86669)
				)
			)
		)
	)
	(zone
		(layers "B.Cu" "In6.Cu" "In11.Cu" "In13.Cu" "In15.Cu")
		(hatch none 0.5)
		(connect_pads
			(clearance 0)
		)
		(min_thickness 0.25)
		(keepout
			(tracks not_allowed)
			(vias allowed)
			(pads allowed)
			(copperpour not_allowed)
			(footprints allowed)
		)
		(placement
			(enabled no)
			(sheetname "")
		)
		(fill yes
			(thermal_gap 0.5)
			(thermal_bridge_width 0.5)
			(island_removal_mode 0)
		)
		(polygon
			(pts
				(arc
					(start 379.752606 -268.569694)
					(mid 379.099826 -268.569694)
					(end 379.752606 -268.569694)
				)
			)
		)
	)
	(zone
		(layers "B.Cu" "In6.Cu" "In11.Cu" "In13.Cu" "In15.Cu")
		(hatch none 0.5)
		(connect_pads
			(clearance 0)
		)
		(min_thickness 0.25)
		(keepout
			(tracks not_allowed)
			(vias allowed)
			(pads allowed)
			(copperpour not_allowed)
			(footprints allowed)
		)
		(placement
			(enabled no)
			(sheetname "")
		)
		(fill yes
			(thermal_gap 0.5)
			(thermal_bridge_width 0.5)
			(island_removal_mode 0)
		)
		(polygon
			(pts
				(arc
					(start 32.203136 -241.516662)
					(mid 31.550356 -241.516662)
					(end 32.203136 -241.516662)
				)
			)
		)
	)
	(zone
		(layers "B.Cu" "In6.Cu" "In11.Cu" "In13.Cu" "In15.Cu")
		(hatch none 0.5)
		(connect_pads
			(clearance 0)
		)
		(min_thickness 0.25)
		(keepout
			(tracks not_allowed)
			(vias allowed)
			(pads allowed)
			(copperpour not_allowed)
			(footprints allowed)
		)
		(placement
			(enabled no)
			(sheetname "")
		)
		(fill yes
			(thermal_gap 0.5)
			(thermal_bridge_width 0.5)
			(island_removal_mode 0)
		)
		(polygon
			(pts
				(arc
					(start 188.209936 -297.616626)
					(mid 187.557156 -297.616626)
					(end 188.209936 -297.616626)
				)
			)
		)
	)
	(zone
		(layers "B.Cu" "In6.Cu" "In11.Cu" "In13.Cu" "In15.Cu")
		(hatch none 0.5)
		(connect_pads
			(clearance 0)
		)
		(min_thickness 0.25)
		(keepout
			(tracks not_allowed)
			(vias allowed)
			(pads allowed)
			(copperpour not_allowed)
			(footprints allowed)
		)
		(placement
			(enabled no)
			(sheetname "")
		)
		(fill yes
			(thermal_gap 0.5)
			(thermal_bridge_width 0.5)
			(island_removal_mode 0)
		)
		(polygon
			(pts
				(arc
					(start 51.390804 -227.91674)
					(mid 50.738024 -227.91674)
					(end 51.390804 -227.91674)
				)
			)
		)
	)
	(zone
		(layers "B.Cu" "In6.Cu" "In11.Cu" "In13.Cu" "In15.Cu")
		(hatch none 0.5)
		(connect_pads
			(clearance 0)
		)
		(min_thickness 0.25)
		(keepout
			(tracks not_allowed)
			(vias allowed)
			(pads allowed)
			(copperpour not_allowed)
			(footprints allowed)
		)
		(placement
			(enabled no)
			(sheetname "")
		)
		(fill yes
			(thermal_gap 0.5)
			(thermal_bridge_width 0.5)
			(island_removal_mode 0)
		)
		(polygon
			(pts
				(arc
					(start 188.209936 -209.216752)
					(mid 187.557156 -209.216752)
					(end 188.209936 -209.216752)
				)
			)
		)
	)
	(zone
		(layers "B.Cu" "In6.Cu" "In11.Cu" "In13.Cu" "In15.Cu")
		(hatch none 0.5)
		(connect_pads
			(clearance 0)
		)
		(min_thickness 0.25)
		(keepout
			(tracks not_allowed)
			(vias allowed)
			(pads allowed)
			(copperpour not_allowed)
			(footprints allowed)
		)
		(placement
			(enabled no)
			(sheetname "")
		)
		(fill yes
			(thermal_gap 0.5)
			(thermal_bridge_width 0.5)
			(island_removal_mode 0)
		)
		(polygon
			(pts
				(arc
					(start 379.642624 -243.922804)
					(mid 378.989844 -243.922804)
					(end 379.642624 -243.922804)
				)
			)
		)
	)
	(zone
		(layers "B.Cu" "In6.Cu" "In11.Cu" "In13.Cu" "In15.Cu")
		(hatch none 0.5)
		(connect_pads
			(clearance 0)
		)
		(min_thickness 0.25)
		(keepout
			(tracks not_allowed)
			(vias allowed)
			(pads allowed)
			(copperpour not_allowed)
			(footprints allowed)
		)
		(placement
			(enabled no)
			(sheetname "")
		)
		(fill yes
			(thermal_gap 0.5)
			(thermal_bridge_width 0.5)
			(island_removal_mode 0)
		)
		(polygon
			(pts
				(arc
					(start 131.812538 -275.08073)
					(mid 131.159758 -275.08073)
					(end 131.812538 -275.08073)
				)
			)
		)
	)
	(zone
		(layers "B.Cu" "In6.Cu" "In11.Cu" "In13.Cu" "In15.Cu")
		(hatch none 0.5)
		(connect_pads
			(clearance 0)
		)
		(min_thickness 0.25)
		(keepout
			(tracks not_allowed)
			(vias allowed)
			(pads allowed)
			(copperpour not_allowed)
			(footprints allowed)
		)
		(placement
			(enabled no)
			(sheetname "")
		)
		(fill yes
			(thermal_gap 0.5)
			(thermal_bridge_width 0.5)
			(island_removal_mode 0)
		)
		(polygon
			(pts
				(arc
					(start 340.171024 -243.922804)
					(mid 339.518244 -243.922804)
					(end 340.171024 -243.922804)
				)
			)
		)
	)
	(zone
		(layers "B.Cu" "In6.Cu" "In11.Cu" "In13.Cu" "In15.Cu")
		(hatch none 0.5)
		(connect_pads
			(clearance 0)
		)
		(min_thickness 0.25)
		(keepout
			(tracks not_allowed)
			(vias allowed)
			(pads allowed)
			(copperpour not_allowed)
			(footprints allowed)
		)
		(placement
			(enabled no)
			(sheetname "")
		)
		(fill yes
			(thermal_gap 0.5)
			(thermal_bridge_width 0.5)
			(island_removal_mode 0)
		)
		(polygon
			(pts
				(arc
					(start 343.061544 -47.040292)
					(mid 342.408764 -47.040292)
					(end 343.061544 -47.040292)
				)
			)
		)
	)
	(zone
		(layers "B.Cu" "In6.Cu" "In11.Cu" "In13.Cu" "In15.Cu")
		(hatch none 0.5)
		(connect_pads
			(clearance 0)
		)
		(min_thickness 0.25)
		(keepout
			(tracks not_allowed)
			(vias allowed)
			(pads allowed)
			(copperpour not_allowed)
			(footprints allowed)
		)
		(placement
			(enabled no)
			(sheetname "")
		)
		(fill yes
			(thermal_gap 0.5)
			(thermal_bridge_width 0.5)
			(island_removal_mode 0)
		)
		(polygon
			(pts
				(arc
					(start 380.692406 -275.08073)
					(mid 380.039626 -275.08073)
					(end 380.692406 -275.08073)
				)
			)
		)
	)
	(zone
		(layers "B.Cu" "In6.Cu" "In11.Cu" "In13.Cu" "In15.Cu")
		(hatch none 0.5)
		(connect_pads
			(clearance 0)
		)
		(min_thickness 0.25)
		(keepout
			(tracks not_allowed)
			(vias allowed)
			(pads allowed)
			(copperpour not_allowed)
			(footprints allowed)
		)
		(placement
			(enabled no)
			(sheetname "")
		)
		(fill yes
			(thermal_gap 0.5)
			(thermal_bridge_width 0.5)
			(island_removal_mode 0)
		)
		(polygon
			(pts
				(arc
					(start 94.580202 -239.853216)
					(mid 93.927422 -239.853216)
					(end 94.580202 -239.853216)
				)
			)
		)
	)
	(zone
		(layers "B.Cu" "In6.Cu" "In11.Cu" "In13.Cu" "In15.Cu")
		(hatch none 0.5)
		(connect_pads
			(clearance 0)
		)
		(min_thickness 0.25)
		(keepout
			(tracks not_allowed)
			(vias allowed)
			(pads allowed)
			(copperpour not_allowed)
			(footprints allowed)
		)
		(placement
			(enabled no)
			(sheetname "")
		)
		(fill yes
			(thermal_gap 0.5)
			(thermal_bridge_width 0.5)
			(island_removal_mode 0)
		)
		(polygon
			(pts
				(arc
					(start 280.143204 -205.816708)
					(mid 279.490424 -205.816708)
					(end 280.143204 -205.816708)
				)
			)
		)
	)
	(zone
		(layers "B.Cu" "In6.Cu" "In11.Cu" "In13.Cu" "In15.Cu")
		(hatch none 0.5)
		(connect_pads
			(clearance 0)
		)
		(min_thickness 0.25)
		(keepout
			(tracks not_allowed)
			(vias allowed)
			(pads allowed)
			(copperpour not_allowed)
			(footprints allowed)
		)
		(placement
			(enabled no)
			(sheetname "")
		)
		(fill yes
			(thermal_gap 0.5)
			(thermal_bridge_width 0.5)
			(island_removal_mode 0)
		)
		(polygon
			(pts
				(arc
					(start 28.759404 -259.366766)
					(mid 28.106624 -259.366766)
					(end 28.759404 -259.366766)
				)
			)
		)
	)
	(zone
		(layers "B.Cu" "In6.Cu" "In11.Cu" "In13.Cu" "In15.Cu")
		(hatch none 0.5)
		(connect_pads
			(clearance 0)
		)
		(min_thickness 0.25)
		(keepout
			(tracks not_allowed)
			(vias allowed)
			(pads allowed)
			(copperpour not_allowed)
			(footprints allowed)
		)
		(placement
			(enabled no)
			(sheetname "")
		)
		(fill yes
			(thermal_gap 0.5)
			(thermal_bridge_width 0.5)
			(island_removal_mode 0)
		)
		(polygon
			(pts
				(arc
					(start 188.209936 -238.116618)
					(mid 187.557156 -238.116618)
					(end 188.209936 -238.116618)
				)
			)
		)
	)
	(zone
		(layers "B.Cu" "In6.Cu" "In11.Cu" "In13.Cu" "In15.Cu")
		(hatch none 0.5)
		(connect_pads
			(clearance 0)
		)
		(min_thickness 0.25)
		(keepout
			(tracks not_allowed)
			(vias allowed)
			(pads allowed)
			(copperpour not_allowed)
			(footprints allowed)
		)
		(placement
			(enabled no)
			(sheetname "")
		)
		(fill yes
			(thermal_gap 0.5)
			(thermal_bridge_width 0.5)
			(island_removal_mode 0)
		)
		(polygon
			(pts
				(arc
					(start 132.642356 -242.294918)
					(mid 131.989576 -242.294918)
					(end 132.642356 -242.294918)
				)
			)
		)
	)
	(zone
		(layers "B.Cu" "In6.Cu" "In11.Cu" "In13.Cu" "In15.Cu")
		(hatch none 0.5)
		(connect_pads
			(clearance 0)
		)
		(min_thickness 0.25)
		(keepout
			(tracks not_allowed)
			(vias allowed)
			(pads allowed)
			(copperpour not_allowed)
			(footprints allowed)
		)
		(placement
			(enabled no)
			(sheetname "")
		)
		(fill yes
			(thermal_gap 0.5)
			(thermal_bridge_width 0.5)
			(island_removal_mode 0)
		)
		(polygon
			(pts
				(arc
					(start 117.135402 -217.064336)
					(mid 116.482622 -217.064336)
					(end 117.135402 -217.064336)
				)
			)
		)
	)
	(zone
		(layers "B.Cu" "In6.Cu" "In11.Cu" "In13.Cu" "In15.Cu")
		(hatch none 0.5)
		(connect_pads
			(clearance 0)
		)
		(min_thickness 0.25)
		(keepout
			(tracks not_allowed)
			(vias allowed)
			(pads allowed)
			(copperpour not_allowed)
			(footprints allowed)
		)
		(placement
			(enabled no)
			(sheetname "")
		)
		(fill yes
			(thermal_gap 0.5)
			(thermal_bridge_width 0.5)
			(island_removal_mode 0)
		)
		(polygon
			(pts
				(arc
					(start 341.58047 -243.108988)
					(mid 340.92769 -243.108988)
					(end 341.58047 -243.108988)
				)
			)
		)
	)
	(zone
		(layers "B.Cu" "In6.Cu" "In11.Cu" "In13.Cu" "In15.Cu")
		(hatch none 0.5)
		(connect_pads
			(clearance 0)
		)
		(min_thickness 0.25)
		(keepout
			(tracks not_allowed)
			(vias allowed)
			(pads allowed)
			(copperpour not_allowed)
			(footprints allowed)
		)
		(placement
			(enabled no)
			(sheetname "")
		)
		(fill yes
			(thermal_gap 0.5)
			(thermal_bridge_width 0.5)
			(island_removal_mode 0)
		)
		(polygon
			(pts
				(arc
					(start 349.09887 -218.692222)
					(mid 348.44609 -218.692222)
					(end 349.09887 -218.692222)
				)
			)
		)
	)
	(zone
		(layers "B.Cu" "In6.Cu" "In11.Cu" "In13.Cu" "In15.Cu")
		(hatch none 0.5)
		(connect_pads
			(clearance 0)
		)
		(min_thickness 0.25)
		(keepout
			(tracks not_allowed)
			(vias allowed)
			(pads allowed)
			(copperpour not_allowed)
			(footprints allowed)
		)
		(placement
			(enabled no)
			(sheetname "")
		)
		(fill yes
			(thermal_gap 0.5)
			(thermal_bridge_width 0.5)
			(island_removal_mode 0)
		)
		(polygon
			(pts
				(arc
					(start 284.243272 -212.616796)
					(mid 283.590492 -212.616796)
					(end 284.243272 -212.616796)
				)
			)
		)
	)
	(zone
		(layers "B.Cu" "In6.Cu" "In11.Cu" "In13.Cu" "In15.Cu")
		(hatch none 0.5)
		(connect_pads
			(clearance 0)
		)
		(min_thickness 0.25)
		(keepout
			(tracks not_allowed)
			(vias allowed)
			(pads allowed)
			(copperpour not_allowed)
			(footprints allowed)
		)
		(placement
			(enabled no)
			(sheetname "")
		)
		(fill yes
			(thermal_gap 0.5)
			(thermal_bridge_width 0.5)
			(island_removal_mode 0)
		)
		(polygon
			(pts
				(arc
					(start 343.875868 -46.570392)
					(mid 343.223088 -46.570392)
					(end 343.875868 -46.570392)
				)
			)
		)
	)
	(zone
		(layers "B.Cu" "In6.Cu" "In11.Cu" "In13.Cu" "In15.Cu")
		(hatch none 0.5)
		(connect_pads
			(clearance 0)
		)
		(min_thickness 0.25)
		(keepout
			(tracks not_allowed)
			(vias allowed)
			(pads allowed)
			(copperpour not_allowed)
			(footprints allowed)
		)
		(placement
			(enabled no)
			(sheetname "")
		)
		(fill yes
			(thermal_gap 0.5)
			(thermal_bridge_width 0.5)
			(island_removal_mode 0)
		)
		(polygon
			(pts
				(arc
					(start 192.310004 -260.21665)
					(mid 191.657224 -260.21665)
					(end 192.310004 -260.21665)
				)
			)
		)
	)
	(zone
		(layers "B.Cu" "In6.Cu" "In11.Cu" "In13.Cu" "In15.Cu")
		(hatch none 0.5)
		(connect_pads
			(clearance 0)
		)
		(min_thickness 0.25)
		(keepout
			(tracks not_allowed)
			(vias allowed)
			(pads allowed)
			(copperpour not_allowed)
			(footprints allowed)
		)
		(placement
			(enabled no)
			(sheetname "")
		)
		(fill yes
			(thermal_gap 0.5)
			(thermal_bridge_width 0.5)
			(island_removal_mode 0)
		)
		(polygon
			(pts
				(arc
					(start 131.702556 -217.878406)
					(mid 131.049776 -217.878406)
					(end 131.702556 -217.878406)
				)
			)
		)
	)
	(zone
		(layers "B.Cu" "In6.Cu" "In11.Cu" "In13.Cu" "In15.Cu")
		(hatch none 0.5)
		(connect_pads
			(clearance 0)
		)
		(min_thickness 0.25)
		(keepout
			(tracks not_allowed)
			(vias allowed)
			(pads allowed)
			(copperpour not_allowed)
			(footprints allowed)
		)
		(placement
			(enabled no)
			(sheetname "")
		)
		(fill yes
			(thermal_gap 0.5)
			(thermal_bridge_width 0.5)
			(island_removal_mode 0)
		)
		(polygon
			(pts
				(arc
					(start 440.250072 -208.366614)
					(mid 439.597292 -208.366614)
					(end 440.250072 -208.366614)
				)
			)
		)
	)
	(zone
		(layers "B.Cu" "In6.Cu" "In11.Cu" "In13.Cu" "In15.Cu")
		(hatch none 0.5)
		(connect_pads
			(clearance 0)
		)
		(min_thickness 0.25)
		(keepout
			(tracks not_allowed)
			(vias allowed)
			(pads allowed)
			(copperpour not_allowed)
			(footprints allowed)
		)
		(placement
			(enabled no)
			(sheetname "")
		)
		(fill yes
			(thermal_gap 0.5)
			(thermal_bridge_width 0.5)
			(island_removal_mode 0)
		)
		(polygon
			(pts
				(arc
					(start 92.810584 -261.244842)
					(mid 92.157804 -261.244842)
					(end 92.810584 -261.244842)
				)
			)
		)
	)
	(zone
		(layers "B.Cu" "In6.Cu" "In11.Cu" "In13.Cu" "In15.Cu")
		(hatch none 0.5)
		(connect_pads
			(clearance 0)
		)
		(min_thickness 0.25)
		(keepout
			(tracks not_allowed)
			(vias allowed)
			(pads allowed)
			(copperpour not_allowed)
			(footprints allowed)
		)
		(placement
			(enabled no)
			(sheetname "")
		)
		(fill yes
			(thermal_gap 0.5)
			(thermal_bridge_width 0.5)
			(island_removal_mode 0)
		)
		(polygon
			(pts
				(arc
					(start 96.570038 -288.917126)
					(mid 95.917258 -288.917126)
					(end 96.570038 -288.917126)
				)
			)
		)
	)
	(zone
		(layers "B.Cu" "In6.Cu" "In11.Cu" "In13.Cu" "In15.Cu")
		(hatch none 0.5)
		(connect_pads
			(clearance 0)
		)
		(min_thickness 0.25)
		(keepout
			(tracks not_allowed)
			(vias allowed)
			(pads allowed)
			(copperpour not_allowed)
			(footprints allowed)
		)
		(placement
			(enabled no)
			(sheetname "")
		)
		(fill yes
			(thermal_gap 0.5)
			(thermal_bridge_width 0.5)
			(island_removal_mode 0)
		)
		(polygon
			(pts
				(arc
					(start 383.511806 -288.103056)
					(mid 382.859026 -288.103056)
					(end 383.511806 -288.103056)
				)
			)
		)
	)
	(zone
		(layers "B.Cu" "In6.Cu" "In11.Cu" "In13.Cu" "In15.Cu")
		(hatch none 0.5)
		(connect_pads
			(clearance 0)
		)
		(min_thickness 0.25)
		(keepout
			(tracks not_allowed)
			(vias allowed)
			(pads allowed)
			(copperpour not_allowed)
			(footprints allowed)
		)
		(placement
			(enabled no)
			(sheetname "")
		)
		(fill yes
			(thermal_gap 0.5)
			(thermal_bridge_width 0.5)
			(island_removal_mode 0)
		)
		(polygon
			(pts
				(arc
					(start 129.352802 -249.620024)
					(mid 128.700022 -249.620024)
					(end 129.352802 -249.620024)
				)
			)
		)
	)
	(zone
		(layers "B.Cu" "In6.Cu" "In11.Cu" "In13.Cu" "In15.Cu")
		(hatch none 0.5)
		(connect_pads
			(clearance 0)
		)
		(min_thickness 0.25)
		(keepout
			(tracks not_allowed)
			(vias allowed)
			(pads allowed)
			(copperpour not_allowed)
			(footprints allowed)
		)
		(placement
			(enabled no)
			(sheetname "")
		)
		(fill yes
			(thermal_gap 0.5)
			(thermal_bridge_width 0.5)
			(island_removal_mode 0)
		)
		(polygon
			(pts
				(arc
					(start 108.677202 -218.692222)
					(mid 108.024422 -218.692222)
					(end 108.677202 -218.692222)
				)
			)
		)
	)
	(zone
		(layers "B.Cu" "In6.Cu" "In11.Cu" "In13.Cu" "In15.Cu")
		(hatch none 0.5)
		(connect_pads
			(clearance 0)
		)
		(min_thickness 0.25)
		(keepout
			(tracks not_allowed)
			(vias allowed)
			(pads allowed)
			(copperpour not_allowed)
			(footprints allowed)
		)
		(placement
			(enabled no)
			(sheetname "")
		)
		(fill yes
			(thermal_gap 0.5)
			(thermal_bridge_width 0.5)
			(island_removal_mode 0)
		)
		(polygon
			(pts
				(arc
					(start 352.498406 -288.103056)
					(mid 351.845626 -288.103056)
					(end 352.498406 -288.103056)
				)
			)
		)
	)
	(zone
		(layers "B.Cu" "In6.Cu" "In11.Cu" "In13.Cu" "In15.Cu")
		(hatch none 0.5)
		(connect_pads
			(clearance 0)
		)
		(min_thickness 0.25)
		(keepout
			(tracks not_allowed)
			(vias allowed)
			(pads allowed)
			(copperpour not_allowed)
			(footprints allowed)
		)
		(placement
			(enabled no)
			(sheetname "")
		)
		(fill yes
			(thermal_gap 0.5)
			(thermal_bridge_width 0.5)
			(island_removal_mode 0)
		)
		(polygon
			(pts
				(arc
					(start 378.702824 -237.411514)
					(mid 378.050044 -237.411514)
					(end 378.702824 -237.411514)
				)
			)
		)
	)
	(zone
		(layers "B.Cu" "In6.Cu" "In11.Cu" "In13.Cu" "In15.Cu")
		(hatch none 0.5)
		(connect_pads
			(clearance 0)
		)
		(min_thickness 0.25)
		(keepout
			(tracks not_allowed)
			(vias allowed)
			(pads allowed)
			(copperpour not_allowed)
			(footprints allowed)
		)
		(placement
			(enabled no)
			(sheetname "")
		)
		(fill yes
			(thermal_gap 0.5)
			(thermal_bridge_width 0.5)
			(island_removal_mode 0)
		)
		(polygon
			(pts
				(arc
					(start 299.356272 -301.866808)
					(mid 298.703492 -301.866808)
					(end 299.356272 -301.866808)
				)
			)
		)
	)
	(zone
		(layers "B.Cu" "In6.Cu" "In11.Cu" "In13.Cu" "In15.Cu")
		(hatch none 0.5)
		(connect_pads
			(clearance 0)
		)
		(min_thickness 0.25)
		(keepout
			(tracks not_allowed)
			(vias allowed)
			(pads allowed)
			(copperpour not_allowed)
			(footprints allowed)
		)
		(placement
			(enabled no)
			(sheetname "")
		)
		(fill yes
			(thermal_gap 0.5)
			(thermal_bridge_width 0.5)
			(island_removal_mode 0)
		)
		(polygon
			(pts
				(arc
					(start 339.811106 -288.917126)
					(mid 339.158326 -288.917126)
					(end 339.811106 -288.917126)
				)
			)
		)
	)
	(zone
		(layers "B.Cu" "In6.Cu" "In11.Cu" "In13.Cu" "In15.Cu")
		(hatch none 0.5)
		(connect_pads
			(clearance 0)
		)
		(min_thickness 0.25)
		(keepout
			(tracks not_allowed)
			(vias allowed)
			(pads allowed)
			(copperpour not_allowed)
			(footprints allowed)
		)
		(placement
			(enabled no)
			(sheetname "")
		)
		(fill yes
			(thermal_gap 0.5)
			(thermal_bridge_width 0.5)
			(island_removal_mode 0)
		)
		(polygon
			(pts
				(arc
					(start 351.558352 -289.807142)
					(mid 350.905572 -289.807142)
					(end 351.558352 -289.807142)
				)
			)
		)
	)
	(zone
		(layers "B.Cu" "In6.Cu" "In11.Cu" "In13.Cu" "In15.Cu")
		(hatch none 0.5)
		(connect_pads
			(clearance 0)
		)
		(min_thickness 0.25)
		(keepout
			(tracks not_allowed)
			(vias allowed)
			(pads allowed)
			(copperpour not_allowed)
			(footprints allowed)
		)
		(placement
			(enabled no)
			(sheetname "")
		)
		(fill yes
			(thermal_gap 0.5)
			(thermal_bridge_width 0.5)
			(island_removal_mode 0)
		)
		(polygon
			(pts
				(arc
					(start 361.786424 -217.878406)
					(mid 361.133644 -217.878406)
					(end 361.786424 -217.878406)
				)
			)
		)
	)
	(zone
		(layers "B.Cu" "In6.Cu" "In11.Cu" "In13.Cu" "In15.Cu")
		(hatch none 0.5)
		(connect_pads
			(clearance 0)
		)
		(min_thickness 0.25)
		(keepout
			(tracks not_allowed)
			(vias allowed)
			(pads allowed)
			(copperpour not_allowed)
			(footprints allowed)
		)
		(placement
			(enabled no)
			(sheetname "")
		)
		(fill yes
			(thermal_gap 0.5)
			(thermal_bridge_width 0.5)
			(island_removal_mode 0)
		)
		(polygon
			(pts
				(arc
					(start 378.23267 -226.831144)
					(mid 377.57989 -226.831144)
					(end 378.23267 -226.831144)
				)
			)
		)
	)
	(zone
		(layers "B.Cu" "In6.Cu" "In11.Cu" "In13.Cu" "In15.Cu")
		(hatch none 0.5)
		(connect_pads
			(clearance 0)
		)
		(min_thickness 0.25)
		(keepout
			(tracks not_allowed)
			(vias allowed)
			(pads allowed)
			(copperpour not_allowed)
			(footprints allowed)
		)
		(placement
			(enabled no)
			(sheetname "")
		)
		(fill yes
			(thermal_gap 0.5)
			(thermal_bridge_width 0.5)
			(island_removal_mode 0)
		)
		(polygon
			(pts
				(arc
					(start 374.943624 -248.806208)
					(mid 374.290844 -248.806208)
					(end 374.943624 -248.806208)
				)
			)
		)
	)
	(zone
		(layers "B.Cu" "In6.Cu" "In11.Cu" "In13.Cu" "In15.Cu")
		(hatch none 0.5)
		(connect_pads
			(clearance 0)
		)
		(min_thickness 0.25)
		(keepout
			(tracks not_allowed)
			(vias allowed)
			(pads allowed)
			(copperpour not_allowed)
			(footprints allowed)
		)
		(placement
			(enabled no)
			(sheetname "")
		)
		(fill yes
			(thermal_gap 0.5)
			(thermal_bridge_width 0.5)
			(island_removal_mode 0)
		)
		(polygon
			(pts
				(arc
					(start 115.725956 -217.878406)
					(mid 115.073176 -217.878406)
					(end 115.725956 -217.878406)
				)
			)
		)
	)
	(zone
		(layers "B.Cu" "In6.Cu" "In11.Cu" "In13.Cu" "In15.Cu")
		(hatch none 0.5)
		(connect_pads
			(clearance 0)
		)
		(min_thickness 0.25)
		(keepout
			(tracks not_allowed)
			(vias allowed)
			(pads allowed)
			(copperpour not_allowed)
			(footprints allowed)
		)
		(placement
			(enabled no)
			(sheetname "")
		)
		(fill yes
			(thermal_gap 0.5)
			(thermal_bridge_width 0.5)
			(island_removal_mode 0)
		)
		(polygon
			(pts
				(arc
					(start 188.209936 -250.866656)
					(mid 187.557156 -250.866656)
					(end 188.209936 -250.866656)
				)
			)
		)
	)
	(zone
		(layers "B.Cu" "In6.Cu" "In11.Cu" "In13.Cu" "In15.Cu")
		(hatch none 0.5)
		(connect_pads
			(clearance 0)
		)
		(min_thickness 0.25)
		(keepout
			(tracks not_allowed)
			(vias allowed)
			(pads allowed)
			(copperpour not_allowed)
			(footprints allowed)
		)
		(placement
			(enabled no)
			(sheetname "")
		)
		(fill yes
			(thermal_gap 0.5)
			(thermal_bridge_width 0.5)
			(island_removal_mode 0)
		)
		(polygon
			(pts
				(arc
					(start 379.752606 -270.19758)
					(mid 379.099826 -270.19758)
					(end 379.752606 -270.19758)
				)
			)
		)
	)
	(zone
		(layers "B.Cu" "In6.Cu" "In11.Cu" "In13.Cu" "In15.Cu")
		(hatch none 0.5)
		(connect_pads
			(clearance 0)
		)
		(min_thickness 0.25)
		(keepout
			(tracks not_allowed)
			(vias allowed)
			(pads allowed)
			(copperpour not_allowed)
			(footprints allowed)
		)
		(placement
			(enabled no)
			(sheetname "")
		)
		(fill yes
			(thermal_gap 0.5)
			(thermal_bridge_width 0.5)
			(island_removal_mode 0)
		)
		(polygon
			(pts
				(arc
					(start 341.58047 -239.853216)
					(mid 340.92769 -239.853216)
					(end 341.58047 -239.853216)
				)
			)
		)
	)
	(zone
		(layers "B.Cu" "In6.Cu" "In11.Cu" "In13.Cu" "In15.Cu")
		(hatch none 0.5)
		(connect_pads
			(clearance 0)
		)
		(min_thickness 0.25)
		(keepout
			(tracks not_allowed)
			(vias allowed)
			(pads allowed)
			(copperpour not_allowed)
			(footprints allowed)
		)
		(placement
			(enabled no)
			(sheetname "")
		)
		(fill yes
			(thermal_gap 0.5)
			(thermal_bridge_width 0.5)
			(island_removal_mode 0)
		)
		(polygon
			(pts
				(arc
					(start 94.110556 -235.783882)
					(mid 93.457776 -235.783882)
					(end 94.110556 -235.783882)
				)
			)
		)
	)
	(zone
		(layers "B.Cu" "In6.Cu" "In11.Cu" "In13.Cu" "In15.Cu")
		(hatch none 0.5)
		(connect_pads
			(clearance 0)
		)
		(min_thickness 0.25)
		(keepout
			(tracks not_allowed)
			(vias allowed)
			(pads allowed)
			(copperpour not_allowed)
			(footprints allowed)
		)
		(placement
			(enabled no)
			(sheetname "")
		)
		(fill yes
			(thermal_gap 0.5)
			(thermal_bridge_width 0.5)
			(island_removal_mode 0)
		)
		(polygon
			(pts
				(arc
					(start 92.230956 -235.783882)
					(mid 91.578176 -235.783882)
					(end 92.230956 -235.783882)
				)
			)
		)
	)
	(zone
		(layers "B.Cu" "In6.Cu" "In11.Cu" "In13.Cu" "In15.Cu")
		(hatch none 0.5)
		(connect_pads
			(clearance 0)
		)
		(min_thickness 0.25)
		(keepout
			(tracks not_allowed)
			(vias allowed)
			(pads allowed)
			(copperpour not_allowed)
			(footprints allowed)
		)
		(placement
			(enabled no)
			(sheetname "")
		)
		(fill yes
			(thermal_gap 0.5)
			(thermal_bridge_width 0.5)
			(island_removal_mode 0)
		)
		(polygon
			(pts
				(arc
					(start 337.351624 -217.878406)
					(mid 336.698844 -217.878406)
					(end 337.351624 -217.878406)
				)
			)
		)
	)
	(zone
		(layers "B.Cu" "In6.Cu" "In11.Cu" "In13.Cu" "In15.Cu")
		(hatch none 0.5)
		(connect_pads
			(clearance 0)
		)
		(min_thickness 0.25)
		(keepout
			(tracks not_allowed)
			(vias allowed)
			(pads allowed)
			(copperpour not_allowed)
			(footprints allowed)
		)
		(placement
			(enabled no)
			(sheetname "")
		)
		(fill yes
			(thermal_gap 0.5)
			(thermal_bridge_width 0.5)
			(island_removal_mode 0)
		)
		(polygon
			(pts
				(arc
					(start 97.509838 -288.917126)
					(mid 96.857058 -288.917126)
					(end 97.509838 -288.917126)
				)
			)
		)
	)
	(zone
		(layers "B.Cu" "In6.Cu" "In11.Cu" "In13.Cu" "In15.Cu")
		(hatch none 0.5)
		(connect_pads
			(clearance 0)
		)
		(min_thickness 0.25)
		(keepout
			(tracks not_allowed)
			(vias allowed)
			(pads allowed)
			(copperpour not_allowed)
			(footprints allowed)
		)
		(placement
			(enabled no)
			(sheetname "")
		)
		(fill yes
			(thermal_gap 0.5)
			(thermal_bridge_width 0.5)
			(island_removal_mode 0)
		)
		(polygon
			(pts
				(arc
					(start 372.704106 -288.917126)
					(mid 372.051326 -288.917126)
					(end 372.704106 -288.917126)
				)
			)
		)
	)
	(zone
		(layers "B.Cu" "In6.Cu" "In11.Cu" "In13.Cu" "In15.Cu")
		(hatch none 0.5)
		(connect_pads
			(clearance 0)
		)
		(min_thickness 0.25)
		(keepout
			(tracks not_allowed)
			(vias allowed)
			(pads allowed)
			(copperpour not_allowed)
			(footprints allowed)
		)
		(placement
			(enabled no)
			(sheetname "")
		)
		(fill yes
			(thermal_gap 0.5)
			(thermal_bridge_width 0.5)
			(island_removal_mode 0)
		)
		(polygon
			(pts
				(arc
					(start 131.702556 -230.900478)
					(mid 131.049776 -230.900478)
					(end 131.702556 -230.900478)
				)
			)
		)
	)
	(zone
		(layers "B.Cu" "In6.Cu" "In11.Cu" "In13.Cu" "In15.Cu")
		(hatch none 0.5)
		(connect_pads
			(clearance 0)
		)
		(min_thickness 0.25)
		(keepout
			(tracks not_allowed)
			(vias allowed)
			(pads allowed)
			(copperpour not_allowed)
			(footprints allowed)
		)
		(placement
			(enabled no)
			(sheetname "")
		)
		(fill yes
			(thermal_gap 0.5)
			(thermal_bridge_width 0.5)
			(island_removal_mode 0)
		)
		(polygon
			(pts
				(arc
					(start 32.203136 -314.616592)
					(mid 31.550356 -314.616592)
					(end 32.203136 -314.616592)
				)
			)
		)
	)
	(zone
		(layers "B.Cu" "In6.Cu" "In11.Cu" "In13.Cu" "In15.Cu")
		(hatch none 0.5)
		(connect_pads
			(clearance 0)
		)
		(min_thickness 0.25)
		(keepout
			(tracks not_allowed)
			(vias allowed)
			(pads allowed)
			(copperpour not_allowed)
			(footprints allowed)
		)
		(placement
			(enabled no)
			(sheetname "")
		)
		(fill yes
			(thermal_gap 0.5)
			(thermal_bridge_width 0.5)
			(island_removal_mode 0)
		)
		(polygon
			(pts
				(arc
					(start 376.463052 -256.361438)
					(mid 375.810272 -256.361438)
					(end 376.463052 -256.361438)
				)
			)
		)
	)
	(zone
		(layers "B.Cu" "In6.Cu" "In11.Cu" "In13.Cu" "In15.Cu")
		(hatch none 0.5)
		(connect_pads
			(clearance 0)
		)
		(min_thickness 0.25)
		(keepout
			(tracks not_allowed)
			(vias allowed)
			(pads allowed)
			(copperpour not_allowed)
			(footprints allowed)
		)
		(placement
			(enabled no)
			(sheetname "")
		)
		(fill yes
			(thermal_gap 0.5)
			(thermal_bridge_width 0.5)
			(island_removal_mode 0)
		)
		(polygon
			(pts
				(arc
					(start 425.162472 -304.416714)
					(mid 424.509692 -304.416714)
					(end 425.162472 -304.416714)
				)
			)
		)
	)
	(zone
		(layers "B.Cu" "In6.Cu" "In11.Cu" "In13.Cu" "In15.Cu")
		(hatch none 0.5)
		(connect_pads
			(clearance 0)
		)
		(min_thickness 0.25)
		(keepout
			(tracks not_allowed)
			(vias allowed)
			(pads allowed)
			(copperpour not_allowed)
			(footprints allowed)
		)
		(placement
			(enabled no)
			(sheetname "")
		)
		(fill yes
			(thermal_gap 0.5)
			(thermal_bridge_width 0.5)
			(island_removal_mode 0)
		)
		(polygon
			(pts
				(arc
					(start 377.763024 -242.294918)
					(mid 377.110244 -242.294918)
					(end 377.763024 -242.294918)
				)
			)
		)
	)
	(zone
		(layers "B.Cu" "In6.Cu" "In11.Cu" "In13.Cu" "In15.Cu")
		(hatch none 0.5)
		(connect_pads
			(clearance 0)
		)
		(min_thickness 0.25)
		(keepout
			(tracks not_allowed)
			(vias allowed)
			(pads allowed)
			(copperpour not_allowed)
			(footprints allowed)
		)
		(placement
			(enabled no)
			(sheetname "")
		)
		(fill yes
			(thermal_gap 0.5)
			(thermal_bridge_width 0.5)
			(island_removal_mode 0)
		)
		(polygon
			(pts
				(arc
					(start 123.244356 -217.878406)
					(mid 122.591576 -217.878406)
					(end 123.244356 -217.878406)
				)
			)
		)
	)
	(zone
		(layers "B.Cu" "In6.Cu" "In11.Cu" "In13.Cu" "In15.Cu")
		(hatch none 0.5)
		(connect_pads
			(clearance 0)
		)
		(min_thickness 0.25)
		(keepout
			(tracks not_allowed)
			(vias allowed)
			(pads allowed)
			(copperpour not_allowed)
			(footprints allowed)
		)
		(placement
			(enabled no)
			(sheetname "")
		)
		(fill yes
			(thermal_gap 0.5)
			(thermal_bridge_width 0.5)
			(island_removal_mode 0)
		)
		(polygon
			(pts
				(arc
					(start 377.873006 -270.19758)
					(mid 377.220226 -270.19758)
					(end 377.873006 -270.19758)
				)
			)
		)
	)
	(zone
		(layers "B.Cu" "In6.Cu" "In11.Cu" "In13.Cu" "In15.Cu")
		(hatch none 0.5)
		(connect_pads
			(clearance 0)
		)
		(min_thickness 0.25)
		(keepout
			(tracks not_allowed)
			(vias allowed)
			(pads allowed)
			(copperpour not_allowed)
			(footprints allowed)
		)
		(placement
			(enabled no)
			(sheetname "")
		)
		(fill yes
			(thermal_gap 0.5)
			(thermal_bridge_width 0.5)
			(island_removal_mode 0)
		)
		(polygon
			(pts
				(arc
					(start 104.918002 -218.692222)
					(mid 104.265222 -218.692222)
					(end 104.918002 -218.692222)
				)
			)
		)
	)
	(zone
		(layers "B.Cu" "In6.Cu" "In11.Cu" "In13.Cu" "In15.Cu")
		(hatch none 0.5)
		(connect_pads
			(clearance 0)
		)
		(min_thickness 0.25)
		(keepout
			(tracks not_allowed)
			(vias allowed)
			(pads allowed)
			(copperpour not_allowed)
			(footprints allowed)
		)
		(placement
			(enabled no)
			(sheetname "")
		)
		(fill yes
			(thermal_gap 0.5)
			(thermal_bridge_width 0.5)
			(island_removal_mode 0)
		)
		(polygon
			(pts
				(arc
					(start 36.303204 -267.016738)
					(mid 35.650424 -267.016738)
					(end 36.303204 -267.016738)
				)
			)
		)
	)
	(zone
		(layers "B.Cu" "In6.Cu" "In11.Cu" "In13.Cu" "In15.Cu")
		(hatch none 0.5)
		(connect_pads
			(clearance 0)
		)
		(min_thickness 0.25)
		(keepout
			(tracks not_allowed)
			(vias allowed)
			(pads allowed)
			(copperpour not_allowed)
			(footprints allowed)
		)
		(placement
			(enabled no)
			(sheetname "")
		)
		(fill yes
			(thermal_gap 0.5)
			(thermal_bridge_width 0.5)
			(island_removal_mode 0)
		)
		(polygon
			(pts
				(arc
					(start 93.750384 -264.50036)
					(mid 93.097604 -264.50036)
					(end 93.750384 -264.50036)
				)
			)
		)
	)
	(zone
		(layers "B.Cu" "In6.Cu" "In11.Cu" "In13.Cu" "In15.Cu")
		(hatch none 0.5)
		(connect_pads
			(clearance 0)
		)
		(min_thickness 0.25)
		(keepout
			(tracks not_allowed)
			(vias allowed)
			(pads allowed)
			(copperpour not_allowed)
			(footprints allowed)
		)
		(placement
			(enabled no)
			(sheetname "")
		)
		(fill yes
			(thermal_gap 0.5)
			(thermal_bridge_width 0.5)
			(island_removal_mode 0)
		)
		(polygon
			(pts
				(arc
					(start 36.303204 -290.816792)
					(mid 35.650424 -290.816792)
					(end 36.303204 -290.816792)
				)
			)
		)
	)
	(zone
		(layers "B.Cu" "In6.Cu" "In11.Cu" "In13.Cu" "In15.Cu")
		(hatch none 0.5)
		(connect_pads
			(clearance 0)
		)
		(min_thickness 0.25)
		(keepout
			(tracks not_allowed)
			(vias allowed)
			(pads allowed)
			(copperpour not_allowed)
			(footprints allowed)
		)
		(placement
			(enabled no)
			(sheetname "")
		)
		(fill yes
			(thermal_gap 0.5)
			(thermal_bridge_width 0.5)
			(island_removal_mode 0)
		)
		(polygon
			(pts
				(arc
					(start 436.150004 -261.066788)
					(mid 435.497224 -261.066788)
					(end 436.150004 -261.066788)
				)
			)
		)
	)
	(zone
		(layers "B.Cu" "In6.Cu" "In11.Cu" "In13.Cu" "In15.Cu")
		(hatch none 0.5)
		(connect_pads
			(clearance 0)
		)
		(min_thickness 0.25)
		(keepout
			(tracks not_allowed)
			(vias allowed)
			(pads allowed)
			(copperpour not_allowed)
			(footprints allowed)
		)
		(placement
			(enabled no)
			(sheetname "")
		)
		(fill yes
			(thermal_gap 0.5)
			(thermal_bridge_width 0.5)
			(island_removal_mode 0)
		)
		(polygon
			(pts
				(arc
					(start 295.230804 -227.91674)
					(mid 294.578024 -227.91674)
					(end 295.230804 -227.91674)
				)
			)
		)
	)
	(zone
		(layers "B.Cu" "In6.Cu" "In11.Cu" "In13.Cu" "In15.Cu")
		(hatch none 0.5)
		(connect_pads
			(clearance 0)
		)
		(min_thickness 0.25)
		(keepout
			(tracks not_allowed)
			(vias allowed)
			(pads allowed)
			(copperpour not_allowed)
			(footprints allowed)
		)
		(placement
			(enabled no)
			(sheetname "")
		)
		(fill yes
			(thermal_gap 0.5)
			(thermal_bridge_width 0.5)
			(island_removal_mode 0)
		)
		(polygon
			(pts
				(arc
					(start 436.150004 -239.81664)
					(mid 435.497224 -239.81664)
					(end 436.150004 -239.81664)
				)
			)
		)
	)
	(zone
		(layers "B.Cu" "In6.Cu" "In11.Cu" "In13.Cu" "In15.Cu")
		(hatch none 0.5)
		(connect_pads
			(clearance 0)
		)
		(min_thickness 0.25)
		(keepout
			(tracks not_allowed)
			(vias allowed)
			(pads allowed)
			(copperpour not_allowed)
			(footprints allowed)
		)
		(placement
			(enabled no)
			(sheetname "")
		)
		(fill yes
			(thermal_gap 0.5)
			(thermal_bridge_width 0.5)
			(island_removal_mode 0)
		)
		(polygon
			(pts
				(arc
					(start 352.85807 -218.692222)
					(mid 352.20529 -218.692222)
					(end 352.85807 -218.692222)
				)
			)
		)
	)
	(zone
		(layers "B.Cu" "In6.Cu" "In11.Cu" "In13.Cu" "In15.Cu")
		(hatch none 0.5)
		(connect_pads
			(clearance 0)
		)
		(min_thickness 0.25)
		(keepout
			(tracks not_allowed)
			(vias allowed)
			(pads allowed)
			(copperpour not_allowed)
			(footprints allowed)
		)
		(placement
			(enabled no)
			(sheetname "")
		)
		(fill yes
			(thermal_gap 0.5)
			(thermal_bridge_width 0.5)
			(island_removal_mode 0)
		)
		(polygon
			(pts
				(arc
					(start 123.714002 -218.692222)
					(mid 123.061222 -218.692222)
					(end 123.714002 -218.692222)
				)
			)
		)
	)
	(zone
		(layers "B.Cu" "In6.Cu" "In11.Cu" "In13.Cu" "In15.Cu")
		(hatch none 0.5)
		(connect_pads
			(clearance 0)
		)
		(min_thickness 0.25)
		(keepout
			(tracks not_allowed)
			(vias allowed)
			(pads allowed)
			(copperpour not_allowed)
			(footprints allowed)
		)
		(placement
			(enabled no)
			(sheetname "")
		)
		(fill yes
			(thermal_gap 0.5)
			(thermal_bridge_width 0.5)
			(island_removal_mode 0)
		)
		(polygon
			(pts
				(arc
					(start 340.750652 -262.872474)
					(mid 340.097872 -262.872474)
					(end 340.750652 -262.872474)
				)
			)
		)
	)
	(zone
		(layers "B.Cu" "In6.Cu" "In11.Cu" "In13.Cu" "In15.Cu")
		(hatch none 0.5)
		(connect_pads
			(clearance 0)
		)
		(min_thickness 0.25)
		(keepout
			(tracks not_allowed)
			(vias allowed)
			(pads allowed)
			(copperpour not_allowed)
			(footprints allowed)
		)
		(placement
			(enabled no)
			(sheetname "")
		)
		(fill yes
			(thermal_gap 0.5)
			(thermal_bridge_width 0.5)
			(island_removal_mode 0)
		)
		(polygon
			(pts
				(arc
					(start 361.31627 -217.064336)
					(mid 360.66349 -217.064336)
					(end 361.31627 -217.064336)
				)
			)
		)
	)
	(zone
		(layers "B.Cu" "In6.Cu" "In11.Cu" "In13.Cu" "In15.Cu")
		(hatch none 0.5)
		(connect_pads
			(clearance 0)
		)
		(min_thickness 0.25)
		(keepout
			(tracks not_allowed)
			(vias allowed)
			(pads allowed)
			(copperpour not_allowed)
			(footprints allowed)
		)
		(placement
			(enabled no)
			(sheetname "")
		)
		(fill yes
			(thermal_gap 0.5)
			(thermal_bridge_width 0.5)
			(island_removal_mode 0)
		)
		(polygon
			(pts
				(arc
					(start 299.356272 -279.766776)
					(mid 298.703492 -279.766776)
					(end 299.356272 -279.766776)
				)
			)
		)
	)
	(zone
		(layers "B.Cu" "In6.Cu" "In11.Cu" "In13.Cu" "In15.Cu")
		(hatch none 0.5)
		(connect_pads
			(clearance 0)
		)
		(min_thickness 0.25)
		(keepout
			(tracks not_allowed)
			(vias allowed)
			(pads allowed)
			(copperpour not_allowed)
			(footprints allowed)
		)
		(placement
			(enabled no)
			(sheetname "")
		)
		(fill yes
			(thermal_gap 0.5)
			(thermal_bridge_width 0.5)
			(island_removal_mode 0)
		)
		(polygon
			(pts
				(arc
					(start 103.038402 -218.692222)
					(mid 102.385622 -218.692222)
					(end 103.038402 -218.692222)
				)
			)
		)
	)
	(zone
		(layers "B.Cu" "In6.Cu" "In11.Cu" "In13.Cu" "In15.Cu")
		(hatch none 0.5)
		(connect_pads
			(clearance 0)
		)
		(min_thickness 0.25)
		(keepout
			(tracks not_allowed)
			(vias allowed)
			(pads allowed)
			(copperpour not_allowed)
			(footprints allowed)
		)
		(placement
			(enabled no)
			(sheetname "")
		)
		(fill yes
			(thermal_gap 0.5)
			(thermal_bridge_width 0.5)
			(island_removal_mode 0)
		)
		(polygon
			(pts
				(arc
					(start 136.041638 -288.917126)
					(mid 135.388858 -288.917126)
					(end 136.041638 -288.917126)
				)
			)
		)
	)
	(zone
		(layers "B.Cu" "In6.Cu" "In11.Cu" "In13.Cu" "In15.Cu")
		(hatch none 0.5)
		(connect_pads
			(clearance 0)
		)
		(min_thickness 0.25)
		(keepout
			(tracks not_allowed)
			(vias allowed)
			(pads allowed)
			(copperpour not_allowed)
			(footprints allowed)
		)
		(placement
			(enabled no)
			(sheetname "")
		)
		(fill yes
			(thermal_gap 0.5)
			(thermal_bridge_width 0.5)
			(island_removal_mode 0)
		)
		(polygon
			(pts
				(arc
					(start 51.416204 -283.16682)
					(mid 50.763424 -283.16682)
					(end 51.416204 -283.16682)
				)
			)
		)
	)
	(zone
		(layers "B.Cu" "In6.Cu" "In11.Cu" "In13.Cu" "In15.Cu")
		(hatch none 0.5)
		(connect_pads
			(clearance 0)
		)
		(min_thickness 0.25)
		(keepout
			(tracks not_allowed)
			(vias allowed)
			(pads allowed)
			(copperpour not_allowed)
			(footprints allowed)
		)
		(placement
			(enabled no)
			(sheetname "")
		)
		(fill yes
			(thermal_gap 0.5)
			(thermal_bridge_width 0.5)
			(island_removal_mode 0)
		)
		(polygon
			(pts
				(arc
					(start 436.150004 -267.866622)
					(mid 435.497224 -267.866622)
					(end 436.150004 -267.866622)
				)
			)
		)
	)
	(zone
		(layers "B.Cu" "In6.Cu" "In11.Cu" "In13.Cu" "In15.Cu")
		(hatch none 0.5)
		(connect_pads
			(clearance 0)
		)
		(min_thickness 0.25)
		(keepout
			(tracks not_allowed)
			(vias allowed)
			(pads allowed)
			(copperpour not_allowed)
			(footprints allowed)
		)
		(placement
			(enabled no)
			(sheetname "")
		)
		(fill yes
			(thermal_gap 0.5)
			(thermal_bridge_width 0.5)
			(island_removal_mode 0)
		)
		(polygon
			(pts
				(arc
					(start 188.209936 -294.216582)
					(mid 187.557156 -294.216582)
					(end 188.209936 -294.216582)
				)
			)
		)
	)
	(zone
		(layers "B.Cu" "In6.Cu" "In11.Cu" "In13.Cu" "In15.Cu")
		(hatch none 0.5)
		(connect_pads
			(clearance 0)
		)
		(min_thickness 0.25)
		(keepout
			(tracks not_allowed)
			(vias allowed)
			(pads allowed)
			(copperpour not_allowed)
			(footprints allowed)
		)
		(placement
			(enabled no)
			(sheetname "")
		)
		(fill yes
			(thermal_gap 0.5)
			(thermal_bridge_width 0.5)
			(island_removal_mode 0)
		)
		(polygon
			(pts
				(arc
					(start 51.390804 -201.56678)
					(mid 50.738024 -201.56678)
					(end 51.390804 -201.56678)
				)
			)
		)
	)
	(zone
		(layers "B.Cu" "In6.Cu" "In11.Cu" "In13.Cu" "In15.Cu")
		(hatch none 0.5)
		(connect_pads
			(clearance 0)
		)
		(min_thickness 0.25)
		(keepout
			(tracks not_allowed)
			(vias allowed)
			(pads allowed)
			(copperpour not_allowed)
			(footprints allowed)
		)
		(placement
			(enabled no)
			(sheetname "")
		)
		(fill yes
			(thermal_gap 0.5)
			(thermal_bridge_width 0.5)
			(island_removal_mode 0)
		)
		(polygon
			(pts
				(arc
					(start 345.449906 -288.917126)
					(mid 344.797126 -288.917126)
					(end 345.449906 -288.917126)
				)
			)
		)
	)
	(zone
		(layers "B.Cu" "In6.Cu" "In11.Cu" "In13.Cu" "In15.Cu")
		(hatch none 0.5)
		(connect_pads
			(clearance 0)
		)
		(min_thickness 0.25)
		(keepout
			(tracks not_allowed)
			(vias allowed)
			(pads allowed)
			(copperpour not_allowed)
			(footprints allowed)
		)
		(placement
			(enabled no)
			(sheetname "")
		)
		(fill yes
			(thermal_gap 0.5)
			(thermal_bridge_width 0.5)
			(island_removal_mode 0)
		)
		(polygon
			(pts
				(arc
					(start 177.222404 -223.666558)
					(mid 176.569624 -223.666558)
					(end 177.222404 -223.666558)
				)
			)
		)
	)
	(zone
		(layers "B.Cu" "In6.Cu" "In11.Cu" "In13.Cu" "In15.Cu")
		(hatch none 0.5)
		(connect_pads
			(clearance 0)
		)
		(min_thickness 0.25)
		(keepout
			(tracks not_allowed)
			(vias allowed)
			(pads allowed)
			(copperpour not_allowed)
			(footprints allowed)
		)
		(placement
			(enabled no)
			(sheetname "")
		)
		(fill yes
			(thermal_gap 0.5)
			(thermal_bridge_width 0.5)
			(island_removal_mode 0)
		)
		(polygon
			(pts
				(arc
					(start 380.11227 -231.714548)
					(mid 379.45949 -231.714548)
					(end 380.11227 -231.714548)
				)
			)
		)
	)
	(zone
		(layers "B.Cu" "In6.Cu" "In11.Cu" "In13.Cu" "In15.Cu")
		(hatch none 0.5)
		(connect_pads
			(clearance 0)
		)
		(min_thickness 0.25)
		(keepout
			(tracks not_allowed)
			(vias allowed)
			(pads allowed)
			(copperpour not_allowed)
			(footprints allowed)
		)
		(placement
			(enabled no)
			(sheetname "")
		)
		(fill yes
			(thermal_gap 0.5)
			(thermal_bridge_width 0.5)
			(island_removal_mode 0)
		)
		(polygon
			(pts
				(arc
					(start 192.310004 -295.06672)
					(mid 191.657224 -295.06672)
					(end 192.310004 -295.06672)
				)
			)
		)
	)
	(zone
		(layers "B.Cu" "In6.Cu" "In11.Cu" "In13.Cu" "In15.Cu")
		(hatch none 0.5)
		(connect_pads
			(clearance 0)
		)
		(min_thickness 0.25)
		(keepout
			(tracks not_allowed)
			(vias allowed)
			(pads allowed)
			(copperpour not_allowed)
			(footprints allowed)
		)
		(placement
			(enabled no)
			(sheetname "")
		)
		(fill yes
			(thermal_gap 0.5)
			(thermal_bridge_width 0.5)
			(island_removal_mode 0)
		)
		(polygon
			(pts
				(arc
					(start 378.702824 -217.878406)
					(mid 378.050044 -217.878406)
					(end 378.702824 -217.878406)
				)
			)
		)
	)
	(zone
		(layers "B.Cu" "In6.Cu" "In11.Cu" "In13.Cu" "In15.Cu")
		(hatch none 0.5)
		(connect_pads
			(clearance 0)
		)
		(min_thickness 0.25)
		(keepout
			(tracks not_allowed)
			(vias allowed)
			(pads allowed)
			(copperpour not_allowed)
			(footprints allowed)
		)
		(placement
			(enabled no)
			(sheetname "")
		)
		(fill yes
			(thermal_gap 0.5)
			(thermal_bridge_width 0.5)
			(island_removal_mode 0)
		)
		(polygon
			(pts
				(arc
					(start 299.330872 -199.866758)
					(mid 298.678092 -199.866758)
					(end 299.330872 -199.866758)
				)
			)
		)
	)
	(zone
		(layers "B.Cu" "In6.Cu" "In11.Cu" "In13.Cu" "In15.Cu")
		(hatch none 0.5)
		(connect_pads
			(clearance 0)
		)
		(min_thickness 0.25)
		(keepout
			(tracks not_allowed)
			(vias allowed)
			(pads allowed)
			(copperpour not_allowed)
			(footprints allowed)
		)
		(placement
			(enabled no)
			(sheetname "")
		)
		(fill yes
			(thermal_gap 0.5)
			(thermal_bridge_width 0.5)
			(island_removal_mode 0)
		)
		(polygon
			(pts
				(arc
					(start 192.233804 -265.316716)
					(mid 191.581024 -265.316716)
					(end 192.233804 -265.316716)
				)
			)
		)
	)
	(zone
		(layers "B.Cu" "In6.Cu" "In11.Cu" "In13.Cu" "In15.Cu")
		(hatch none 0.5)
		(connect_pads
			(clearance 0)
		)
		(min_thickness 0.25)
		(keepout
			(tracks not_allowed)
			(vias allowed)
			(pads allowed)
			(copperpour not_allowed)
			(footprints allowed)
		)
		(placement
			(enabled no)
			(sheetname "")
		)
		(fill yes
			(thermal_gap 0.5)
			(thermal_bridge_width 0.5)
			(island_removal_mode 0)
		)
		(polygon
			(pts
				(arc
					(start 92.340938 -273.453098)
					(mid 91.688158 -273.453098)
					(end 92.340938 -273.453098)
				)
			)
		)
	)
	(zone
		(layers "B.Cu" "In6.Cu" "In11.Cu" "In13.Cu" "In15.Cu")
		(hatch none 0.5)
		(connect_pads
			(clearance 0)
		)
		(min_thickness 0.25)
		(keepout
			(tracks not_allowed)
			(vias allowed)
			(pads allowed)
			(copperpour not_allowed)
			(footprints allowed)
		)
		(placement
			(enabled no)
			(sheetname "")
		)
		(fill yes
			(thermal_gap 0.5)
			(thermal_bridge_width 0.5)
			(island_removal_mode 0)
		)
		(polygon
			(pts
				(arc
					(start 335.941924 -225.203258)
					(mid 335.289144 -225.203258)
					(end 335.941924 -225.203258)
				)
			)
		)
	)
	(zone
		(layers "B.Cu" "In6.Cu" "In11.Cu" "In13.Cu" "In15.Cu")
		(hatch none 0.5)
		(connect_pads
			(clearance 0)
		)
		(min_thickness 0.25)
		(keepout
			(tracks not_allowed)
			(vias allowed)
			(pads allowed)
			(copperpour not_allowed)
			(footprints allowed)
		)
		(placement
			(enabled no)
			(sheetname "")
		)
		(fill yes
			(thermal_gap 0.5)
			(thermal_bridge_width 0.5)
			(island_removal_mode 0)
		)
		(polygon
			(pts
				(arc
					(start 280.143204 -308.666642)
					(mid 279.490424 -308.666642)
					(end 280.143204 -308.666642)
				)
			)
		)
	)
	(zone
		(layers "B.Cu" "In6.Cu" "In11.Cu" "In13.Cu" "In15.Cu")
		(hatch none 0.5)
		(connect_pads
			(clearance 0)
		)
		(min_thickness 0.25)
		(keepout
			(tracks not_allowed)
			(vias allowed)
			(pads allowed)
			(copperpour not_allowed)
			(footprints allowed)
		)
		(placement
			(enabled no)
			(sheetname "")
		)
		(fill yes
			(thermal_gap 0.5)
			(thermal_bridge_width 0.5)
			(island_removal_mode 0)
		)
		(polygon
			(pts
				(arc
					(start 131.812538 -266.941808)
					(mid 131.159758 -266.941808)
					(end 131.812538 -266.941808)
				)
			)
		)
	)
	(zone
		(layers "B.Cu" "In6.Cu" "In11.Cu" "In13.Cu" "In15.Cu")
		(hatch none 0.5)
		(connect_pads
			(clearance 0)
		)
		(min_thickness 0.25)
		(keepout
			(tracks not_allowed)
			(vias allowed)
			(pads allowed)
			(copperpour not_allowed)
			(footprints allowed)
		)
		(placement
			(enabled no)
			(sheetname "")
		)
		(fill yes
			(thermal_gap 0.5)
			(thermal_bridge_width 0.5)
			(island_removal_mode 0)
		)
		(polygon
			(pts
				(arc
					(start 32.203136 -310.366664)
					(mid 31.550356 -310.366664)
					(end 32.203136 -310.366664)
				)
			)
		)
	)
	(zone
		(layers "B.Cu" "In6.Cu" "In11.Cu" "In13.Cu" "In15.Cu")
		(hatch none 0.5)
		(connect_pads
			(clearance 0)
		)
		(min_thickness 0.25)
		(keepout
			(tracks not_allowed)
			(vias allowed)
			(pads allowed)
			(copperpour not_allowed)
			(footprints allowed)
		)
		(placement
			(enabled no)
			(sheetname "")
		)
		(fill yes
			(thermal_gap 0.5)
			(thermal_bridge_width 0.5)
			(island_removal_mode 0)
		)
		(polygon
			(pts
				(arc
					(start 341.690452 -271.011396)
					(mid 341.037672 -271.011396)
					(end 341.690452 -271.011396)
				)
			)
		)
	)
	(zone
		(layers "B.Cu" "In6.Cu" "In11.Cu" "In13.Cu" "In15.Cu")
		(hatch none 0.5)
		(connect_pads
			(clearance 0)
		)
		(min_thickness 0.25)
		(keepout
			(tracks not_allowed)
			(vias allowed)
			(pads allowed)
			(copperpour not_allowed)
			(footprints allowed)
		)
		(placement
			(enabled no)
			(sheetname "")
		)
		(fill yes
			(thermal_gap 0.5)
			(thermal_bridge_width 0.5)
			(island_removal_mode 0)
		)
		(polygon
			(pts
				(arc
					(start 295.230804 -224.516696)
					(mid 294.578024 -224.516696)
					(end 295.230804 -224.516696)
				)
			)
		)
	)
	(zone
		(layers "B.Cu" "In6.Cu" "In11.Cu" "In13.Cu" "In15.Cu")
		(hatch none 0.5)
		(connect_pads
			(clearance 0)
		)
		(min_thickness 0.25)
		(keepout
			(tracks not_allowed)
			(vias allowed)
			(pads allowed)
			(copperpour not_allowed)
			(footprints allowed)
		)
		(placement
			(enabled no)
			(sheetname "")
		)
		(fill yes
			(thermal_gap 0.5)
			(thermal_bridge_width 0.5)
			(island_removal_mode 0)
		)
		(polygon
			(pts
				(arc
					(start 280.143204 -310.366664)
					(mid 279.490424 -310.366664)
					(end 280.143204 -310.366664)
				)
			)
		)
	)
	(zone
		(layers "B.Cu" "In6.Cu" "In11.Cu" "In13.Cu" "In15.Cu")
		(hatch none 0.5)
		(connect_pads
			(clearance 0)
		)
		(min_thickness 0.25)
		(keepout
			(tracks not_allowed)
			(vias allowed)
			(pads allowed)
			(copperpour not_allowed)
			(footprints allowed)
		)
		(placement
			(enabled no)
			(sheetname "")
		)
		(fill yes
			(thermal_gap 0.5)
			(thermal_bridge_width 0.5)
			(island_removal_mode 0)
		)
		(polygon
			(pts
				(arc
					(start 95.630238 -288.917126)
					(mid 94.977458 -288.917126)
					(end 95.630238 -288.917126)
				)
			)
		)
	)
	(zone
		(layers "B.Cu" "In6.Cu" "In11.Cu" "In13.Cu" "In15.Cu")
		(hatch none 0.5)
		(connect_pads
			(clearance 0)
		)
		(min_thickness 0.25)
		(keepout
			(tracks not_allowed)
			(vias allowed)
			(pads allowed)
			(copperpour not_allowed)
			(footprints allowed)
		)
		(placement
			(enabled no)
			(sheetname "")
		)
		(fill yes
			(thermal_gap 0.5)
			(thermal_bridge_width 0.5)
			(island_removal_mode 0)
		)
		(polygon
			(pts
				(arc
					(start 371.184424 -217.878406)
					(mid 370.531644 -217.878406)
					(end 371.184424 -217.878406)
				)
			)
		)
	)
	(zone
		(layers "B.Cu" "In6.Cu" "In11.Cu" "In13.Cu" "In15.Cu")
		(hatch none 0.5)
		(connect_pads
			(clearance 0)
		)
		(min_thickness 0.25)
		(keepout
			(tracks not_allowed)
			(vias allowed)
			(pads allowed)
			(copperpour not_allowed)
			(footprints allowed)
		)
		(placement
			(enabled no)
			(sheetname "")
		)
		(fill yes
			(thermal_gap 0.5)
			(thermal_bridge_width 0.5)
			(island_removal_mode 0)
		)
		(polygon
			(pts
				(arc
					(start 341.110824 -217.878406)
					(mid 340.458044 -217.878406)
					(end 341.110824 -217.878406)
				)
			)
		)
	)
	(zone
		(layers "B.Cu" "In6.Cu" "In11.Cu" "In13.Cu" "In15.Cu")
		(hatch none 0.5)
		(connect_pads
			(clearance 0)
		)
		(min_thickness 0.25)
		(keepout
			(tracks not_allowed)
			(vias allowed)
			(pads allowed)
			(copperpour not_allowed)
			(footprints allowed)
		)
		(placement
			(enabled no)
			(sheetname "")
		)
		(fill yes
			(thermal_gap 0.5)
			(thermal_bridge_width 0.5)
			(island_removal_mode 0)
		)
		(polygon
			(pts
				(arc
					(start 299.356272 -304.416714)
					(mid 298.703492 -304.416714)
					(end 299.356272 -304.416714)
				)
			)
		)
	)
	(zone
		(layers "B.Cu" "In6.Cu" "In11.Cu" "In13.Cu" "In15.Cu")
		(hatch none 0.5)
		(connect_pads
			(clearance 0)
		)
		(min_thickness 0.25)
		(keepout
			(tracks not_allowed)
			(vias allowed)
			(pads allowed)
			(copperpour not_allowed)
			(footprints allowed)
		)
		(placement
			(enabled no)
			(sheetname "")
		)
		(fill yes
			(thermal_gap 0.5)
			(thermal_bridge_width 0.5)
			(island_removal_mode 0)
		)
		(polygon
			(pts
				(arc
					(start 32.203136 -238.116618)
					(mid 31.550356 -238.116618)
					(end 32.203136 -238.116618)
				)
			)
		)
	)
	(zone
		(layers "B.Cu" "In6.Cu" "In11.Cu" "In13.Cu" "In15.Cu")
		(hatch none 0.5)
		(connect_pads
			(clearance 0)
		)
		(min_thickness 0.25)
		(keepout
			(tracks not_allowed)
			(vias allowed)
			(pads allowed)
			(copperpour not_allowed)
			(footprints allowed)
		)
		(placement
			(enabled no)
			(sheetname "")
		)
		(fill yes
			(thermal_gap 0.5)
			(thermal_bridge_width 0.5)
			(island_removal_mode 0)
		)
		(polygon
			(pts
				(arc
					(start 107.737402 -217.064336)
					(mid 107.084622 -217.064336)
					(end 107.737402 -217.064336)
				)
			)
		)
	)
	(zone
		(layers "B.Cu" "In6.Cu" "In11.Cu" "In13.Cu" "In15.Cu")
		(hatch none 0.5)
		(connect_pads
			(clearance 0)
		)
		(min_thickness 0.25)
		(keepout
			(tracks not_allowed)
			(vias allowed)
			(pads allowed)
			(copperpour not_allowed)
			(footprints allowed)
		)
		(placement
			(enabled no)
			(sheetname "")
		)
		(fill yes
			(thermal_gap 0.5)
			(thermal_bridge_width 0.5)
			(island_removal_mode 0)
		)
		(polygon
			(pts
				(arc
					(start 440.250072 -251.716794)
					(mid 439.597292 -251.716794)
					(end 440.250072 -251.716794)
				)
			)
		)
	)
	(zone
		(layers "B.Cu" "In6.Cu" "In11.Cu" "In13.Cu" "In15.Cu")
		(hatch none 0.5)
		(connect_pads
			(clearance 0)
		)
		(min_thickness 0.25)
		(keepout
			(tracks not_allowed)
			(vias allowed)
			(pads allowed)
			(copperpour not_allowed)
			(footprints allowed)
		)
		(placement
			(enabled no)
			(sheetname "")
		)
		(fill yes
			(thermal_gap 0.5)
			(thermal_bridge_width 0.5)
			(island_removal_mode 0)
		)
		(polygon
			(pts
				(arc
					(start 192.310004 -307.816758)
					(mid 191.657224 -307.816758)
					(end 192.310004 -307.816758)
				)
			)
		)
	)
	(zone
		(layers "B.Cu" "In6.Cu" "In11.Cu" "In13.Cu" "In15.Cu")
		(hatch none 0.5)
		(connect_pads
			(clearance 0)
		)
		(min_thickness 0.25)
		(keepout
			(tracks not_allowed)
			(vias allowed)
			(pads allowed)
			(copperpour not_allowed)
			(footprints allowed)
		)
		(placement
			(enabled no)
			(sheetname "")
		)
		(fill yes
			(thermal_gap 0.5)
			(thermal_bridge_width 0.5)
			(island_removal_mode 0)
		)
		(polygon
			(pts
				(arc
					(start 32.203136 -294.216582)
					(mid 31.550356 -294.216582)
					(end 32.203136 -294.216582)
				)
			)
		)
	)
	(zone
		(layers "B.Cu" "In6.Cu" "In11.Cu" "In13.Cu" "In15.Cu")
		(hatch none 0.5)
		(connect_pads
			(clearance 0)
		)
		(min_thickness 0.25)
		(keepout
			(tracks not_allowed)
			(vias allowed)
			(pads allowed)
			(copperpour not_allowed)
			(footprints allowed)
		)
		(placement
			(enabled no)
			(sheetname "")
		)
		(fill yes
			(thermal_gap 0.5)
			(thermal_bridge_width 0.5)
			(island_removal_mode 0)
		)
		(polygon
			(pts
				(arc
					(start 173.122336 -199.866758)
					(mid 172.469556 -199.866758)
					(end 173.122336 -199.866758)
				)
			)
		)
	)
	(zone
		(layers "B.Cu" "In6.Cu" "In11.Cu" "In13.Cu" "In15.Cu")
		(hatch none 0.5)
		(connect_pads
			(clearance 0)
		)
		(min_thickness 0.25)
		(keepout
			(tracks not_allowed)
			(vias allowed)
			(pads allowed)
			(copperpour not_allowed)
			(footprints allowed)
		)
		(placement
			(enabled no)
			(sheetname "")
		)
		(fill yes
			(thermal_gap 0.5)
			(thermal_bridge_width 0.5)
			(island_removal_mode 0)
		)
		(polygon
			(pts
				(arc
					(start 425.162472 -231.316784)
					(mid 424.509692 -231.316784)
					(end 425.162472 -231.316784)
				)
			)
		)
	)
	(zone
		(layers "B.Cu" "In6.Cu" "In11.Cu" "In13.Cu" "In15.Cu")
		(hatch none 0.5)
		(connect_pads
			(clearance 0)
		)
		(min_thickness 0.25)
		(keepout
			(tracks not_allowed)
			(vias allowed)
			(pads allowed)
			(copperpour not_allowed)
			(footprints allowed)
		)
		(placement
			(enabled no)
			(sheetname "")
		)
		(fill yes
			(thermal_gap 0.5)
			(thermal_bridge_width 0.5)
			(island_removal_mode 0)
		)
		(polygon
			(pts
				(arc
					(start 340.750652 -277.522432)
					(mid 340.097872 -277.522432)
					(end 340.750652 -277.522432)
				)
			)
		)
	)
	(zone
		(layers "B.Cu" "In6.Cu" "In11.Cu" "In13.Cu" "In15.Cu")
		(hatch none 0.5)
		(connect_pads
			(clearance 0)
		)
		(min_thickness 0.25)
		(keepout
			(tracks not_allowed)
			(vias allowed)
			(pads allowed)
			(copperpour not_allowed)
			(footprints allowed)
		)
		(placement
			(enabled no)
			(sheetname "")
		)
		(fill yes
			(thermal_gap 0.5)
			(thermal_bridge_width 0.5)
			(island_removal_mode 0)
		)
		(polygon
			(pts
				(arc
					(start 377.873006 -265.314176)
					(mid 377.220226 -265.314176)
					(end 377.873006 -265.314176)
				)
			)
		)
	)
	(zone
		(layers "B.Cu" "In6.Cu" "In11.Cu" "In13.Cu" "In15.Cu")
		(hatch none 0.5)
		(connect_pads
			(clearance 0)
		)
		(min_thickness 0.25)
		(keepout
			(tracks not_allowed)
			(vias allowed)
			(pads allowed)
			(copperpour not_allowed)
			(footprints allowed)
		)
		(placement
			(enabled no)
			(sheetname "")
		)
		(fill yes
			(thermal_gap 0.5)
			(thermal_bridge_width 0.5)
			(island_removal_mode 0)
		)
		(polygon
			(pts
				(arc
					(start 36.303204 -295.06672)
					(mid 35.650424 -295.06672)
					(end 36.303204 -295.06672)
				)
			)
		)
	)
	(zone
		(layers "B.Cu" "In6.Cu" "In11.Cu" "In13.Cu" "In15.Cu")
		(hatch none 0.5)
		(connect_pads
			(clearance 0)
		)
		(min_thickness 0.25)
		(keepout
			(tracks not_allowed)
			(vias allowed)
			(pads allowed)
			(copperpour not_allowed)
			(footprints allowed)
		)
		(placement
			(enabled no)
			(sheetname "")
		)
		(fill yes
			(thermal_gap 0.5)
			(thermal_bridge_width 0.5)
			(island_removal_mode 0)
		)
		(polygon
			(pts
				(arc
					(start 117.605556 -217.878406)
					(mid 116.952776 -217.878406)
					(end 117.605556 -217.878406)
				)
			)
		)
	)
	(zone
		(layers "B.Cu" "In6.Cu" "In11.Cu" "In13.Cu" "In15.Cu")
		(hatch none 0.5)
		(connect_pads
			(clearance 0)
		)
		(min_thickness 0.25)
		(keepout
			(tracks not_allowed)
			(vias allowed)
			(pads allowed)
			(copperpour not_allowed)
			(footprints allowed)
		)
		(placement
			(enabled no)
			(sheetname "")
		)
		(fill yes
			(thermal_gap 0.5)
			(thermal_bridge_width 0.5)
			(island_removal_mode 0)
		)
		(polygon
			(pts
				(arc
					(start 342.160606 -263.686544)
					(mid 341.507826 -263.686544)
					(end 342.160606 -263.686544)
				)
			)
		)
	)
	(zone
		(layers "B.Cu" "In6.Cu" "In11.Cu" "In13.Cu" "In15.Cu")
		(hatch none 0.5)
		(connect_pads
			(clearance 0)
		)
		(min_thickness 0.25)
		(keepout
			(tracks not_allowed)
			(vias allowed)
			(pads allowed)
			(copperpour not_allowed)
			(footprints allowed)
		)
		(placement
			(enabled no)
			(sheetname "")
		)
		(fill yes
			(thermal_gap 0.5)
			(thermal_bridge_width 0.5)
			(island_removal_mode 0)
		)
		(polygon
			(pts
				(arc
					(start 94.220538 -266.941808)
					(mid 93.567758 -266.941808)
					(end 94.220538 -266.941808)
				)
			)
		)
	)
	(zone
		(layers "B.Cu" "In6.Cu" "In11.Cu" "In13.Cu" "In15.Cu")
		(hatch none 0.5)
		(connect_pads
			(clearance 0)
		)
		(min_thickness 0.25)
		(keepout
			(tracks not_allowed)
			(vias allowed)
			(pads allowed)
			(copperpour not_allowed)
			(footprints allowed)
		)
		(placement
			(enabled no)
			(sheetname "")
		)
		(fill yes
			(thermal_gap 0.5)
			(thermal_bridge_width 0.5)
			(island_removal_mode 0)
		)
		(polygon
			(pts
				(arc
					(start 436.150004 -247.466612)
					(mid 435.497224 -247.466612)
					(end 436.150004 -247.466612)
				)
			)
		)
	)
	(zone
		(layers "B.Cu" "In6.Cu" "In11.Cu" "In13.Cu" "In15.Cu")
		(hatch none 0.5)
		(connect_pads
			(clearance 0)
		)
		(min_thickness 0.25)
		(keepout
			(tracks not_allowed)
			(vias allowed)
			(pads allowed)
			(copperpour not_allowed)
			(footprints allowed)
		)
		(placement
			(enabled no)
			(sheetname "")
		)
		(fill yes
			(thermal_gap 0.5)
			(thermal_bridge_width 0.5)
			(island_removal_mode 0)
		)
		(polygon
			(pts
				(arc
					(start 95.990156 -217.878406)
					(mid 95.337376 -217.878406)
					(end 95.990156 -217.878406)
				)
			)
		)
	)
	(zone
		(layers "B.Cu" "In6.Cu" "In11.Cu" "In13.Cu" "In15.Cu")
		(hatch none 0.5)
		(connect_pads
			(clearance 0)
		)
		(min_thickness 0.25)
		(keepout
			(tracks not_allowed)
			(vias allowed)
			(pads allowed)
			(copperpour not_allowed)
			(footprints allowed)
		)
		(placement
			(enabled no)
			(sheetname "")
		)
		(fill yes
			(thermal_gap 0.5)
			(thermal_bridge_width 0.5)
			(island_removal_mode 0)
		)
		(polygon
			(pts
				(arc
					(start 128.883156 -248.806208)
					(mid 128.230376 -248.806208)
					(end 128.883156 -248.806208)
				)
			)
		)
	)
	(zone
		(layers "B.Cu" "In6.Cu" "In11.Cu" "In13.Cu" "In15.Cu")
		(hatch none 0.5)
		(connect_pads
			(clearance 0)
		)
		(min_thickness 0.25)
		(keepout
			(tracks not_allowed)
			(vias allowed)
			(pads allowed)
			(copperpour not_allowed)
			(footprints allowed)
		)
		(placement
			(enabled no)
			(sheetname "")
		)
		(fill yes
			(thermal_gap 0.5)
			(thermal_bridge_width 0.5)
			(island_removal_mode 0)
		)
		(polygon
			(pts
				(arc
					(start 378.23267 -236.597952)
					(mid 377.57989 -236.597952)
					(end 378.23267 -236.597952)
				)
			)
		)
	)
	(zone
		(layers "B.Cu" "In6.Cu" "In11.Cu" "In13.Cu" "In15.Cu")
		(hatch none 0.5)
		(connect_pads
			(clearance 0)
		)
		(min_thickness 0.25)
		(keepout
			(tracks not_allowed)
			(vias allowed)
			(pads allowed)
			(copperpour not_allowed)
			(footprints allowed)
		)
		(placement
			(enabled no)
			(sheetname "")
		)
		(fill yes
			(thermal_gap 0.5)
			(thermal_bridge_width 0.5)
			(island_removal_mode 0)
		)
		(polygon
			(pts
				(arc
					(start 93.640402 -238.225584)
					(mid 92.987622 -238.225584)
					(end 93.640402 -238.225584)
				)
			)
		)
	)
	(zone
		(layers "B.Cu" "In6.Cu" "In11.Cu" "In13.Cu" "In15.Cu")
		(hatch none 0.5)
		(connect_pads
			(clearance 0)
		)
		(min_thickness 0.25)
		(keepout
			(tracks not_allowed)
			(vias allowed)
			(pads allowed)
			(copperpour not_allowed)
			(footprints allowed)
		)
		(placement
			(enabled no)
			(sheetname "")
		)
		(fill yes
			(thermal_gap 0.5)
			(thermal_bridge_width 0.5)
			(island_removal_mode 0)
		)
		(polygon
			(pts
				(arc
					(start 132.642356 -217.878406)
					(mid 131.989576 -217.878406)
					(end 132.642356 -217.878406)
				)
			)
		)
	)
	(zone
		(layers "B.Cu" "In6.Cu" "In11.Cu" "In13.Cu" "In15.Cu")
		(hatch none 0.5)
		(connect_pads
			(clearance 0)
		)
		(min_thickness 0.25)
		(keepout
			(tracks not_allowed)
			(vias allowed)
			(pads allowed)
			(copperpour not_allowed)
			(footprints allowed)
		)
		(placement
			(enabled no)
			(sheetname "")
		)
		(fill yes
			(thermal_gap 0.5)
			(thermal_bridge_width 0.5)
			(island_removal_mode 0)
		)
		(polygon
			(pts
				(arc
					(start 341.58047 -233.34218)
					(mid 340.92769 -233.34218)
					(end 341.58047 -233.34218)
				)
			)
		)
	)
	(zone
		(layers "B.Cu" "In6.Cu" "In11.Cu" "In13.Cu" "In15.Cu")
		(hatch none 0.5)
		(connect_pads
			(clearance 0)
		)
		(min_thickness 0.25)
		(keepout
			(tracks not_allowed)
			(vias allowed)
			(pads allowed)
			(copperpour not_allowed)
			(footprints allowed)
		)
		(placement
			(enabled no)
			(sheetname "")
		)
		(fill yes
			(thermal_gap 0.5)
			(thermal_bridge_width 0.5)
			(island_removal_mode 0)
		)
		(polygon
			(pts
				(arc
					(start 284.243272 -292.516814)
					(mid 283.590492 -292.516814)
					(end 284.243272 -292.516814)
				)
			)
		)
	)
	(zone
		(layers "B.Cu" "In6.Cu" "In11.Cu" "In13.Cu" "In15.Cu")
		(hatch none 0.5)
		(connect_pads
			(clearance 0)
		)
		(min_thickness 0.25)
		(keepout
			(tracks not_allowed)
			(vias allowed)
			(pads allowed)
			(copperpour not_allowed)
			(footprints allowed)
		)
		(placement
			(enabled no)
			(sheetname "")
		)
		(fill yes
			(thermal_gap 0.5)
			(thermal_bridge_width 0.5)
			(island_removal_mode 0)
		)
		(polygon
			(pts
				(arc
					(start 92.810584 -262.872474)
					(mid 92.157804 -262.872474)
					(end 92.810584 -262.872474)
				)
			)
		)
	)
	(zone
		(layers "B.Cu" "In6.Cu" "In11.Cu" "In13.Cu" "In15.Cu")
		(hatch none 0.5)
		(connect_pads
			(clearance 0)
		)
		(min_thickness 0.25)
		(keepout
			(tracks not_allowed)
			(vias allowed)
			(pads allowed)
			(copperpour not_allowed)
			(footprints allowed)
		)
		(placement
			(enabled no)
			(sheetname "")
		)
		(fill yes
			(thermal_gap 0.5)
			(thermal_bridge_width 0.5)
			(island_removal_mode 0)
		)
		(polygon
			(pts
				(arc
					(start 375.41327 -249.620024)
					(mid 374.76049 -249.620024)
					(end 375.41327 -249.620024)
				)
			)
		)
	)
	(zone
		(layers "B.Cu" "In6.Cu" "In11.Cu" "In13.Cu" "In15.Cu")
		(hatch none 0.5)
		(connect_pads
			(clearance 0)
		)
		(min_thickness 0.25)
		(keepout
			(tracks not_allowed)
			(vias allowed)
			(pads allowed)
			(copperpour not_allowed)
			(footprints allowed)
		)
		(placement
			(enabled no)
			(sheetname "")
		)
		(fill yes
			(thermal_gap 0.5)
			(thermal_bridge_width 0.5)
			(island_removal_mode 0)
		)
		(polygon
			(pts
				(arc
					(start 36.303204 -307.816758)
					(mid 35.650424 -307.816758)
					(end 36.303204 -307.816758)
				)
			)
		)
	)
	(zone
		(layers "B.Cu" "In6.Cu" "In11.Cu" "In13.Cu" "In15.Cu")
		(hatch none 0.5)
		(connect_pads
			(clearance 0)
		)
		(min_thickness 0.25)
		(keepout
			(tracks not_allowed)
			(vias allowed)
			(pads allowed)
			(copperpour not_allowed)
			(footprints allowed)
		)
		(placement
			(enabled no)
			(sheetname "")
		)
		(fill yes
			(thermal_gap 0.5)
			(thermal_bridge_width 0.5)
			(island_removal_mode 0)
		)
		(polygon
			(pts
				(arc
					(start 192.310004 -311.216548)
					(mid 191.657224 -311.216548)
					(end 192.310004 -311.216548)
				)
			)
		)
	)
	(zone
		(layers "B.Cu" "In6.Cu" "In11.Cu" "In13.Cu" "In15.Cu")
		(hatch none 0.5)
		(connect_pads
			(clearance 0)
		)
		(min_thickness 0.25)
		(keepout
			(tracks not_allowed)
			(vias allowed)
			(pads allowed)
			(copperpour not_allowed)
			(footprints allowed)
		)
		(placement
			(enabled no)
			(sheetname "")
		)
		(fill yes
			(thermal_gap 0.5)
			(thermal_bridge_width 0.5)
			(island_removal_mode 0)
		)
		(polygon
			(pts
				(arc
					(start 130.402584 -259.616956)
					(mid 129.749804 -259.616956)
					(end 130.402584 -259.616956)
				)
			)
		)
	)
	(zone
		(layers "B.Cu" "In6.Cu" "In11.Cu" "In13.Cu" "In15.Cu")
		(hatch none 0.5)
		(connect_pads
			(clearance 0)
		)
		(min_thickness 0.25)
		(keepout
			(tracks not_allowed)
			(vias allowed)
			(pads allowed)
			(copperpour not_allowed)
			(footprints allowed)
		)
		(placement
			(enabled no)
			(sheetname "")
		)
		(fill yes
			(thermal_gap 0.5)
			(thermal_bridge_width 0.5)
			(island_removal_mode 0)
		)
		(polygon
			(pts
				(arc
					(start 94.110556 -229.272846)
					(mid 93.457776 -229.272846)
					(end 94.110556 -229.272846)
				)
			)
		)
	)
	(zone
		(layers "B.Cu" "In6.Cu" "In11.Cu" "In13.Cu" "In15.Cu")
		(hatch none 0.5)
		(connect_pads
			(clearance 0)
		)
		(min_thickness 0.25)
		(keepout
			(tracks not_allowed)
			(vias allowed)
			(pads allowed)
			(copperpour not_allowed)
			(footprints allowed)
		)
		(placement
			(enabled no)
			(sheetname "")
		)
		(fill yes
			(thermal_gap 0.5)
			(thermal_bridge_width 0.5)
			(island_removal_mode 0)
		)
		(polygon
			(pts
				(arc
					(start 177.222404 -301.866554)
					(mid 176.569624 -301.866554)
					(end 177.222404 -301.866554)
				)
			)
		)
	)
	(zone
		(layers "B.Cu" "In6.Cu" "In11.Cu" "In13.Cu" "In15.Cu")
		(hatch none 0.5)
		(connect_pads
			(clearance 0)
		)
		(min_thickness 0.25)
		(keepout
			(tracks not_allowed)
			(vias allowed)
			(pads allowed)
			(copperpour not_allowed)
			(footprints allowed)
		)
		(placement
			(enabled no)
			(sheetname "")
		)
		(fill yes
			(thermal_gap 0.5)
			(thermal_bridge_width 0.5)
			(island_removal_mode 0)
		)
		(polygon
			(pts
				(arc
					(start 129.822956 -217.878406)
					(mid 129.170176 -217.878406)
					(end 129.822956 -217.878406)
				)
			)
		)
	)
	(zone
		(layers "B.Cu" "In6.Cu" "In11.Cu" "In13.Cu" "In15.Cu")
		(hatch none 0.5)
		(connect_pads
			(clearance 0)
		)
		(min_thickness 0.25)
		(keepout
			(tracks not_allowed)
			(vias allowed)
			(pads allowed)
			(copperpour not_allowed)
			(footprints allowed)
		)
		(placement
			(enabled no)
			(sheetname "")
		)
		(fill yes
			(thermal_gap 0.5)
			(thermal_bridge_width 0.5)
			(island_removal_mode 0)
		)
		(polygon
			(pts
				(arc
					(start 32.203136 -289.966654)
					(mid 31.550356 -289.966654)
					(end 32.203136 -289.966654)
				)
			)
		)
	)
	(zone
		(layers "B.Cu" "In6.Cu" "In11.Cu" "In13.Cu" "In15.Cu")
		(hatch none 0.5)
		(connect_pads
			(clearance 0)
		)
		(min_thickness 0.25)
		(keepout
			(tracks not_allowed)
			(vias allowed)
			(pads allowed)
			(copperpour not_allowed)
			(footprints allowed)
		)
		(placement
			(enabled no)
			(sheetname "")
		)
		(fill yes
			(thermal_gap 0.5)
			(thermal_bridge_width 0.5)
			(island_removal_mode 0)
		)
		(polygon
			(pts
				(arc
					(start 94.690184 -267.755878)
					(mid 94.037404 -267.755878)
					(end 94.690184 -267.755878)
				)
			)
		)
	)
	(zone
		(layers "B.Cu" "In6.Cu" "In11.Cu" "In13.Cu" "In15.Cu")
		(hatch none 0.5)
		(connect_pads
			(clearance 0)
		)
		(min_thickness 0.25)
		(keepout
			(tracks not_allowed)
			(vias allowed)
			(pads allowed)
			(copperpour not_allowed)
			(footprints allowed)
		)
		(placement
			(enabled no)
			(sheetname "")
		)
		(fill yes
			(thermal_gap 0.5)
			(thermal_bridge_width 0.5)
			(island_removal_mode 0)
		)
		(polygon
			(pts
				(arc
					(start 173.122336 -230.466646)
					(mid 172.469556 -230.466646)
					(end 173.122336 -230.466646)
				)
			)
		)
	)
	(zone
		(layers "B.Cu" "In6.Cu" "In11.Cu" "In13.Cu" "In15.Cu")
		(hatch none 0.5)
		(connect_pads
			(clearance 0)
		)
		(min_thickness 0.25)
		(keepout
			(tracks not_allowed)
			(vias allowed)
			(pads allowed)
			(copperpour not_allowed)
			(footprints allowed)
		)
		(placement
			(enabled no)
			(sheetname "")
		)
		(fill yes
			(thermal_gap 0.5)
			(thermal_bridge_width 0.5)
			(island_removal_mode 0)
		)
		(polygon
			(pts
				(arc
					(start 130.402584 -269.38351)
					(mid 129.749804 -269.38351)
					(end 130.402584 -269.38351)
				)
			)
		)
	)
	(zone
		(layers "B.Cu" "In6.Cu" "In11.Cu" "In13.Cu" "In15.Cu")
		(hatch none 0.5)
		(connect_pads
			(clearance 0)
		)
		(min_thickness 0.25)
		(keepout
			(tracks not_allowed)
			(vias allowed)
			(pads allowed)
			(copperpour not_allowed)
			(footprints allowed)
		)
		(placement
			(enabled no)
			(sheetname "")
		)
		(fill yes
			(thermal_gap 0.5)
			(thermal_bridge_width 0.5)
			(island_removal_mode 0)
		)
		(polygon
			(pts
				(arc
					(start 92.700602 -246.364506)
					(mid 92.047822 -246.364506)
					(end 92.700602 -246.364506)
				)
			)
		)
	)
	(zone
		(layers "B.Cu" "In6.Cu" "In11.Cu" "In13.Cu" "In15.Cu")
		(hatch none 0.5)
		(connect_pads
			(clearance 0)
		)
		(min_thickness 0.25)
		(keepout
			(tracks not_allowed)
			(vias allowed)
			(pads allowed)
			(copperpour not_allowed)
			(footprints allowed)
		)
		(placement
			(enabled no)
			(sheetname "")
		)
		(fill yes
			(thermal_gap 0.5)
			(thermal_bridge_width 0.5)
			(island_removal_mode 0)
		)
		(polygon
			(pts
				(arc
					(start 365.07547 -217.064336)
					(mid 364.42269 -217.064336)
					(end 365.07547 -217.064336)
				)
			)
		)
	)
	(zone
		(layers "B.Cu" "In6.Cu" "In11.Cu" "In13.Cu" "In15.Cu")
		(hatch none 0.5)
		(connect_pads
			(clearance 0)
		)
		(min_thickness 0.25)
		(keepout
			(tracks not_allowed)
			(vias allowed)
			(pads allowed)
			(copperpour not_allowed)
			(footprints allowed)
		)
		(placement
			(enabled no)
			(sheetname "")
		)
		(fill yes
			(thermal_gap 0.5)
			(thermal_bridge_width 0.5)
			(island_removal_mode 0)
		)
		(polygon
			(pts
				(arc
					(start 380.582424 -217.878406)
					(mid 379.929644 -217.878406)
					(end 380.582424 -217.878406)
				)
			)
		)
	)
	(zone
		(layers "B.Cu" "In6.Cu" "In11.Cu" "In13.Cu" "In15.Cu")
		(hatch none 0.5)
		(connect_pads
			(clearance 0)
		)
		(min_thickness 0.25)
		(keepout
			(tracks not_allowed)
			(vias allowed)
			(pads allowed)
			(copperpour not_allowed)
			(footprints allowed)
		)
		(placement
			(enabled no)
			(sheetname "")
		)
		(fill yes
			(thermal_gap 0.5)
			(thermal_bridge_width 0.5)
			(island_removal_mode 0)
		)
		(polygon
			(pts
				(arc
					(start 93.640402 -243.108988)
					(mid 92.987622 -243.108988)
					(end 93.640402 -243.108988)
				)
			)
		)
	)
	(zone
		(layers "B.Cu" "In6.Cu" "In11.Cu" "In13.Cu" "In15.Cu")
		(hatch none 0.5)
		(connect_pads
			(clearance 0)
		)
		(min_thickness 0.25)
		(keepout
			(tracks not_allowed)
			(vias allowed)
			(pads allowed)
			(copperpour not_allowed)
			(footprints allowed)
		)
		(placement
			(enabled no)
			(sheetname "")
		)
		(fill yes
			(thermal_gap 0.5)
			(thermal_bridge_width 0.5)
			(island_removal_mode 0)
		)
		(polygon
			(pts
				(arc
					(start 425.162472 -223.666558)
					(mid 424.509692 -223.666558)
					(end 425.162472 -223.666558)
				)
			)
		)
	)
	(zone
		(layers "B.Cu" "In6.Cu" "In11.Cu" "In13.Cu" "In15.Cu")
		(hatch none 0.5)
		(connect_pads
			(clearance 0)
		)
		(min_thickness 0.25)
		(keepout
			(tracks not_allowed)
			(vias allowed)
			(pads allowed)
			(copperpour not_allowed)
			(footprints allowed)
		)
		(placement
			(enabled no)
			(sheetname "")
		)
		(fill yes
			(thermal_gap 0.5)
			(thermal_bridge_width 0.5)
			(island_removal_mode 0)
		)
		(polygon
			(pts
				(arc
					(start 340.64067 -217.064336)
					(mid 339.98789 -217.064336)
					(end 340.64067 -217.064336)
				)
			)
		)
	)
	(zone
		(layers "B.Cu" "In6.Cu" "In11.Cu" "In13.Cu" "In15.Cu")
		(hatch none 0.5)
		(connect_pads
			(clearance 0)
		)
		(min_thickness 0.25)
		(keepout
			(tracks not_allowed)
			(vias allowed)
			(pads allowed)
			(copperpour not_allowed)
			(footprints allowed)
		)
		(placement
			(enabled no)
			(sheetname "")
		)
		(fill yes
			(thermal_gap 0.5)
			(thermal_bridge_width 0.5)
			(island_removal_mode 0)
		)
		(polygon
			(pts
				(arc
					(start 280.143204 -241.516662)
					(mid 279.490424 -241.516662)
					(end 280.143204 -241.516662)
				)
			)
		)
	)
	(zone
		(layers "B.Cu" "In6.Cu" "In11.Cu" "In13.Cu" "In15.Cu")
		(hatch none 0.5)
		(connect_pads
			(clearance 0)
		)
		(min_thickness 0.25)
		(keepout
			(tracks not_allowed)
			(vias allowed)
			(pads allowed)
			(copperpour not_allowed)
			(footprints allowed)
		)
		(placement
			(enabled no)
			(sheetname "")
		)
		(fill yes
			(thermal_gap 0.5)
			(thermal_bridge_width 0.5)
			(island_removal_mode 0)
		)
		(polygon
			(pts
				(arc
					(start 375.41327 -247.992138)
					(mid 374.76049 -247.992138)
					(end 375.41327 -247.992138)
				)
			)
		)
	)
	(zone
		(layers "B.Cu" "In6.Cu" "In11.Cu" "In13.Cu" "In15.Cu")
		(hatch none 0.5)
		(connect_pads
			(clearance 0)
		)
		(min_thickness 0.25)
		(keepout
			(tracks not_allowed)
			(vias allowed)
			(pads allowed)
			(copperpour not_allowed)
			(footprints allowed)
		)
		(placement
			(enabled no)
			(sheetname "")
		)
		(fill yes
			(thermal_gap 0.5)
			(thermal_bridge_width 0.5)
			(island_removal_mode 0)
		)
		(polygon
			(pts
				(arc
					(start 436.150004 -312.91657)
					(mid 435.497224 -312.91657)
					(end 436.150004 -312.91657)
				)
			)
		)
	)
	(zone
		(layers "B.Cu" "In6.Cu" "In11.Cu" "In13.Cu" "In15.Cu")
		(hatch none 0.5)
		(connect_pads
			(clearance 0)
		)
		(min_thickness 0.25)
		(keepout
			(tracks not_allowed)
			(vias allowed)
			(pads allowed)
			(copperpour not_allowed)
			(footprints allowed)
		)
		(placement
			(enabled no)
			(sheetname "")
		)
		(fill yes
			(thermal_gap 0.5)
			(thermal_bridge_width 0.5)
			(island_removal_mode 0)
		)
		(polygon
			(pts
				(arc
					(start 378.812806 -276.708616)
					(mid 378.160026 -276.708616)
					(end 378.812806 -276.708616)
				)
			)
		)
	)
	(zone
		(layers "B.Cu" "In11.Cu" "In13.Cu" "In15.Cu")
		(hatch none 0.5)
		(connect_pads
			(clearance 0)
		)
		(min_thickness 0.25)
		(keepout
			(tracks not_allowed)
			(vias allowed)
			(pads allowed)
			(copperpour not_allowed)
			(footprints allowed)
		)
		(placement
			(enabled no)
			(sheetname "")
		)
		(fill yes
			(thermal_gap 0.5)
			(thermal_bridge_width 0.5)
			(island_removal_mode 0)
		)
		(polygon
			(pts
				(arc
					(start 280.143204 -288.266632)
					(mid 279.490424 -288.266632)
					(end 280.143204 -288.266632)
				)
			)
		)
	)
	(zone
		(layers "B.Cu" "In11.Cu" "In13.Cu" "In15.Cu")
		(hatch none 0.5)
		(connect_pads
			(clearance 0)
		)
		(min_thickness 0.25)
		(keepout
			(tracks not_allowed)
			(vias allowed)
			(pads allowed)
			(copperpour not_allowed)
			(footprints allowed)
		)
		(placement
			(enabled no)
			(sheetname "")
		)
		(fill yes
			(thermal_gap 0.5)
			(thermal_bridge_width 0.5)
			(island_removal_mode 0)
		)
		(polygon
			(pts
				(arc
					(start 440.250072 -217.716608)
					(mid 439.597292 -217.716608)
					(end 440.250072 -217.716608)
				)
			)
		)
	)
	(zone
		(layers "B.Cu" "In11.Cu" "In13.Cu" "In15.Cu")
		(hatch none 0.5)
		(connect_pads
			(clearance 0)
		)
		(min_thickness 0.25)
		(keepout
			(tracks not_allowed)
			(vias allowed)
			(pads allowed)
			(copperpour not_allowed)
			(footprints allowed)
		)
		(placement
			(enabled no)
			(sheetname "")
		)
		(fill yes
			(thermal_gap 0.5)
			(thermal_bridge_width 0.5)
			(island_removal_mode 0)
		)
		(polygon
			(pts
				(arc
					(start 127.473202 -228.45903)
					(mid 126.820422 -228.45903)
					(end 127.473202 -228.45903)
				)
			)
		)
	)
	(zone
		(layers "B.Cu" "In11.Cu" "In13.Cu" "In15.Cu")
		(hatch none 0.5)
		(connect_pads
			(clearance 0)
		)
		(min_thickness 0.25)
		(keepout
			(tracks not_allowed)
			(vias allowed)
			(pads allowed)
			(copperpour not_allowed)
			(footprints allowed)
		)
		(placement
			(enabled no)
			(sheetname "")
		)
		(fill yes
			(thermal_gap 0.5)
			(thermal_bridge_width 0.5)
			(island_removal_mode 0)
		)
		(polygon
			(pts
				(arc
					(start 153.154888 -437.889904)
					(mid 152.345136 -437.889904)
					(end 153.154888 -437.889904)
				)
			)
		)
	)
	(zone
		(layers "B.Cu" "In11.Cu" "In13.Cu" "In15.Cu")
		(hatch none 0.5)
		(connect_pads
			(clearance 0)
		)
		(min_thickness 0.25)
		(keepout
			(tracks not_allowed)
			(vias allowed)
			(pads allowed)
			(copperpour not_allowed)
			(footprints allowed)
		)
		(placement
			(enabled no)
			(sheetname "")
		)
		(fill yes
			(thermal_gap 0.5)
			(thermal_bridge_width 0.5)
			(island_removal_mode 0)
		)
		(polygon
			(pts
				(arc
					(start 352.387916 -214.622634)
					(mid 351.735136 -214.622634)
					(end 352.387916 -214.622634)
				)
			)
		)
	)
	(zone
		(layers "B.Cu" "In11.Cu" "In13.Cu" "In15.Cu")
		(hatch none 0.5)
		(connect_pads
			(clearance 0)
		)
		(min_thickness 0.25)
		(keepout
			(tracks not_allowed)
			(vias allowed)
			(pads allowed)
			(copperpour not_allowed)
			(footprints allowed)
		)
		(placement
			(enabled no)
			(sheetname "")
		)
		(fill yes
			(thermal_gap 0.5)
			(thermal_bridge_width 0.5)
			(island_removal_mode 0)
		)
		(polygon
			(pts
				(arc
					(start 97.399602 -215.436704)
					(mid 96.746822 -215.436704)
					(end 97.399602 -215.436704)
				)
			)
		)
	)
	(zone
		(layers "B.Cu" "In11.Cu" "In13.Cu" "In15.Cu")
		(hatch none 0.5)
		(connect_pads
			(clearance 0)
		)
		(min_thickness 0.25)
		(keepout
			(tracks not_allowed)
			(vias allowed)
			(pads allowed)
			(copperpour not_allowed)
			(footprints allowed)
		)
		(placement
			(enabled no)
			(sheetname "")
		)
		(fill yes
			(thermal_gap 0.5)
			(thermal_bridge_width 0.5)
			(island_removal_mode 0)
		)
		(polygon
			(pts
				(arc
					(start 346.054934 -428.28972)
					(mid 345.245182 -428.28972)
					(end 346.054934 -428.28972)
				)
			)
		)
	)
	(zone
		(layers "B.Cu" "In11.Cu" "In13.Cu" "In15.Cu")
		(hatch none 0.5)
		(connect_pads
			(clearance 0)
		)
		(min_thickness 0.25)
		(keepout
			(tracks not_allowed)
			(vias allowed)
			(pads allowed)
			(copperpour not_allowed)
			(footprints allowed)
		)
		(placement
			(enabled no)
			(sheetname "")
		)
		(fill yes
			(thermal_gap 0.5)
			(thermal_bridge_width 0.5)
			(island_removal_mode 0)
		)
		(polygon
			(pts
				(arc
					(start 376.463052 -264.50036)
					(mid 375.810272 -264.50036)
					(end 376.463052 -264.50036)
				)
			)
		)
	)
	(zone
		(layers "B.Cu" "In11.Cu" "In13.Cu" "In15.Cu")
		(hatch none 0.5)
		(connect_pads
			(clearance 0)
		)
		(min_thickness 0.25)
		(keepout
			(tracks not_allowed)
			(vias allowed)
			(pads allowed)
			(copperpour not_allowed)
			(footprints allowed)
		)
		(placement
			(enabled no)
			(sheetname "")
		)
		(fill yes
			(thermal_gap 0.5)
			(thermal_bridge_width 0.5)
			(island_removal_mode 0)
		)
		(polygon
			(pts
				(arc
					(start 358.966516 -214.622634)
					(mid 358.313736 -214.622634)
					(end 358.966516 -214.622634)
				)
			)
		)
	)
	(zone
		(layers "B.Cu" "In11.Cu" "In13.Cu" "In15.Cu")
		(hatch none 0.5)
		(connect_pads
			(clearance 0)
		)
		(min_thickness 0.25)
		(keepout
			(tracks not_allowed)
			(vias allowed)
			(pads allowed)
			(copperpour not_allowed)
			(footprints allowed)
		)
		(placement
			(enabled no)
			(sheetname "")
		)
		(fill yes
			(thermal_gap 0.5)
			(thermal_bridge_width 0.5)
			(island_removal_mode 0)
		)
		(polygon
			(pts
				(arc
					(start 32.203136 -301.01667)
					(mid 31.550356 -301.01667)
					(end 32.203136 -301.01667)
				)
			)
		)
	)
	(zone
		(layers "B.Cu" "In11.Cu" "In13.Cu" "In15.Cu")
		(hatch none 0.5)
		(connect_pads
			(clearance 0)
		)
		(min_thickness 0.25)
		(keepout
			(tracks not_allowed)
			(vias allowed)
			(pads allowed)
			(copperpour not_allowed)
			(footprints allowed)
		)
		(placement
			(enabled no)
			(sheetname "")
		)
		(fill yes
			(thermal_gap 0.5)
			(thermal_bridge_width 0.5)
			(island_removal_mode 0)
		)
		(polygon
			(pts
				(arc
					(start 280.143204 -280.61666)
					(mid 279.490424 -280.61666)
					(end 280.143204 -280.61666)
				)
			)
		)
	)
	(zone
		(layers "B.Cu" "In11.Cu" "In13.Cu" "In15.Cu")
		(hatch none 0.5)
		(connect_pads
			(clearance 0)
		)
		(min_thickness 0.25)
		(keepout
			(tracks not_allowed)
			(vias allowed)
			(pads allowed)
			(copperpour not_allowed)
			(footprints allowed)
		)
		(placement
			(enabled no)
			(sheetname "")
		)
		(fill yes
			(thermal_gap 0.5)
			(thermal_bridge_width 0.5)
			(island_removal_mode 0)
		)
		(polygon
			(pts
				(arc
					(start 280.143204 -243.216684)
					(mid 279.490424 -243.216684)
					(end 280.143204 -243.216684)
				)
			)
		)
	)
	(zone
		(layers "B.Cu" "In11.Cu" "In13.Cu" "In15.Cu")
		(hatch none 0.5)
		(connect_pads
			(clearance 0)
		)
		(min_thickness 0.25)
		(keepout
			(tracks not_allowed)
			(vias allowed)
			(pads allowed)
			(copperpour not_allowed)
			(footprints allowed)
		)
		(placement
			(enabled no)
			(sheetname "")
		)
		(fill yes
			(thermal_gap 0.5)
			(thermal_bridge_width 0.5)
			(island_removal_mode 0)
		)
		(polygon
			(pts
				(arc
					(start 149.154896 -430.689766)
					(mid 148.345144 -430.689766)
					(end 149.154896 -430.689766)
				)
			)
		)
	)
	(zone
		(layers "B.Cu" "In11.Cu" "In13.Cu" "In15.Cu")
		(hatch none 0.5)
		(connect_pads
			(clearance 0)
		)
		(min_thickness 0.25)
		(keepout
			(tracks not_allowed)
			(vias allowed)
			(pads allowed)
			(copperpour not_allowed)
			(footprints allowed)
		)
		(placement
			(enabled no)
			(sheetname "")
		)
		(fill yes
			(thermal_gap 0.5)
			(thermal_bridge_width 0.5)
			(island_removal_mode 0)
		)
		(polygon
			(pts
				(arc
					(start 351.004378 -66.099944)
					(mid 350.300798 -66.099944)
					(end 351.004378 -66.099944)
				)
			)
		)
	)
	(zone
		(layers "B.Cu" "In11.Cu" "In13.Cu" "In15.Cu")
		(hatch none 0.5)
		(connect_pads
			(clearance 0)
		)
		(min_thickness 0.25)
		(keepout
			(tracks not_allowed)
			(vias allowed)
			(pads allowed)
			(copperpour not_allowed)
			(footprints allowed)
		)
		(placement
			(enabled no)
			(sheetname "")
		)
		(fill yes
			(thermal_gap 0.5)
			(thermal_bridge_width 0.5)
			(island_removal_mode 0)
		)
		(polygon
			(pts
				(arc
					(start 21.215604 -210.916774)
					(mid 20.562824 -210.916774)
					(end 21.215604 -210.916774)
				)
			)
		)
	)
	(zone
		(layers "B.Cu" "In11.Cu" "In13.Cu" "In15.Cu")
		(hatch none 0.5)
		(connect_pads
			(clearance 0)
		)
		(min_thickness 0.25)
		(keepout
			(tracks not_allowed)
			(vias allowed)
			(pads allowed)
			(copperpour not_allowed)
			(footprints allowed)
		)
		(placement
			(enabled no)
			(sheetname "")
		)
		(fill yes
			(thermal_gap 0.5)
			(thermal_bridge_width 0.5)
			(island_removal_mode 0)
		)
		(polygon
			(pts
				(arc
					(start 36.303204 -216.016586)
					(mid 35.650424 -216.016586)
					(end 36.303204 -216.016586)
				)
			)
		)
	)
	(zone
		(layers "B.Cu" "In11.Cu" "In13.Cu" "In15.Cu")
		(hatch none 0.5)
		(connect_pads
			(clearance 0)
		)
		(min_thickness 0.25)
		(keepout
			(tracks not_allowed)
			(vias allowed)
			(pads allowed)
			(copperpour not_allowed)
			(footprints allowed)
		)
		(placement
			(enabled no)
			(sheetname "")
		)
		(fill yes
			(thermal_gap 0.5)
			(thermal_bridge_width 0.5)
			(island_removal_mode 0)
		)
		(polygon
			(pts
				(arc
					(start 50.541428 -410.030168)
					(mid 49.837848 -410.030168)
					(end 50.541428 -410.030168)
				)
			)
		)
	)
	(zone
		(layers "B.Cu" "In11.Cu" "In13.Cu" "In15.Cu")
		(hatch none 0.5)
		(connect_pads
			(clearance 0)
		)
		(min_thickness 0.25)
		(keepout
			(tracks not_allowed)
			(vias allowed)
			(pads allowed)
			(copperpour not_allowed)
			(footprints allowed)
		)
		(placement
			(enabled no)
			(sheetname "")
		)
		(fill yes
			(thermal_gap 0.5)
			(thermal_bridge_width 0.5)
			(island_removal_mode 0)
		)
		(polygon
			(pts
				(arc
					(start 343.570052 -264.50036)
					(mid 342.917272 -264.50036)
					(end 343.570052 -264.50036)
				)
			)
		)
	)
	(zone
		(layers "B.Cu" "In11.Cu" "In13.Cu" "In15.Cu")
		(hatch none 0.5)
		(connect_pads
			(clearance 0)
		)
		(min_thickness 0.25)
		(keepout
			(tracks not_allowed)
			(vias allowed)
			(pads allowed)
			(copperpour not_allowed)
			(footprints allowed)
		)
		(placement
			(enabled no)
			(sheetname "")
		)
		(fill yes
			(thermal_gap 0.5)
			(thermal_bridge_width 0.5)
			(island_removal_mode 0)
		)
		(polygon
			(pts
				(arc
					(start 344.040206 -271.825212)
					(mid 343.387426 -271.825212)
					(end 344.040206 -271.825212)
				)
			)
		)
	)
	(zone
		(layers "B.Cu" "In11.Cu" "In13.Cu" "In15.Cu")
		(hatch none 0.5)
		(connect_pads
			(clearance 0)
		)
		(min_thickness 0.25)
		(keepout
			(tracks not_allowed)
			(vias allowed)
			(pads allowed)
			(copperpour not_allowed)
			(footprints allowed)
		)
		(placement
			(enabled no)
			(sheetname "")
		)
		(fill yes
			(thermal_gap 0.5)
			(thermal_bridge_width 0.5)
			(island_removal_mode 0)
		)
		(polygon
			(pts
				(arc
					(start 128.992884 -278.336502)
					(mid 128.340104 -278.336502)
					(end 128.992884 -278.336502)
				)
			)
		)
	)
	(zone
		(layers "B.Cu" "In11.Cu" "In13.Cu" "In15.Cu")
		(hatch none 0.5)
		(connect_pads
			(clearance 0)
		)
		(min_thickness 0.25)
		(keepout
			(tracks not_allowed)
			(vias allowed)
			(pads allowed)
			(copperpour not_allowed)
			(footprints allowed)
		)
		(placement
			(enabled no)
			(sheetname "")
		)
		(fill yes
			(thermal_gap 0.5)
			(thermal_bridge_width 0.5)
			(island_removal_mode 0)
		)
		(polygon
			(pts
				(arc
					(start 192.310004 -284.016704)
					(mid 191.657224 -284.016704)
					(end 192.310004 -284.016704)
				)
			)
		)
	)
	(zone
		(layers "B.Cu" "In11.Cu" "In13.Cu" "In15.Cu")
		(hatch none 0.5)
		(connect_pads
			(clearance 0)
		)
		(min_thickness 0.25)
		(keepout
			(tracks not_allowed)
			(vias allowed)
			(pads allowed)
			(copperpour not_allowed)
			(footprints allowed)
		)
		(placement
			(enabled no)
			(sheetname "")
		)
		(fill yes
			(thermal_gap 0.5)
			(thermal_bridge_width 0.5)
			(island_removal_mode 0)
		)
		(polygon
			(pts
				(arc
					(start 192.310004 -201.56678)
					(mid 191.657224 -201.56678)
					(end 192.310004 -201.56678)
				)
			)
		)
	)
	(zone
		(layers "B.Cu" "In11.Cu" "In13.Cu" "In15.Cu")
		(hatch none 0.5)
		(connect_pads
			(clearance 0)
		)
		(min_thickness 0.25)
		(keepout
			(tracks not_allowed)
			(vias allowed)
			(pads allowed)
			(copperpour not_allowed)
			(footprints allowed)
		)
		(placement
			(enabled no)
			(sheetname "")
		)
		(fill yes
			(thermal_gap 0.5)
			(thermal_bridge_width 0.5)
			(island_removal_mode 0)
		)
		(polygon
			(pts
				(arc
					(start 265.055604 -308.666642)
					(mid 264.402824 -308.666642)
					(end 265.055604 -308.666642)
				)
			)
		)
	)
	(zone
		(layers "B.Cu" "In11.Cu" "In13.Cu" "In15.Cu")
		(hatch none 0.5)
		(connect_pads
			(clearance 0)
		)
		(min_thickness 0.25)
		(keepout
			(tracks not_allowed)
			(vias allowed)
			(pads allowed)
			(copperpour not_allowed)
			(footprints allowed)
		)
		(placement
			(enabled no)
			(sheetname "")
		)
		(fill yes
			(thermal_gap 0.5)
			(thermal_bridge_width 0.5)
			(island_removal_mode 0)
		)
		(polygon
			(pts
				(arc
					(start 90.821256 -213.732618)
					(mid 90.168476 -213.732618)
					(end 90.821256 -213.732618)
				)
			)
		)
	)
	(zone
		(layers "B.Cu" "In11.Cu" "In13.Cu" "In15.Cu")
		(hatch none 0.5)
		(connect_pads
			(clearance 0)
		)
		(min_thickness 0.25)
		(keepout
			(tracks not_allowed)
			(vias allowed)
			(pads allowed)
			(copperpour not_allowed)
			(footprints allowed)
		)
		(placement
			(enabled no)
			(sheetname "")
		)
		(fill yes
			(thermal_gap 0.5)
			(thermal_bridge_width 0.5)
			(island_removal_mode 0)
		)
		(polygon
			(pts
				(arc
					(start 192.310004 -197.316598)
					(mid 191.657224 -197.316598)
					(end 192.310004 -197.316598)
				)
			)
		)
	)
	(zone
		(layers "B.Cu" "In11.Cu" "In13.Cu" "In15.Cu")
		(hatch none 0.5)
		(connect_pads
			(clearance 0)
		)
		(min_thickness 0.25)
		(keepout
			(tracks not_allowed)
			(vias allowed)
			(pads allowed)
			(copperpour not_allowed)
			(footprints allowed)
		)
		(placement
			(enabled no)
			(sheetname "")
		)
		(fill yes
			(thermal_gap 0.5)
			(thermal_bridge_width 0.5)
			(island_removal_mode 0)
		)
		(polygon
			(pts
				(arc
					(start 89.411048 -216.25052)
					(mid 88.758268 -216.25052)
					(end 89.411048 -216.25052)
				)
			)
		)
	)
	(zone
		(layers "B.Cu" "In11.Cu" "In13.Cu" "In15.Cu")
		(hatch none 0.5)
		(connect_pads
			(clearance 0)
		)
		(min_thickness 0.25)
		(keepout
			(tracks not_allowed)
			(vias allowed)
			(pads allowed)
			(copperpour not_allowed)
			(footprints allowed)
		)
		(placement
			(enabled no)
			(sheetname "")
		)
		(fill yes
			(thermal_gap 0.5)
			(thermal_bridge_width 0.5)
			(island_removal_mode 0)
		)
		(polygon
			(pts
				(arc
					(start 280.143204 -221.116652)
					(mid 279.490424 -221.116652)
					(end 280.143204 -221.116652)
				)
			)
		)
	)
	(zone
		(layers "B.Cu" "In11.Cu" "In13.Cu" "In15.Cu")
		(hatch none 0.5)
		(connect_pads
			(clearance 0)
		)
		(min_thickness 0.25)
		(keepout
			(tracks not_allowed)
			(vias allowed)
			(pads allowed)
			(copperpour not_allowed)
			(footprints allowed)
		)
		(placement
			(enabled no)
			(sheetname "")
		)
		(fill yes
			(thermal_gap 0.5)
			(thermal_bridge_width 0.5)
			(island_removal_mode 0)
		)
		(polygon
			(pts
				(arc
					(start 305.195478 -403.883876)
					(mid 304.491898 -403.883876)
					(end 305.195478 -403.883876)
				)
			)
		)
	)
	(zone
		(layers "B.Cu" "In11.Cu" "In13.Cu" "In15.Cu")
		(hatch none 0.5)
		(connect_pads
			(clearance 0)
		)
		(min_thickness 0.25)
		(keepout
			(tracks not_allowed)
			(vias allowed)
			(pads allowed)
			(copperpour not_allowed)
			(footprints allowed)
		)
		(placement
			(enabled no)
			(sheetname "")
		)
		(fill yes
			(thermal_gap 0.5)
			(thermal_bridge_width 0.5)
			(island_removal_mode 0)
		)
		(polygon
			(pts
				(arc
					(start 440.250072 -218.566746)
					(mid 439.597292 -218.566746)
					(end 440.250072 -218.566746)
				)
			)
		)
	)
	(zone
		(layers "B.Cu" "In11.Cu" "In13.Cu" "In15.Cu")
		(hatch none 0.5)
		(connect_pads
			(clearance 0)
		)
		(min_thickness 0.25)
		(keepout
			(tracks not_allowed)
			(vias allowed)
			(pads allowed)
			(copperpour not_allowed)
			(footprints allowed)
		)
		(placement
			(enabled no)
			(sheetname "")
		)
		(fill yes
			(thermal_gap 0.5)
			(thermal_bridge_width 0.5)
			(island_removal_mode 0)
		)
		(polygon
			(pts
				(arc
					(start 127.113538 -276.708616)
					(mid 126.460758 -276.708616)
					(end 127.113538 -276.708616)
				)
			)
		)
	)
	(zone
		(layers "B.Cu" "In11.Cu" "In13.Cu" "In15.Cu")
		(hatch none 0.5)
		(connect_pads
			(clearance 0)
		)
		(min_thickness 0.25)
		(keepout
			(tracks not_allowed)
			(vias allowed)
			(pads allowed)
			(copperpour not_allowed)
			(footprints allowed)
		)
		(placement
			(enabled no)
			(sheetname "")
		)
		(fill yes
			(thermal_gap 0.5)
			(thermal_bridge_width 0.5)
			(island_removal_mode 0)
		)
		(polygon
			(pts
				(arc
					(start 96.100138 -263.686544)
					(mid 95.447358 -263.686544)
					(end 96.100138 -263.686544)
				)
			)
		)
	)
	(zone
		(layers "B.Cu" "In11.Cu" "In13.Cu" "In15.Cu")
		(hatch none 0.5)
		(connect_pads
			(clearance 0)
		)
		(min_thickness 0.25)
		(keepout
			(tracks not_allowed)
			(vias allowed)
			(pads allowed)
			(copperpour not_allowed)
			(footprints allowed)
		)
		(placement
			(enabled no)
			(sheetname "")
		)
		(fill yes
			(thermal_gap 0.5)
			(thermal_bridge_width 0.5)
			(island_removal_mode 0)
		)
		(polygon
			(pts
				(arc
					(start 192.310004 -273.816572)
					(mid 191.657224 -273.816572)
					(end 192.310004 -273.816572)
				)
			)
		)
	)
	(zone
		(layers "B.Cu" "In11.Cu" "In13.Cu" "In15.Cu")
		(hatch none 0.5)
		(connect_pads
			(clearance 0)
		)
		(min_thickness 0.25)
		(keepout
			(tracks not_allowed)
			(vias allowed)
			(pads allowed)
			(copperpour not_allowed)
			(footprints allowed)
		)
		(placement
			(enabled no)
			(sheetname "")
		)
		(fill yes
			(thermal_gap 0.5)
			(thermal_bridge_width 0.5)
			(island_removal_mode 0)
		)
		(polygon
			(pts
				(arc
					(start 127.473202 -231.714548)
					(mid 126.820422 -231.714548)
					(end 127.473202 -231.714548)
				)
			)
		)
	)
	(zone
		(layers "B.Cu" "In11.Cu" "In13.Cu" "In15.Cu")
		(hatch none 0.5)
		(connect_pads
			(clearance 0)
		)
		(min_thickness 0.25)
		(keepout
			(tracks not_allowed)
			(vias allowed)
			(pads allowed)
			(copperpour not_allowed)
			(footprints allowed)
		)
		(placement
			(enabled no)
			(sheetname "")
		)
		(fill yes
			(thermal_gap 0.5)
			(thermal_bridge_width 0.5)
			(island_removal_mode 0)
		)
		(polygon
			(pts
				(arc
					(start 97.039938 -268.569694)
					(mid 96.387158 -268.569694)
					(end 97.039938 -268.569694)
				)
			)
		)
	)
	(zone
		(layers "B.Cu" "In11.Cu" "In13.Cu" "In15.Cu")
		(hatch none 0.5)
		(connect_pads
			(clearance 0)
		)
		(min_thickness 0.25)
		(keepout
			(tracks not_allowed)
			(vias allowed)
			(pads allowed)
			(copperpour not_allowed)
			(footprints allowed)
		)
		(placement
			(enabled no)
			(sheetname "")
		)
		(fill yes
			(thermal_gap 0.5)
			(thermal_bridge_width 0.5)
			(island_removal_mode 0)
		)
		(polygon
			(pts
				(arc
					(start 353.222814 -50.207672)
					(mid 352.519234 -50.207672)
					(end 353.222814 -50.207672)
				)
			)
		)
	)
	(zone
		(layers "B.Cu" "In11.Cu" "In13.Cu" "In15.Cu")
		(hatch none 0.5)
		(connect_pads
			(clearance 0)
		)
		(min_thickness 0.25)
		(keepout
			(tracks not_allowed)
			(vias allowed)
			(pads allowed)
			(copperpour not_allowed)
			(footprints allowed)
		)
		(placement
			(enabled no)
			(sheetname "")
		)
		(fill yes
			(thermal_gap 0.5)
			(thermal_bridge_width 0.5)
			(island_removal_mode 0)
		)
		(polygon
			(pts
				(arc
					(start 376.823224 -243.922804)
					(mid 376.170444 -243.922804)
					(end 376.823224 -243.922804)
				)
			)
		)
	)
	(zone
		(layers "B.Cu" "In11.Cu" "In13.Cu" "In15.Cu")
		(hatch none 0.5)
		(connect_pads
			(clearance 0)
		)
		(min_thickness 0.25)
		(keepout
			(tracks not_allowed)
			(vias allowed)
			(pads allowed)
			(copperpour not_allowed)
			(footprints allowed)
		)
		(placement
			(enabled no)
			(sheetname "")
		)
		(fill yes
			(thermal_gap 0.5)
			(thermal_bridge_width 0.5)
			(island_removal_mode 0)
		)
		(polygon
			(pts
				(arc
					(start 97.039938 -262.058658)
					(mid 96.387158 -262.058658)
					(end 97.039938 -262.058658)
				)
			)
		)
	)
	(zone
		(layers "B.Cu" "In11.Cu" "In13.Cu" "In15.Cu")
		(hatch none 0.5)
		(connect_pads
			(clearance 0)
		)
		(min_thickness 0.25)
		(keepout
			(tracks not_allowed)
			(vias allowed)
			(pads allowed)
			(copperpour not_allowed)
			(footprints allowed)
		)
		(placement
			(enabled no)
			(sheetname "")
		)
		(fill yes
			(thermal_gap 0.5)
			(thermal_bridge_width 0.5)
			(island_removal_mode 0)
		)
		(polygon
			(pts
				(arc
					(start 32.203136 -299.316648)
					(mid 31.550356 -299.316648)
					(end 32.203136 -299.316648)
				)
			)
		)
	)
	(zone
		(layers "B.Cu" "In11.Cu" "In13.Cu" "In15.Cu")
		(hatch none 0.5)
		(connect_pads
			(clearance 0)
		)
		(min_thickness 0.25)
		(keepout
			(tracks not_allowed)
			(vias allowed)
			(pads allowed)
			(copperpour not_allowed)
			(footprints allowed)
		)
		(placement
			(enabled no)
			(sheetname "")
		)
		(fill yes
			(thermal_gap 0.5)
			(thermal_bridge_width 0.5)
			(island_removal_mode 0)
		)
		(polygon
			(pts
				(arc
					(start 352.465132 -69.10578)
					(mid 351.761552 -69.10578)
					(end 352.465132 -69.10578)
				)
			)
		)
	)
	(zone
		(layers "B.Cu" "In11.Cu" "In13.Cu" "In15.Cu")
		(hatch none 0.5)
		(connect_pads
			(clearance 0)
		)
		(min_thickness 0.25)
		(keepout
			(tracks not_allowed)
			(vias allowed)
			(pads allowed)
			(copperpour not_allowed)
			(footprints allowed)
		)
		(placement
			(enabled no)
			(sheetname "")
		)
		(fill yes
			(thermal_gap 0.5)
			(thermal_bridge_width 0.5)
			(island_removal_mode 0)
		)
		(polygon
			(pts
				(arc
					(start 249.500136 -5.1308)
					(mid 248.796556 -5.1308)
					(end 249.500136 -5.1308)
				)
			)
		)
	)
	(zone
		(layers "B.Cu" "In11.Cu" "In13.Cu" "In15.Cu")
		(hatch none 0.5)
		(connect_pads
			(clearance 0)
		)
		(min_thickness 0.25)
		(keepout
			(tracks not_allowed)
			(vias allowed)
			(pads allowed)
			(copperpour not_allowed)
			(footprints allowed)
		)
		(placement
			(enabled no)
			(sheetname "")
		)
		(fill yes
			(thermal_gap 0.5)
			(thermal_bridge_width 0.5)
			(island_removal_mode 0)
		)
		(polygon
			(pts
				(arc
					(start 265.055604 -244.066568)
					(mid 264.402824 -244.066568)
					(end 265.055604 -244.066568)
				)
			)
		)
	)
	(zone
		(layers "B.Cu" "In11.Cu" "In13.Cu" "In15.Cu")
		(hatch none 0.5)
		(connect_pads
			(clearance 0)
		)
		(min_thickness 0.25)
		(keepout
			(tracks not_allowed)
			(vias allowed)
			(pads allowed)
			(copperpour not_allowed)
			(footprints allowed)
		)
		(placement
			(enabled no)
			(sheetname "")
		)
		(fill yes
			(thermal_gap 0.5)
			(thermal_bridge_width 0.5)
			(island_removal_mode 0)
		)
		(polygon
			(pts
				(arc
					(start 353.798124 -213.732618)
					(mid 353.145344 -213.732618)
					(end 353.798124 -213.732618)
				)
			)
		)
	)
	(zone
		(layers "B.Cu" "In11.Cu" "In13.Cu" "In15.Cu")
		(hatch none 0.5)
		(connect_pads
			(clearance 0)
		)
		(min_thickness 0.25)
		(keepout
			(tracks not_allowed)
			(vias allowed)
			(pads allowed)
			(copperpour not_allowed)
			(footprints allowed)
		)
		(placement
			(enabled no)
			(sheetname "")
		)
		(fill yes
			(thermal_gap 0.5)
			(thermal_bridge_width 0.5)
			(island_removal_mode 0)
		)
		(polygon
			(pts
				(arc
					(start 284.243272 -298.466764)
					(mid 283.590492 -298.466764)
					(end 284.243272 -298.466764)
				)
			)
		)
	)
	(zone
		(layers "B.Cu" "In11.Cu" "In13.Cu" "In15.Cu")
		(hatch none 0.5)
		(connect_pads
			(clearance 0)
		)
		(min_thickness 0.25)
		(keepout
			(tracks not_allowed)
			(vias allowed)
			(pads allowed)
			(copperpour not_allowed)
			(footprints allowed)
		)
		(placement
			(enabled no)
			(sheetname "")
		)
		(fill yes
			(thermal_gap 0.5)
			(thermal_bridge_width 0.5)
			(island_removal_mode 0)
		)
		(polygon
			(pts
				(arc
					(start 153.154888 -431.889916)
					(mid 152.345136 -431.889916)
					(end 153.154888 -431.889916)
				)
			)
		)
	)
	(zone
		(layers "B.Cu" "In11.Cu" "In13.Cu" "In15.Cu")
		(hatch none 0.5)
		(connect_pads
			(clearance 0)
		)
		(min_thickness 0.25)
		(keepout
			(tracks not_allowed)
			(vias allowed)
			(pads allowed)
			(copperpour not_allowed)
			(footprints allowed)
		)
		(placement
			(enabled no)
			(sheetname "")
		)
		(fill yes
			(thermal_gap 0.5)
			(thermal_bridge_width 0.5)
			(island_removal_mode 0)
		)
		(polygon
			(pts
				(arc
					(start 97.03943 -260.430772)
					(mid 96.38665 -260.430772)
					(end 97.03943 -260.430772)
				)
			)
		)
	)
	(zone
		(layers "B.Cu" "In11.Cu" "In13.Cu" "In15.Cu")
		(hatch none 0.5)
		(connect_pads
			(clearance 0)
		)
		(min_thickness 0.25)
		(keepout
			(tracks not_allowed)
			(vias allowed)
			(pads allowed)
			(copperpour not_allowed)
			(footprints allowed)
		)
		(placement
			(enabled no)
			(sheetname "")
		)
		(fill yes
			(thermal_gap 0.5)
			(thermal_bridge_width 0.5)
			(island_removal_mode 0)
		)
		(polygon
			(pts
				(arc
					(start 344.870024 -243.922804)
					(mid 344.217244 -243.922804)
					(end 344.870024 -243.922804)
				)
			)
		)
	)
	(zone
		(layers "B.Cu" "In11.Cu" "In13.Cu" "In15.Cu")
		(hatch none 0.5)
		(connect_pads
			(clearance 0)
		)
		(min_thickness 0.25)
		(keepout
			(tracks not_allowed)
			(vias allowed)
			(pads allowed)
			(copperpour not_allowed)
			(footprints allowed)
		)
		(placement
			(enabled no)
			(sheetname "")
		)
		(fill yes
			(thermal_gap 0.5)
			(thermal_bridge_width 0.5)
			(island_removal_mode 0)
		)
		(polygon
			(pts
				(arc
					(start 280.143204 -282.316682)
					(mid 279.490424 -282.316682)
					(end 280.143204 -282.316682)
				)
			)
		)
	)
	(zone
		(layers "B.Cu" "In11.Cu" "In13.Cu" "In15.Cu")
		(hatch none 0.5)
		(connect_pads
			(clearance 0)
		)
		(min_thickness 0.25)
		(keepout
			(tracks not_allowed)
			(vias allowed)
			(pads allowed)
			(copperpour not_allowed)
			(footprints allowed)
		)
		(placement
			(enabled no)
			(sheetname "")
		)
		(fill yes
			(thermal_gap 0.5)
			(thermal_bridge_width 0.5)
			(island_removal_mode 0)
		)
		(polygon
			(pts
				(arc
					(start 284.243272 -201.56678)
					(mid 283.590492 -201.56678)
					(end 284.243272 -201.56678)
				)
			)
		)
	)
	(zone
		(layers "B.Cu" "In11.Cu" "In13.Cu" "In15.Cu")
		(hatch none 0.5)
		(connect_pads
			(clearance 0)
		)
		(min_thickness 0.25)
		(keepout
			(tracks not_allowed)
			(vias allowed)
			(pads allowed)
			(copperpour not_allowed)
			(footprints allowed)
		)
		(placement
			(enabled no)
			(sheetname "")
		)
		(fill yes
			(thermal_gap 0.5)
			(thermal_bridge_width 0.5)
			(island_removal_mode 0)
		)
		(polygon
			(pts
				(arc
					(start 118.544848 -214.622634)
					(mid 117.892068 -214.622634)
					(end 118.544848 -214.622634)
				)
			)
		)
	)
	(zone
		(layers "B.Cu" "In11.Cu" "In13.Cu" "In15.Cu")
		(hatch none 0.5)
		(connect_pads
			(clearance 0)
		)
		(min_thickness 0.25)
		(keepout
			(tracks not_allowed)
			(vias allowed)
			(pads allowed)
			(copperpour not_allowed)
			(footprints allowed)
		)
		(placement
			(enabled no)
			(sheetname "")
		)
		(fill yes
			(thermal_gap 0.5)
			(thermal_bridge_width 0.5)
			(island_removal_mode 0)
		)
		(polygon
			(pts
				(arc
					(start 355.207316 -214.622634)
					(mid 354.554536 -214.622634)
					(end 355.207316 -214.622634)
				)
			)
		)
	)
	(zone
		(layers "B.Cu" "In11.Cu" "In13.Cu" "In15.Cu")
		(hatch none 0.5)
		(connect_pads
			(clearance 0)
		)
		(min_thickness 0.25)
		(keepout
			(tracks not_allowed)
			(vias allowed)
			(pads allowed)
			(copperpour not_allowed)
			(footprints allowed)
		)
		(placement
			(enabled no)
			(sheetname "")
		)
		(fill yes
			(thermal_gap 0.5)
			(thermal_bridge_width 0.5)
			(island_removal_mode 0)
		)
		(polygon
			(pts
				(arc
					(start 124.184156 -248.806208)
					(mid 123.531376 -248.806208)
					(end 124.184156 -248.806208)
				)
			)
		)
	)
	(zone
		(layers "B.Cu" "In11.Cu" "In13.Cu" "In15.Cu")
		(hatch none 0.5)
		(connect_pads
			(clearance 0)
		)
		(min_thickness 0.25)
		(keepout
			(tracks not_allowed)
			(vias allowed)
			(pads allowed)
			(copperpour not_allowed)
			(footprints allowed)
		)
		(placement
			(enabled no)
			(sheetname "")
		)
		(fill yes
			(thermal_gap 0.5)
			(thermal_bridge_width 0.5)
			(island_removal_mode 0)
		)
		(polygon
			(pts
				(arc
					(start 69.05498 -428.28972)
					(mid 68.245228 -428.28972)
					(end 69.05498 -428.28972)
				)
			)
		)
	)
	(zone
		(layers "B.Cu" "In11.Cu" "In13.Cu" "In15.Cu")
		(hatch none 0.5)
		(connect_pads
			(clearance 0)
		)
		(min_thickness 0.25)
		(keepout
			(tracks not_allowed)
			(vias allowed)
			(pads allowed)
			(copperpour not_allowed)
			(footprints allowed)
		)
		(placement
			(enabled no)
			(sheetname "")
		)
		(fill yes
			(thermal_gap 0.5)
			(thermal_bridge_width 0.5)
			(island_removal_mode 0)
		)
		(polygon
			(pts
				(arc
					(start 36.303204 -276.366732)
					(mid 35.650424 -276.366732)
					(end 36.303204 -276.366732)
				)
			)
		)
	)
	(zone
		(layers "B.Cu" "In11.Cu" "In13.Cu" "In15.Cu")
		(hatch none 0.5)
		(connect_pads
			(clearance 0)
		)
		(min_thickness 0.25)
		(keepout
			(tracks not_allowed)
			(vias allowed)
			(pads allowed)
			(copperpour not_allowed)
			(footprints allowed)
		)
		(placement
			(enabled no)
			(sheetname "")
		)
		(fill yes
			(thermal_gap 0.5)
			(thermal_bridge_width 0.5)
			(island_removal_mode 0)
		)
		(polygon
			(pts
				(arc
					(start 406.81656 -410.030168)
					(mid 406.11298 -410.030168)
					(end 406.81656 -410.030168)
				)
			)
		)
	)
	(zone
		(layers "B.Cu" "In11.Cu" "In13.Cu" "In15.Cu")
		(hatch none 0.5)
		(connect_pads
			(clearance 0)
		)
		(min_thickness 0.25)
		(keepout
			(tracks not_allowed)
			(vias allowed)
			(pads allowed)
			(copperpour not_allowed)
			(footprints allowed)
		)
		(placement
			(enabled no)
			(sheetname "")
		)
		(fill yes
			(thermal_gap 0.5)
			(thermal_bridge_width 0.5)
			(island_removal_mode 0)
		)
		(polygon
			(pts
				(arc
					(start 89.521284 -279.964134)
					(mid 88.868504 -279.964134)
					(end 89.521284 -279.964134)
				)
			)
		)
	)
	(zone
		(layers "B.Cu" "In11.Cu" "In13.Cu" "In15.Cu")
		(hatch none 0.5)
		(connect_pads
			(clearance 0)
		)
		(min_thickness 0.25)
		(keepout
			(tracks not_allowed)
			(vias allowed)
			(pads allowed)
			(copperpour not_allowed)
			(footprints allowed)
		)
		(placement
			(enabled no)
			(sheetname "")
		)
		(fill yes
			(thermal_gap 0.5)
			(thermal_bridge_width 0.5)
			(island_removal_mode 0)
		)
		(polygon
			(pts
				(arc
					(start 98.809048 -214.622634)
					(mid 98.156268 -214.622634)
					(end 98.809048 -214.622634)
				)
			)
		)
	)
	(zone
		(layers "B.Cu" "In11.Cu" "In13.Cu" "In15.Cu")
		(hatch none 0.5)
		(connect_pads
			(clearance 0)
		)
		(min_thickness 0.25)
		(keepout
			(tracks not_allowed)
			(vias allowed)
			(pads allowed)
			(copperpour not_allowed)
			(footprints allowed)
		)
		(placement
			(enabled no)
			(sheetname "")
		)
		(fill yes
			(thermal_gap 0.5)
			(thermal_bridge_width 0.5)
			(island_removal_mode 0)
		)
		(polygon
			(pts
				(arc
					(start 135.461502 -214.546434)
					(mid 134.808722 -214.546434)
					(end 135.461502 -214.546434)
				)
			)
		)
	)
	(zone
		(layers "B.Cu" "In11.Cu" "In13.Cu" "In15.Cu")
		(hatch none 0.5)
		(connect_pads
			(clearance 0)
		)
		(min_thickness 0.25)
		(keepout
			(tracks not_allowed)
			(vias allowed)
			(pads allowed)
			(copperpour not_allowed)
			(footprints allowed)
		)
		(placement
			(enabled no)
			(sheetname "")
		)
		(fill yes
			(thermal_gap 0.5)
			(thermal_bridge_width 0.5)
			(island_removal_mode 0)
		)
		(polygon
			(pts
				(arc
					(start 329.701398 -403.883876)
					(mid 328.997818 -403.883876)
					(end 329.701398 -403.883876)
				)
			)
		)
	)
	(zone
		(layers "B.Cu" "In11.Cu" "In13.Cu" "In15.Cu")
		(hatch none 0.5)
		(connect_pads
			(clearance 0)
		)
		(min_thickness 0.25)
		(keepout
			(tracks not_allowed)
			(vias allowed)
			(pads allowed)
			(copperpour not_allowed)
			(footprints allowed)
		)
		(placement
			(enabled no)
			(sheetname "")
		)
		(fill yes
			(thermal_gap 0.5)
			(thermal_bridge_width 0.5)
			(island_removal_mode 0)
		)
		(polygon
			(pts
				(arc
					(start 96.100138 -258.80314)
					(mid 95.447358 -258.80314)
					(end 96.100138 -258.80314)
				)
			)
		)
	)
	(zone
		(layers "B.Cu" "In11.Cu" "In13.Cu" "In15.Cu")
		(hatch none 0.5)
		(connect_pads
			(clearance 0)
		)
		(min_thickness 0.25)
		(keepout
			(tracks not_allowed)
			(vias allowed)
			(pads allowed)
			(copperpour not_allowed)
			(footprints allowed)
		)
		(placement
			(enabled no)
			(sheetname "")
		)
		(fill yes
			(thermal_gap 0.5)
			(thermal_bridge_width 0.5)
			(island_removal_mode 0)
		)
		(polygon
			(pts
				(arc
					(start 71.054976 -427.289976)
					(mid 70.245224 -427.289976)
					(end 71.054976 -427.289976)
				)
			)
		)
	)
	(zone
		(layers "B.Cu" "In11.Cu" "In13.Cu" "In15.Cu")
		(hatch none 0.5)
		(connect_pads
			(clearance 0)
		)
		(min_thickness 0.25)
		(keepout
			(tracks not_allowed)
			(vias allowed)
			(pads allowed)
			(copperpour not_allowed)
			(footprints allowed)
		)
		(placement
			(enabled no)
			(sheetname "")
		)
		(fill yes
			(thermal_gap 0.5)
			(thermal_bridge_width 0.5)
			(island_removal_mode 0)
		)
		(polygon
			(pts
				(arc
					(start 73.054972 -427.089824)
					(mid 72.24522 -427.089824)
					(end 73.054972 -427.089824)
				)
			)
		)
	)
	(zone
		(layers "B.Cu" "In11.Cu" "In13.Cu" "In15.Cu")
		(hatch none 0.5)
		(connect_pads
			(clearance 0)
		)
		(min_thickness 0.25)
		(keepout
			(tracks not_allowed)
			(vias allowed)
			(pads allowed)
			(copperpour not_allowed)
			(footprints allowed)
		)
		(placement
			(enabled no)
			(sheetname "")
		)
		(fill yes
			(thermal_gap 0.5)
			(thermal_bridge_width 0.5)
			(island_removal_mode 0)
		)
		(polygon
			(pts
				(arc
					(start 192.310004 -231.316784)
					(mid 191.657224 -231.316784)
					(end 192.310004 -231.316784)
				)
			)
		)
	)
	(zone
		(layers "B.Cu" "In11.Cu" "In13.Cu" "In15.Cu")
		(hatch none 0.5)
		(connect_pads
			(clearance 0)
		)
		(min_thickness 0.25)
		(keepout
			(tracks not_allowed)
			(vias allowed)
			(pads allowed)
			(copperpour not_allowed)
			(footprints allowed)
		)
		(placement
			(enabled no)
			(sheetname "")
		)
		(fill yes
			(thermal_gap 0.5)
			(thermal_bridge_width 0.5)
			(island_removal_mode 0)
		)
		(polygon
			(pts
				(arc
					(start 455.337672 -309.51678)
					(mid 454.684892 -309.51678)
					(end 455.337672 -309.51678)
				)
			)
		)
	)
	(zone
		(layers "B.Cu" "In11.Cu" "In13.Cu" "In15.Cu")
		(hatch none 0.5)
		(connect_pads
			(clearance 0)
		)
		(min_thickness 0.25)
		(keepout
			(tracks not_allowed)
			(vias allowed)
			(pads allowed)
			(copperpour not_allowed)
			(footprints allowed)
		)
		(placement
			(enabled no)
			(sheetname "")
		)
		(fill yes
			(thermal_gap 0.5)
			(thermal_bridge_width 0.5)
			(island_removal_mode 0)
		)
		(polygon
			(pts
				(arc
					(start 138.032744 -410.030168)
					(mid 137.329164 -410.030168)
					(end 138.032744 -410.030168)
				)
			)
		)
	)
	(zone
		(layers "B.Cu" "In11.Cu" "In13.Cu" "In15.Cu")
		(hatch none 0.5)
		(connect_pads
			(clearance 0)
		)
		(min_thickness 0.25)
		(keepout
			(tracks not_allowed)
			(vias allowed)
			(pads allowed)
			(copperpour not_allowed)
			(footprints allowed)
		)
		(placement
			(enabled no)
			(sheetname "")
		)
		(fill yes
			(thermal_gap 0.5)
			(thermal_bridge_width 0.5)
			(island_removal_mode 0)
		)
		(polygon
			(pts
				(arc
					(start 52.741068 -410.030168)
					(mid 52.037488 -410.030168)
					(end 52.741068 -410.030168)
				)
			)
		)
	)
	(zone
		(layers "B.Cu" "In11.Cu" "In13.Cu" "In15.Cu")
		(hatch none 0.5)
		(connect_pads
			(clearance 0)
		)
		(min_thickness 0.25)
		(keepout
			(tracks not_allowed)
			(vias allowed)
			(pads allowed)
			(copperpour not_allowed)
			(footprints allowed)
		)
		(placement
			(enabled no)
			(sheetname "")
		)
		(fill yes
			(thermal_gap 0.5)
			(thermal_bridge_width 0.5)
			(island_removal_mode 0)
		)
		(polygon
			(pts
				(arc
					(start 126.643384 -272.639282)
					(mid 125.990604 -272.639282)
					(end 126.643384 -272.639282)
				)
			)
		)
	)
	(zone
		(layers "B.Cu" "In11.Cu" "In13.Cu" "In15.Cu")
		(hatch none 0.5)
		(connect_pads
			(clearance 0)
		)
		(min_thickness 0.25)
		(keepout
			(tracks not_allowed)
			(vias allowed)
			(pads allowed)
			(copperpour not_allowed)
			(footprints allowed)
		)
		(placement
			(enabled no)
			(sheetname "")
		)
		(fill yes
			(thermal_gap 0.5)
			(thermal_bridge_width 0.5)
			(island_removal_mode 0)
		)
		(polygon
			(pts
				(arc
					(start 356.147624 -227.64496)
					(mid 355.494844 -227.64496)
					(end 356.147624 -227.64496)
				)
			)
		)
	)
	(zone
		(layers "B.Cu" "In11.Cu" "In13.Cu" "In15.Cu")
		(hatch none 0.5)
		(connect_pads
			(clearance 0)
		)
		(min_thickness 0.25)
		(keepout
			(tracks not_allowed)
			(vias allowed)
			(pads allowed)
			(copperpour not_allowed)
			(footprints allowed)
		)
		(placement
			(enabled no)
			(sheetname "")
		)
		(fill yes
			(thermal_gap 0.5)
			(thermal_bridge_width 0.5)
			(island_removal_mode 0)
		)
		(polygon
			(pts
				(arc
					(start 124.916184 -410.030168)
					(mid 124.212604 -410.030168)
					(end 124.916184 -410.030168)
				)
			)
		)
	)
	(zone
		(layers "B.Cu" "In11.Cu" "In13.Cu" "In15.Cu")
		(hatch none 0.5)
		(connect_pads
			(clearance 0)
		)
		(min_thickness 0.25)
		(keepout
			(tracks not_allowed)
			(vias allowed)
			(pads allowed)
			(copperpour not_allowed)
			(footprints allowed)
		)
		(placement
			(enabled no)
			(sheetname "")
		)
		(fill yes
			(thermal_gap 0.5)
			(thermal_bridge_width 0.5)
			(island_removal_mode 0)
		)
		(polygon
			(pts
				(arc
					(start 347.217238 -403.883876)
					(mid 346.513658 -403.883876)
					(end 347.217238 -403.883876)
				)
			)
		)
	)
	(zone
		(layers "B.Cu" "In11.Cu" "In13.Cu" "In15.Cu")
		(hatch none 0.5)
		(connect_pads
			(clearance 0)
		)
		(min_thickness 0.25)
		(keepout
			(tracks not_allowed)
			(vias allowed)
			(pads allowed)
			(copperpour not_allowed)
			(footprints allowed)
		)
		(placement
			(enabled no)
			(sheetname "")
		)
		(fill yes
			(thermal_gap 0.5)
			(thermal_bridge_width 0.5)
			(island_removal_mode 0)
		)
		(polygon
			(pts
				(arc
					(start 84.05495 -433.289964)
					(mid 83.245198 -433.289964)
					(end 84.05495 -433.289964)
				)
			)
		)
	)
	(zone
		(layers "B.Cu" "In11.Cu" "In13.Cu" "In15.Cu")
		(hatch none 0.5)
		(connect_pads
			(clearance 0)
		)
		(min_thickness 0.25)
		(keepout
			(tracks not_allowed)
			(vias allowed)
			(pads allowed)
			(copperpour not_allowed)
			(footprints allowed)
		)
		(placement
			(enabled no)
			(sheetname "")
		)
		(fill yes
			(thermal_gap 0.5)
			(thermal_bridge_width 0.5)
			(island_removal_mode 0)
		)
		(polygon
			(pts
				(arc
					(start 409.154884 -439.0898)
					(mid 408.345132 -439.0898)
					(end 409.154884 -439.0898)
				)
			)
		)
	)
	(zone
		(layers "B.Cu" "In11.Cu" "In13.Cu" "In15.Cu")
		(hatch none 0.5)
		(connect_pads
			(clearance 0)
		)
		(min_thickness 0.25)
		(keepout
			(tracks not_allowed)
			(vias allowed)
			(pads allowed)
			(copperpour not_allowed)
			(footprints allowed)
		)
		(placement
			(enabled no)
			(sheetname "")
		)
		(fill yes
			(thermal_gap 0.5)
			(thermal_bridge_width 0.5)
			(island_removal_mode 0)
		)
		(polygon
			(pts
				(arc
					(start 344.980006 -258.80314)
					(mid 344.327226 -258.80314)
					(end 344.980006 -258.80314)
				)
			)
		)
	)
	(zone
		(layers "B.Cu" "In11.Cu" "In13.Cu" "In15.Cu")
		(hatch none 0.5)
		(connect_pads
			(clearance 0)
		)
		(min_thickness 0.25)
		(keepout
			(tracks not_allowed)
			(vias allowed)
			(pads allowed)
			(copperpour not_allowed)
			(footprints allowed)
		)
		(placement
			(enabled no)
			(sheetname "")
		)
		(fill yes
			(thermal_gap 0.5)
			(thermal_bridge_width 0.5)
			(island_removal_mode 0)
		)
		(polygon
			(pts
				(arc
					(start 97.399602 -236.597952)
					(mid 96.746822 -236.597952)
					(end 97.399602 -236.597952)
				)
			)
		)
	)
	(zone
		(layers "B.Cu" "In11.Cu" "In13.Cu" "In15.Cu")
		(hatch none 0.5)
		(connect_pads
			(clearance 0)
		)
		(min_thickness 0.25)
		(keepout
			(tracks not_allowed)
			(vias allowed)
			(pads allowed)
			(copperpour not_allowed)
			(footprints allowed)
		)
		(placement
			(enabled no)
			(sheetname "")
		)
		(fill yes
			(thermal_gap 0.5)
			(thermal_bridge_width 0.5)
			(island_removal_mode 0)
		)
		(polygon
			(pts
				(arc
					(start 203.297536 -312.91657)
					(mid 202.644756 -312.91657)
					(end 203.297536 -312.91657)
				)
			)
		)
	)
	(zone
		(layers "B.Cu" "In11.Cu" "In13.Cu" "In15.Cu")
		(hatch none 0.5)
		(connect_pads
			(clearance 0)
		)
		(min_thickness 0.25)
		(keepout
			(tracks not_allowed)
			(vias allowed)
			(pads allowed)
			(copperpour not_allowed)
			(footprints allowed)
		)
		(placement
			(enabled no)
			(sheetname "")
		)
		(fill yes
			(thermal_gap 0.5)
			(thermal_bridge_width 0.5)
			(island_removal_mode 0)
		)
		(polygon
			(pts
				(arc
					(start 371.398546 -169.390568)
					(mid 370.694966 -169.390568)
					(end 371.398546 -169.390568)
				)
			)
		)
	)
	(zone
		(layers "B.Cu" "In11.Cu" "In13.Cu" "In15.Cu")
		(hatch none 0.5)
		(connect_pads
			(clearance 0)
		)
		(min_thickness 0.25)
		(keepout
			(tracks not_allowed)
			(vias allowed)
			(pads allowed)
			(copperpour not_allowed)
			(footprints allowed)
		)
		(placement
			(enabled no)
			(sheetname "")
		)
		(fill yes
			(thermal_gap 0.5)
			(thermal_bridge_width 0.5)
			(island_removal_mode 0)
		)
		(polygon
			(pts
				(arc
					(start 109.726984 -277.522432)
					(mid 109.074204 -277.522432)
					(end 109.726984 -277.522432)
				)
			)
		)
	)
	(zone
		(layers "B.Cu" "In11.Cu" "In13.Cu" "In15.Cu")
		(hatch none 0.5)
		(connect_pads
			(clearance 0)
		)
		(min_thickness 0.25)
		(keepout
			(tracks not_allowed)
			(vias allowed)
			(pads allowed)
			(copperpour not_allowed)
			(footprints allowed)
		)
		(placement
			(enabled no)
			(sheetname "")
		)
		(fill yes
			(thermal_gap 0.5)
			(thermal_bridge_width 0.5)
			(island_removal_mode 0)
		)
		(polygon
			(pts
				(arc
					(start 392.154918 -439.0898)
					(mid 391.345166 -439.0898)
					(end 392.154918 -439.0898)
				)
			)
		)
	)
	(zone
		(layers "B.Cu" "In11.Cu" "In13.Cu" "In15.Cu")
		(hatch none 0.5)
		(connect_pads
			(clearance 0)
		)
		(min_thickness 0.25)
		(keepout
			(tracks not_allowed)
			(vias allowed)
			(pads allowed)
			(copperpour not_allowed)
			(footprints allowed)
		)
		(placement
			(enabled no)
			(sheetname "")
		)
		(fill yes
			(thermal_gap 0.5)
			(thermal_bridge_width 0.5)
			(island_removal_mode 0)
		)
		(polygon
			(pts
				(arc
					(start 192.310004 -306.116736)
					(mid 191.657224 -306.116736)
					(end 192.310004 -306.116736)
				)
			)
		)
	)
	(zone
		(layers "B.Cu" "In11.Cu" "In13.Cu" "In15.Cu")
		(hatch none 0.5)
		(connect_pads
			(clearance 0)
		)
		(min_thickness 0.25)
		(keepout
			(tracks not_allowed)
			(vias allowed)
			(pads allowed)
			(copperpour not_allowed)
			(footprints allowed)
		)
		(placement
			(enabled no)
			(sheetname "")
		)
		(fill yes
			(thermal_gap 0.5)
			(thermal_bridge_width 0.5)
			(island_removal_mode 0)
		)
		(polygon
			(pts
				(arc
					(start 134.991602 -215.436704)
					(mid 134.338822 -215.436704)
					(end 134.991602 -215.436704)
				)
			)
		)
	)
	(zone
		(layers "B.Cu" "In11.Cu" "In13.Cu" "In15.Cu")
		(hatch none 0.5)
		(connect_pads
			(clearance 0)
		)
		(min_thickness 0.25)
		(keepout
			(tracks not_allowed)
			(vias allowed)
			(pads allowed)
			(copperpour not_allowed)
			(footprints allowed)
		)
		(placement
			(enabled no)
			(sheetname "")
		)
		(fill yes
			(thermal_gap 0.5)
			(thermal_bridge_width 0.5)
			(island_removal_mode 0)
		)
		(polygon
			(pts
				(arc
					(start 375.053606 -266.941808)
					(mid 374.400826 -266.941808)
					(end 375.053606 -266.941808)
				)
			)
		)
	)
	(zone
		(layers "B.Cu" "In11.Cu" "In13.Cu" "In15.Cu")
		(hatch none 0.5)
		(connect_pads
			(clearance 0)
		)
		(min_thickness 0.25)
		(keepout
			(tracks not_allowed)
			(vias allowed)
			(pads allowed)
			(copperpour not_allowed)
			(footprints allowed)
		)
		(placement
			(enabled no)
			(sheetname "")
		)
		(fill yes
			(thermal_gap 0.5)
			(thermal_bridge_width 0.5)
			(island_removal_mode 0)
		)
		(polygon
			(pts
				(arc
					(start 61.054996 -435.489858)
					(mid 60.245244 -435.489858)
					(end 61.054996 -435.489858)
				)
			)
		)
	)
	(zone
		(layers "B.Cu" "In11.Cu" "In13.Cu" "In15.Cu")
		(hatch none 0.5)
		(connect_pads
			(clearance 0)
		)
		(min_thickness 0.25)
		(keepout
			(tracks not_allowed)
			(vias allowed)
			(pads allowed)
			(copperpour not_allowed)
			(footprints allowed)
		)
		(placement
			(enabled no)
			(sheetname "")
		)
		(fill yes
			(thermal_gap 0.5)
			(thermal_bridge_width 0.5)
			(island_removal_mode 0)
		)
		(polygon
			(pts
				(arc
					(start 111.026956 -214.546434)
					(mid 110.374176 -214.546434)
					(end 111.026956 -214.546434)
				)
			)
		)
	)
	(zone
		(layers "B.Cu" "In11.Cu" "In13.Cu" "In15.Cu")
		(hatch none 0.5)
		(connect_pads
			(clearance 0)
		)
		(min_thickness 0.25)
		(keepout
			(tracks not_allowed)
			(vias allowed)
			(pads allowed)
			(copperpour not_allowed)
			(footprints allowed)
		)
		(placement
			(enabled no)
			(sheetname "")
		)
		(fill yes
			(thermal_gap 0.5)
			(thermal_bridge_width 0.5)
			(island_removal_mode 0)
		)
		(polygon
			(pts
				(arc
					(start 343.930224 -232.528364)
					(mid 343.277444 -232.528364)
					(end 343.930224 -232.528364)
				)
			)
		)
	)
	(zone
		(layers "B.Cu" "In11.Cu" "In13.Cu" "In15.Cu")
		(hatch none 0.5)
		(connect_pads
			(clearance 0)
		)
		(min_thickness 0.25)
		(keepout
			(tracks not_allowed)
			(vias allowed)
			(pads allowed)
			(copperpour not_allowed)
			(footprints allowed)
		)
		(placement
			(enabled no)
			(sheetname "")
		)
		(fill yes
			(thermal_gap 0.5)
			(thermal_bridge_width 0.5)
			(island_removal_mode 0)
		)
		(polygon
			(pts
				(arc
					(start 257.511804 -244.066568)
					(mid 256.859024 -244.066568)
					(end 257.511804 -244.066568)
				)
			)
		)
	)
	(zone
		(layers "B.Cu" "In11.Cu" "In13.Cu" "In15.Cu")
		(hatch none 0.5)
		(connect_pads
			(clearance 0)
		)
		(min_thickness 0.25)
		(keepout
			(tracks not_allowed)
			(vias allowed)
			(pads allowed)
			(copperpour not_allowed)
			(footprints allowed)
		)
		(placement
			(enabled no)
			(sheetname "")
		)
		(fill yes
			(thermal_gap 0.5)
			(thermal_bridge_width 0.5)
			(island_removal_mode 0)
		)
		(polygon
			(pts
				(arc
					(start 17.115536 -244.066568)
					(mid 16.462756 -244.066568)
					(end 17.115536 -244.066568)
				)
			)
		)
	)
	(zone
		(layers "B.Cu" "In11.Cu" "In13.Cu" "In15.Cu")
		(hatch none 0.5)
		(connect_pads
			(clearance 0)
		)
		(min_thickness 0.25)
		(keepout
			(tracks not_allowed)
			(vias allowed)
			(pads allowed)
			(copperpour not_allowed)
			(footprints allowed)
		)
		(placement
			(enabled no)
			(sheetname "")
		)
		(fill yes
			(thermal_gap 0.5)
			(thermal_bridge_width 0.5)
			(island_removal_mode 0)
		)
		(polygon
			(pts
				(arc
					(start 341.690706 -282.405836)
					(mid 341.037926 -282.405836)
					(end 341.690706 -282.405836)
				)
			)
		)
	)
	(zone
		(layers "B.Cu" "In11.Cu" "In13.Cu" "In15.Cu")
		(hatch none 0.5)
		(connect_pads
			(clearance 0)
		)
		(min_thickness 0.25)
		(keepout
			(tracks not_allowed)
			(vias allowed)
			(pads allowed)
			(copperpour not_allowed)
			(footprints allowed)
		)
		(placement
			(enabled no)
			(sheetname "")
		)
		(fill yes
			(thermal_gap 0.5)
			(thermal_bridge_width 0.5)
			(island_removal_mode 0)
		)
		(polygon
			(pts
				(arc
					(start 345.919806 -265.314176)
					(mid 345.267026 -265.314176)
					(end 345.919806 -265.314176)
				)
			)
		)
	)
	(zone
		(layers "B.Cu" "In11.Cu" "In13.Cu" "In15.Cu")
		(hatch none 0.5)
		(connect_pads
			(clearance 0)
		)
		(min_thickness 0.25)
		(keepout
			(tracks not_allowed)
			(vias allowed)
			(pads allowed)
			(copperpour not_allowed)
			(footprints allowed)
		)
		(placement
			(enabled no)
			(sheetname "")
		)
		(fill yes
			(thermal_gap 0.5)
			(thermal_bridge_width 0.5)
			(island_removal_mode 0)
		)
		(polygon
			(pts
				(arc
					(start 411.15488 -436.889906)
					(mid 410.345128 -436.889906)
					(end 411.15488 -436.889906)
				)
			)
		)
	)
	(zone
		(layers "B.Cu" "In11.Cu" "In13.Cu" "In15.Cu")
		(hatch none 0.5)
		(connect_pads
			(clearance 0)
		)
		(min_thickness 0.25)
		(keepout
			(tracks not_allowed)
			(vias allowed)
			(pads allowed)
			(copperpour not_allowed)
			(footprints allowed)
		)
		(placement
			(enabled no)
			(sheetname "")
		)
		(fill yes
			(thermal_gap 0.5)
			(thermal_bridge_width 0.5)
			(island_removal_mode 0)
		)
		(polygon
			(pts
				(arc
					(start 106.797602 -215.436704)
					(mid 106.144822 -215.436704)
					(end 106.797602 -215.436704)
				)
			)
		)
	)
	(zone
		(layers "B.Cu" "In11.Cu" "In13.Cu" "In15.Cu")
		(hatch none 0.5)
		(connect_pads
			(clearance 0)
		)
		(min_thickness 0.25)
		(keepout
			(tracks not_allowed)
			(vias allowed)
			(pads allowed)
			(copperpour not_allowed)
			(footprints allowed)
		)
		(placement
			(enabled no)
			(sheetname "")
		)
		(fill yes
			(thermal_gap 0.5)
			(thermal_bridge_width 0.5)
			(island_removal_mode 0)
		)
		(polygon
			(pts
				(arc
					(start 327.054972 -426.089826)
					(mid 326.24522 -426.089826)
					(end 327.054972 -426.089826)
				)
			)
		)
	)
	(zone
		(layers "B.Cu" "In11.Cu" "In13.Cu" "In15.Cu")
		(hatch none 0.5)
		(connect_pads
			(clearance 0)
		)
		(min_thickness 0.25)
		(keepout
			(tracks not_allowed)
			(vias allowed)
			(pads allowed)
			(copperpour not_allowed)
			(footprints allowed)
		)
		(placement
			(enabled no)
			(sheetname "")
		)
		(fill yes
			(thermal_gap 0.5)
			(thermal_bridge_width 0.5)
			(island_removal_mode 0)
		)
		(polygon
			(pts
				(arc
					(start 308.258718 -403.883876)
					(mid 307.555138 -403.883876)
					(end 308.258718 -403.883876)
				)
			)
		)
	)
	(zone
		(layers "B.Cu" "In11.Cu" "In13.Cu" "In15.Cu")
		(hatch none 0.5)
		(connect_pads
			(clearance 0)
		)
		(min_thickness 0.25)
		(keepout
			(tracks not_allowed)
			(vias allowed)
			(pads allowed)
			(copperpour not_allowed)
			(footprints allowed)
		)
		(placement
			(enabled no)
			(sheetname "")
		)
		(fill yes
			(thermal_gap 0.5)
			(thermal_bridge_width 0.5)
			(island_removal_mode 0)
		)
		(polygon
			(pts
				(arc
					(start 343.930224 -229.272846)
					(mid 343.277444 -229.272846)
					(end 343.930224 -229.272846)
				)
			)
		)
	)
	(zone
		(layers "B.Cu" "In11.Cu" "In13.Cu" "In15.Cu")
		(hatch none 0.5)
		(connect_pads
			(clearance 0)
		)
		(min_thickness 0.25)
		(keepout
			(tracks not_allowed)
			(vias allowed)
			(pads allowed)
			(copperpour not_allowed)
			(footprints allowed)
		)
		(placement
			(enabled no)
			(sheetname "")
		)
		(fill yes
			(thermal_gap 0.5)
			(thermal_bridge_width 0.5)
			(island_removal_mode 0)
		)
		(polygon
			(pts
				(arc
					(start 394.5636 -410.030168)
					(mid 393.86002 -410.030168)
					(end 394.5636 -410.030168)
				)
			)
		)
	)
	(zone
		(layers "B.Cu" "In11.Cu" "In13.Cu" "In15.Cu")
		(hatch none 0.5)
		(connect_pads
			(clearance 0)
		)
		(min_thickness 0.25)
		(keepout
			(tracks not_allowed)
			(vias allowed)
			(pads allowed)
			(copperpour not_allowed)
			(footprints allowed)
		)
		(placement
			(enabled no)
			(sheetname "")
		)
		(fill yes
			(thermal_gap 0.5)
			(thermal_bridge_width 0.5)
			(island_removal_mode 0)
		)
		(polygon
			(pts
				(arc
					(start 261.611872 -244.916706)
					(mid 260.959092 -244.916706)
					(end 261.611872 -244.916706)
				)
			)
		)
	)
	(zone
		(layers "B.Cu" "In11.Cu" "In13.Cu" "In15.Cu")
		(hatch none 0.5)
		(connect_pads
			(clearance 0)
		)
		(min_thickness 0.25)
		(keepout
			(tracks not_allowed)
			(vias allowed)
			(pads allowed)
			(copperpour not_allowed)
			(footprints allowed)
		)
		(placement
			(enabled no)
			(sheetname "")
		)
		(fill yes
			(thermal_gap 0.5)
			(thermal_bridge_width 0.5)
			(island_removal_mode 0)
		)
		(polygon
			(pts
				(arc
					(start 207.397604 -309.51678)
					(mid 206.744824 -309.51678)
					(end 207.397604 -309.51678)
				)
			)
		)
	)
	(zone
		(layers "B.Cu" "In11.Cu" "In13.Cu" "In15.Cu")
		(hatch none 0.5)
		(connect_pads
			(clearance 0)
		)
		(min_thickness 0.25)
		(keepout
			(tracks not_allowed)
			(vias allowed)
			(pads allowed)
			(copperpour not_allowed)
			(footprints allowed)
		)
		(placement
			(enabled no)
			(sheetname "")
		)
		(fill yes
			(thermal_gap 0.5)
			(thermal_bridge_width 0.5)
			(island_removal_mode 0)
		)
		(polygon
			(pts
				(arc
					(start 97.039938 -257.175254)
					(mid 96.387158 -257.175254)
					(end 97.039938 -257.175254)
				)
			)
		)
	)
	(zone
		(layers "B.Cu" "In11.Cu" "In13.Cu" "In15.Cu")
		(hatch none 0.5)
		(connect_pads
			(clearance 0)
		)
		(min_thickness 0.25)
		(keepout
			(tracks not_allowed)
			(vias allowed)
			(pads allowed)
			(copperpour not_allowed)
			(footprints allowed)
		)
		(placement
			(enabled no)
			(sheetname "")
		)
		(fill yes
			(thermal_gap 0.5)
			(thermal_bridge_width 0.5)
			(island_removal_mode 0)
		)
		(polygon
			(pts
				(arc
					(start 17.115536 -243.216684)
					(mid 16.462756 -243.216684)
					(end 17.115536 -243.216684)
				)
			)
		)
	)
	(zone
		(layers "B.Cu" "In11.Cu" "In13.Cu" "In15.Cu")
		(hatch none 0.5)
		(connect_pads
			(clearance 0)
		)
		(min_thickness 0.25)
		(keepout
			(tracks not_allowed)
			(vias allowed)
			(pads allowed)
			(copperpour not_allowed)
			(footprints allowed)
		)
		(placement
			(enabled no)
			(sheetname "")
		)
		(fill yes
			(thermal_gap 0.5)
			(thermal_bridge_width 0.5)
			(island_removal_mode 0)
		)
		(polygon
			(pts
				(arc
					(start 126.154942 -438.089802)
					(mid 125.34519 -438.089802)
					(end 126.154942 -438.089802)
				)
			)
		)
	)
	(zone
		(layers "B.Cu" "In11.Cu" "In13.Cu" "In15.Cu")
		(hatch none 0.5)
		(connect_pads
			(clearance 0)
		)
		(min_thickness 0.25)
		(keepout
			(tracks not_allowed)
			(vias allowed)
			(pads allowed)
			(copperpour not_allowed)
			(footprints allowed)
		)
		(placement
			(enabled no)
			(sheetname "")
		)
		(fill yes
			(thermal_gap 0.5)
			(thermal_bridge_width 0.5)
			(island_removal_mode 0)
		)
		(polygon
			(pts
				(arc
					(start 95.520002 -228.45903)
					(mid 94.867222 -228.45903)
					(end 95.520002 -228.45903)
				)
			)
		)
	)
	(zone
		(layers "B.Cu" "In11.Cu" "In13.Cu" "In15.Cu")
		(hatch none 0.5)
		(connect_pads
			(clearance 0)
		)
		(min_thickness 0.25)
		(keepout
			(tracks not_allowed)
			(vias allowed)
			(pads allowed)
			(copperpour not_allowed)
			(footprints allowed)
		)
		(placement
			(enabled no)
			(sheetname "")
		)
		(fill yes
			(thermal_gap 0.5)
			(thermal_bridge_width 0.5)
			(island_removal_mode 0)
		)
		(polygon
			(pts
				(arc
					(start 323.05498 -433.289964)
					(mid 322.245228 -433.289964)
					(end 323.05498 -433.289964)
				)
			)
		)
	)
	(zone
		(layers "B.Cu" "In11.Cu" "In13.Cu" "In15.Cu")
		(hatch none 0.5)
		(connect_pads
			(clearance 0)
		)
		(min_thickness 0.25)
		(keepout
			(tracks not_allowed)
			(vias allowed)
			(pads allowed)
			(copperpour not_allowed)
			(footprints allowed)
		)
		(placement
			(enabled no)
			(sheetname "")
		)
		(fill yes
			(thermal_gap 0.5)
			(thermal_bridge_width 0.5)
			(island_removal_mode 0)
		)
		(polygon
			(pts
				(arc
					(start 159.475424 -410.030168)
					(mid 158.771844 -410.030168)
					(end 159.475424 -410.030168)
				)
			)
		)
	)
	(zone
		(layers "B.Cu" "In11.Cu" "In13.Cu" "In15.Cu")
		(hatch none 0.5)
		(connect_pads
			(clearance 0)
		)
		(min_thickness 0.25)
		(keepout
			(tracks not_allowed)
			(vias allowed)
			(pads allowed)
			(copperpour not_allowed)
			(footprints allowed)
		)
		(placement
			(enabled no)
			(sheetname "")
		)
		(fill yes
			(thermal_gap 0.5)
			(thermal_bridge_width 0.5)
			(island_removal_mode 0)
		)
		(polygon
			(pts
				(arc
					(start 97.509584 -274.266914)
					(mid 96.856804 -274.266914)
					(end 97.509584 -274.266914)
				)
			)
		)
	)
	(zone
		(layers "B.Cu" "In11.Cu" "In13.Cu" "In15.Cu")
		(hatch none 0.5)
		(connect_pads
			(clearance 0)
		)
		(min_thickness 0.25)
		(keepout
			(tracks not_allowed)
			(vias allowed)
			(pads allowed)
			(copperpour not_allowed)
			(footprints allowed)
		)
		(placement
			(enabled no)
			(sheetname "")
		)
		(fill yes
			(thermal_gap 0.5)
			(thermal_bridge_width 0.5)
			(island_removal_mode 0)
		)
		(polygon
			(pts
				(arc
					(start 95.160338 -265.314176)
					(mid 94.507558 -265.314176)
					(end 95.160338 -265.314176)
				)
			)
		)
	)
	(zone
		(layers "B.Cu" "In11.Cu" "In13.Cu" "In15.Cu")
		(hatch none 0.5)
		(connect_pads
			(clearance 0)
		)
		(min_thickness 0.25)
		(keepout
			(tracks not_allowed)
			(vias allowed)
			(pads allowed)
			(copperpour not_allowed)
			(footprints allowed)
		)
		(placement
			(enabled no)
			(sheetname "")
		)
		(fill yes
			(thermal_gap 0.5)
			(thermal_bridge_width 0.5)
			(island_removal_mode 0)
		)
		(polygon
			(pts
				(arc
					(start 59.055 -434.48986)
					(mid 58.245248 -434.48986)
					(end 59.055 -434.48986)
				)
			)
		)
	)
	(zone
		(layers "B.Cu" "In11.Cu" "In13.Cu" "In15.Cu")
		(hatch none 0.5)
		(connect_pads
			(clearance 0)
		)
		(min_thickness 0.25)
		(keepout
			(tracks not_allowed)
			(vias allowed)
			(pads allowed)
			(copperpour not_allowed)
			(footprints allowed)
		)
		(placement
			(enabled no)
			(sheetname "")
		)
		(fill yes
			(thermal_gap 0.5)
			(thermal_bridge_width 0.5)
			(island_removal_mode 0)
		)
		(polygon
			(pts
				(arc
					(start 128.992884 -253.919736)
					(mid 128.340104 -253.919736)
					(end 128.992884 -253.919736)
				)
			)
		)
	)
	(zone
		(layers "B.Cu" "In11.Cu" "In13.Cu" "In15.Cu")
		(hatch none 0.5)
		(connect_pads
			(clearance 0)
		)
		(min_thickness 0.25)
		(keepout
			(tracks not_allowed)
			(vias allowed)
			(pads allowed)
			(copperpour not_allowed)
			(footprints allowed)
		)
		(placement
			(enabled no)
			(sheetname "")
		)
		(fill yes
			(thermal_gap 0.5)
			(thermal_bridge_width 0.5)
			(island_removal_mode 0)
		)
		(polygon
			(pts
				(arc
					(start 344.980006 -265.314176)
					(mid 344.327226 -265.314176)
					(end 344.980006 -265.314176)
				)
			)
		)
	)
	(zone
		(layers "B.Cu" "In11.Cu" "In13.Cu" "In15.Cu")
		(hatch none 0.5)
		(connect_pads
			(clearance 0)
		)
		(min_thickness 0.25)
		(keepout
			(tracks not_allowed)
			(vias allowed)
			(pads allowed)
			(copperpour not_allowed)
			(footprints allowed)
		)
		(placement
			(enabled no)
			(sheetname "")
		)
		(fill yes
			(thermal_gap 0.5)
			(thermal_bridge_width 0.5)
			(island_removal_mode 0)
		)
		(polygon
			(pts
				(arc
					(start 105.498138 -276.708616)
					(mid 104.845358 -276.708616)
					(end 105.498138 -276.708616)
				)
			)
		)
	)
	(zone
		(layers "B.Cu" "In11.Cu" "In13.Cu" "In15.Cu")
		(hatch none 0.5)
		(connect_pads
			(clearance 0)
		)
		(min_thickness 0.25)
		(keepout
			(tracks not_allowed)
			(vias allowed)
			(pads allowed)
			(copperpour not_allowed)
			(footprints allowed)
		)
		(placement
			(enabled no)
			(sheetname "")
		)
		(fill yes
			(thermal_gap 0.5)
			(thermal_bridge_width 0.5)
			(island_removal_mode 0)
		)
		(polygon
			(pts
				(arc
					(start 117.605048 -214.622634)
					(mid 116.952268 -214.622634)
					(end 117.605048 -214.622634)
				)
			)
		)
	)
	(zone
		(layers "B.Cu" "In11.Cu" "In13.Cu" "In15.Cu")
		(hatch none 0.5)
		(connect_pads
			(clearance 0)
		)
		(min_thickness 0.25)
		(keepout
			(tracks not_allowed)
			(vias allowed)
			(pads allowed)
			(copperpour not_allowed)
			(footprints allowed)
		)
		(placement
			(enabled no)
			(sheetname "")
		)
		(fill yes
			(thermal_gap 0.5)
			(thermal_bridge_width 0.5)
			(island_removal_mode 0)
		)
		(polygon
			(pts
				(arc
					(start 284.243272 -229.616762)
					(mid 283.590492 -229.616762)
					(end 284.243272 -229.616762)
				)
			)
		)
	)
	(zone
		(layers "B.Cu" "In11.Cu" "In13.Cu" "In15.Cu")
		(hatch none 0.5)
		(connect_pads
			(clearance 0)
		)
		(min_thickness 0.25)
		(keepout
			(tracks not_allowed)
			(vias allowed)
			(pads allowed)
			(copperpour not_allowed)
			(footprints allowed)
		)
		(placement
			(enabled no)
			(sheetname "")
		)
		(fill yes
			(thermal_gap 0.5)
			(thermal_bridge_width 0.5)
			(island_removal_mode 0)
		)
		(polygon
			(pts
				(arc
					(start 80.054958 -427.289976)
					(mid 79.245206 -427.289976)
					(end 80.054958 -427.289976)
				)
			)
		)
	)
	(zone
		(layers "B.Cu" "In11.Cu" "In13.Cu" "In15.Cu")
		(hatch none 0.5)
		(connect_pads
			(clearance 0)
		)
		(min_thickness 0.25)
		(keepout
			(tracks not_allowed)
			(vias allowed)
			(pads allowed)
			(copperpour not_allowed)
			(footprints allowed)
		)
		(placement
			(enabled no)
			(sheetname "")
		)
		(fill yes
			(thermal_gap 0.5)
			(thermal_bridge_width 0.5)
			(island_removal_mode 0)
		)
		(polygon
			(pts
				(arc
					(start 64.994028 -410.030168)
					(mid 64.290448 -410.030168)
					(end 64.994028 -410.030168)
				)
			)
		)
	)
	(zone
		(layers "B.Cu" "In11.Cu" "In13.Cu" "In15.Cu")
		(hatch none 0.5)
		(connect_pads
			(clearance 0)
		)
		(min_thickness 0.25)
		(keepout
			(tracks not_allowed)
			(vias allowed)
			(pads allowed)
			(copperpour not_allowed)
			(footprints allowed)
		)
		(placement
			(enabled no)
			(sheetname "")
		)
		(fill yes
			(thermal_gap 0.5)
			(thermal_bridge_width 0.5)
			(island_removal_mode 0)
		)
		(polygon
			(pts
				(arc
					(start 388.154926 -439.0898)
					(mid 387.345174 -439.0898)
					(end 388.154926 -439.0898)
				)
			)
		)
	)
	(zone
		(layers "B.Cu" "In11.Cu" "In13.Cu" "In15.Cu")
		(hatch none 0.5)
		(connect_pads
			(clearance 0)
		)
		(min_thickness 0.25)
		(keepout
			(tracks not_allowed)
			(vias allowed)
			(pads allowed)
			(copperpour not_allowed)
			(footprints allowed)
		)
		(placement
			(enabled no)
			(sheetname "")
		)
		(fill yes
			(thermal_gap 0.5)
			(thermal_bridge_width 0.5)
			(island_removal_mode 0)
		)
		(polygon
			(pts
				(arc
					(start 96.929956 -229.272846)
					(mid 96.277176 -229.272846)
					(end 96.929956 -229.272846)
				)
			)
		)
	)
	(zone
		(layers "B.Cu" "In11.Cu" "In13.Cu" "In15.Cu")
		(hatch none 0.5)
		(connect_pads
			(clearance 0)
		)
		(min_thickness 0.25)
		(keepout
			(tracks not_allowed)
			(vias allowed)
			(pads allowed)
			(copperpour not_allowed)
			(footprints allowed)
		)
		(placement
			(enabled no)
			(sheetname "")
		)
		(fill yes
			(thermal_gap 0.5)
			(thermal_bridge_width 0.5)
			(island_removal_mode 0)
		)
		(polygon
			(pts
				(arc
					(start 357.55707 -226.831144)
					(mid 356.90429 -226.831144)
					(end 357.55707 -226.831144)
				)
			)
		)
	)
	(zone
		(layers "B.Cu" "In11.Cu" "In13.Cu" "In15.Cu")
		(hatch none 0.5)
		(connect_pads
			(clearance 0)
		)
		(min_thickness 0.25)
		(keepout
			(tracks not_allowed)
			(vias allowed)
			(pads allowed)
			(copperpour not_allowed)
			(footprints allowed)
		)
		(placement
			(enabled no)
			(sheetname "")
		)
		(fill yes
			(thermal_gap 0.5)
			(thermal_bridge_width 0.5)
			(island_removal_mode 0)
		)
		(polygon
			(pts
				(arc
					(start 127.113538 -268.569694)
					(mid 126.460758 -268.569694)
					(end 127.113538 -268.569694)
				)
			)
		)
	)
	(zone
		(layers "B.Cu" "In11.Cu" "In13.Cu" "In15.Cu")
		(hatch none 0.5)
		(connect_pads
			(clearance 0)
		)
		(min_thickness 0.25)
		(keepout
			(tracks not_allowed)
			(vias allowed)
			(pads allowed)
			(copperpour not_allowed)
			(footprints allowed)
		)
		(placement
			(enabled no)
			(sheetname "")
		)
		(fill yes
			(thermal_gap 0.5)
			(thermal_bridge_width 0.5)
			(island_removal_mode 0)
		)
		(polygon
			(pts
				(arc
					(start 103.038402 -215.436704)
					(mid 102.385622 -215.436704)
					(end 103.038402 -215.436704)
				)
			)
		)
	)
	(zone
		(layers "B.Cu" "In11.Cu" "In13.Cu" "In15.Cu")
		(hatch none 0.5)
		(connect_pads
			(clearance 0)
		)
		(min_thickness 0.25)
		(keepout
			(tracks not_allowed)
			(vias allowed)
			(pads allowed)
			(copperpour not_allowed)
			(footprints allowed)
		)
		(placement
			(enabled no)
			(sheetname "")
		)
		(fill yes
			(thermal_gap 0.5)
			(thermal_bridge_width 0.5)
			(island_removal_mode 0)
		)
		(polygon
			(pts
				(arc
					(start 375.183146 -174.876968)
					(mid 374.479566 -174.876968)
					(end 375.183146 -174.876968)
				)
			)
		)
	)
	(zone
		(layers "B.Cu" "In11.Cu" "In13.Cu" "In15.Cu")
		(hatch none 0.5)
		(connect_pads
			(clearance 0)
		)
		(min_thickness 0.25)
		(keepout
			(tracks not_allowed)
			(vias allowed)
			(pads allowed)
			(copperpour not_allowed)
			(footprints allowed)
		)
		(placement
			(enabled no)
			(sheetname "")
		)
		(fill yes
			(thermal_gap 0.5)
			(thermal_bridge_width 0.5)
			(island_removal_mode 0)
		)
		(polygon
			(pts
				(arc
					(start 32.203136 -288.266632)
					(mid 31.550356 -288.266632)
					(end 32.203136 -288.266632)
				)
			)
		)
	)
	(zone
		(layers "B.Cu" "In11.Cu" "In13.Cu" "In15.Cu")
		(hatch none 0.5)
		(connect_pads
			(clearance 0)
		)
		(min_thickness 0.25)
		(keepout
			(tracks not_allowed)
			(vias allowed)
			(pads allowed)
			(copperpour not_allowed)
			(footprints allowed)
		)
		(placement
			(enabled no)
			(sheetname "")
		)
		(fill yes
			(thermal_gap 0.5)
			(thermal_bridge_width 0.5)
			(island_removal_mode 0)
		)
		(polygon
			(pts
				(arc
					(start 405.154892 -437.889904)
					(mid 404.34514 -437.889904)
					(end 405.154892 -437.889904)
				)
			)
		)
	)
	(zone
		(layers "B.Cu" "In11.Cu" "In13.Cu" "In15.Cu")
		(hatch none 0.5)
		(connect_pads
			(clearance 0)
		)
		(min_thickness 0.25)
		(keepout
			(tracks not_allowed)
			(vias allowed)
			(pads allowed)
			(copperpour not_allowed)
			(footprints allowed)
		)
		(placement
			(enabled no)
			(sheetname "")
		)
		(fill yes
			(thermal_gap 0.5)
			(thermal_bridge_width 0.5)
			(island_removal_mode 0)
		)
		(polygon
			(pts
				(arc
					(start 32.203136 -275.516594)
					(mid 31.550356 -275.516594)
					(end 32.203136 -275.516594)
				)
			)
		)
	)
	(zone
		(layers "B.Cu" "In11.Cu" "In13.Cu" "In15.Cu")
		(hatch none 0.5)
		(connect_pads
			(clearance 0)
		)
		(min_thickness 0.25)
		(keepout
			(tracks not_allowed)
			(vias allowed)
			(pads allowed)
			(copperpour not_allowed)
			(footprints allowed)
		)
		(placement
			(enabled no)
			(sheetname "")
		)
		(fill yes
			(thermal_gap 0.5)
			(thermal_bridge_width 0.5)
			(island_removal_mode 0)
		)
		(polygon
			(pts
				(arc
					(start 375.053606 -268.569694)
					(mid 374.400826 -268.569694)
					(end 375.053606 -268.569694)
				)
			)
		)
	)
	(zone
		(layers "B.Cu" "In11.Cu" "In13.Cu" "In15.Cu")
		(hatch none 0.5)
		(connect_pads
			(clearance 0)
		)
		(min_thickness 0.25)
		(keepout
			(tracks not_allowed)
			(vias allowed)
			(pads allowed)
			(copperpour not_allowed)
			(footprints allowed)
		)
		(placement
			(enabled no)
			(sheetname "")
		)
		(fill yes
			(thermal_gap 0.5)
			(thermal_bridge_width 0.5)
			(island_removal_mode 0)
		)
		(polygon
			(pts
				(arc
					(start 375.523252 -272.639282)
					(mid 374.870472 -272.639282)
					(end 375.523252 -272.639282)
				)
			)
		)
	)
	(zone
		(layers "B.Cu" "In11.Cu" "In13.Cu" "In15.Cu")
		(hatch none 0.5)
		(connect_pads
			(clearance 0)
		)
		(min_thickness 0.25)
		(keepout
			(tracks not_allowed)
			(vias allowed)
			(pads allowed)
			(copperpour not_allowed)
			(footprints allowed)
		)
		(placement
			(enabled no)
			(sheetname "")
		)
		(fill yes
			(thermal_gap 0.5)
			(thermal_bridge_width 0.5)
			(island_removal_mode 0)
		)
		(polygon
			(pts
				(arc
					(start 105.027984 -275.8948)
					(mid 104.375204 -275.8948)
					(end 105.027984 -275.8948)
				)
			)
		)
	)
	(zone
		(layers "B.Cu" "In11.Cu" "In13.Cu" "In15.Cu")
		(hatch none 0.5)
		(connect_pads
			(clearance 0)
		)
		(min_thickness 0.25)
		(keepout
			(tracks not_allowed)
			(vias allowed)
			(pads allowed)
			(copperpour not_allowed)
			(footprints allowed)
		)
		(placement
			(enabled no)
			(sheetname "")
		)
		(fill yes
			(thermal_gap 0.5)
			(thermal_bridge_width 0.5)
			(island_removal_mode 0)
		)
		(polygon
			(pts
				(arc
					(start 132.641848 -214.622634)
					(mid 131.989068 -214.622634)
					(end 132.641848 -214.622634)
				)
			)
		)
	)
	(zone
		(layers "B.Cu" "In11.Cu" "In13.Cu" "In15.Cu")
		(hatch none 0.5)
		(connect_pads
			(clearance 0)
		)
		(min_thickness 0.25)
		(keepout
			(tracks not_allowed)
			(vias allowed)
			(pads allowed)
			(copperpour not_allowed)
			(footprints allowed)
		)
		(placement
			(enabled no)
			(sheetname "")
		)
		(fill yes
			(thermal_gap 0.5)
			(thermal_bridge_width 0.5)
			(island_removal_mode 0)
		)
		(polygon
			(pts
				(arc
					(start 265.055604 -207.51673)
					(mid 264.402824 -207.51673)
					(end 265.055604 -207.51673)
				)
			)
		)
	)
	(zone
		(layers "B.Cu" "In11.Cu" "In13.Cu" "In15.Cu")
		(hatch none 0.5)
		(connect_pads
			(clearance 0)
		)
		(min_thickness 0.25)
		(keepout
			(tracks not_allowed)
			(vias allowed)
			(pads allowed)
			(copperpour not_allowed)
			(footprints allowed)
		)
		(placement
			(enabled no)
			(sheetname "")
		)
		(fill yes
			(thermal_gap 0.5)
			(thermal_bridge_width 0.5)
			(island_removal_mode 0)
		)
		(polygon
			(pts
				(arc
					(start 127.473202 -234.970066)
					(mid 126.820422 -234.970066)
					(end 127.473202 -234.970066)
				)
			)
		)
	)
	(zone
		(layers "B.Cu" "In11.Cu" "In13.Cu" "In15.Cu")
		(hatch none 0.5)
		(connect_pads
			(clearance 0)
		)
		(min_thickness 0.25)
		(keepout
			(tracks not_allowed)
			(vias allowed)
			(pads allowed)
			(copperpour not_allowed)
			(footprints allowed)
		)
		(placement
			(enabled no)
			(sheetname "")
		)
		(fill yes
			(thermal_gap 0.5)
			(thermal_bridge_width 0.5)
			(island_removal_mode 0)
		)
		(polygon
			(pts
				(arc
					(start 69.05498 -434.289962)
					(mid 68.245228 -434.289962)
					(end 69.05498 -434.289962)
				)
			)
		)
	)
	(zone
		(layers "B.Cu" "In11.Cu" "In13.Cu" "In15.Cu")
		(hatch none 0.5)
		(connect_pads
			(clearance 0)
		)
		(min_thickness 0.25)
		(keepout
			(tracks not_allowed)
			(vias allowed)
			(pads allowed)
			(copperpour not_allowed)
			(footprints allowed)
		)
		(placement
			(enabled no)
			(sheetname "")
		)
		(fill yes
			(thermal_gap 0.5)
			(thermal_bridge_width 0.5)
			(island_removal_mode 0)
		)
		(polygon
			(pts
				(arc
					(start 21.215604 -212.616796)
					(mid 20.562824 -212.616796)
					(end 21.215604 -212.616796)
				)
			)
		)
	)
	(zone
		(layers "B.Cu" "In11.Cu" "In13.Cu" "In15.Cu")
		(hatch none 0.5)
		(connect_pads
			(clearance 0)
		)
		(min_thickness 0.25)
		(keepout
			(tracks not_allowed)
			(vias allowed)
			(pads allowed)
			(copperpour not_allowed)
			(footprints allowed)
		)
		(placement
			(enabled no)
			(sheetname "")
		)
		(fill yes
			(thermal_gap 0.5)
			(thermal_bridge_width 0.5)
			(island_removal_mode 0)
		)
		(polygon
			(pts
				(arc
					(start 440.250072 -199.866758)
					(mid 439.597292 -199.866758)
					(end 440.250072 -199.866758)
				)
			)
		)
	)
	(zone
		(layers "B.Cu" "In11.Cu" "In13.Cu" "In15.Cu")
		(hatch none 0.5)
		(connect_pads
			(clearance 0)
		)
		(min_thickness 0.25)
		(keepout
			(tracks not_allowed)
			(vias allowed)
			(pads allowed)
			(copperpour not_allowed)
			(footprints allowed)
		)
		(placement
			(enabled no)
			(sheetname "")
		)
		(fill yes
			(thermal_gap 0.5)
			(thermal_bridge_width 0.5)
			(island_removal_mode 0)
		)
		(polygon
			(pts
				(arc
					(start 127.003048 -214.622634)
					(mid 126.350268 -214.622634)
					(end 127.003048 -214.622634)
				)
			)
		)
	)
	(zone
		(layers "B.Cu" "In11.Cu" "In13.Cu" "In15.Cu")
		(hatch none 0.5)
		(connect_pads
			(clearance 0)
		)
		(min_thickness 0.25)
		(keepout
			(tracks not_allowed)
			(vias allowed)
			(pads allowed)
			(copperpour not_allowed)
			(footprints allowed)
		)
		(placement
			(enabled no)
			(sheetname "")
		)
		(fill yes
			(thermal_gap 0.5)
			(thermal_bridge_width 0.5)
			(island_removal_mode 0)
		)
		(polygon
			(pts
				(arc
					(start 284.243272 -220.266768)
					(mid 283.590492 -220.266768)
					(end 284.243272 -220.266768)
				)
			)
		)
	)
	(zone
		(layers "B.Cu" "In11.Cu" "In13.Cu" "In15.Cu")
		(hatch none 0.5)
		(connect_pads
			(clearance 0)
		)
		(min_thickness 0.25)
		(keepout
			(tracks not_allowed)
			(vias allowed)
			(pads allowed)
			(copperpour not_allowed)
			(footprints allowed)
		)
		(placement
			(enabled no)
			(sheetname "")
		)
		(fill yes
			(thermal_gap 0.5)
			(thermal_bridge_width 0.5)
			(island_removal_mode 0)
		)
		(polygon
			(pts
				(arc
					(start 384.154934 -439.0898)
					(mid 383.345182 -439.0898)
					(end 384.154934 -439.0898)
				)
			)
		)
	)
	(zone
		(layers "B.Cu" "In11.Cu" "In13.Cu" "In15.Cu")
		(hatch none 0.5)
		(connect_pads
			(clearance 0)
		)
		(min_thickness 0.25)
		(keepout
			(tracks not_allowed)
			(vias allowed)
			(pads allowed)
			(copperpour not_allowed)
			(footprints allowed)
		)
		(placement
			(enabled no)
			(sheetname "")
		)
		(fill yes
			(thermal_gap 0.5)
			(thermal_bridge_width 0.5)
			(island_removal_mode 0)
		)
		(polygon
			(pts
				(arc
					(start 342.990424 -242.294918)
					(mid 342.337644 -242.294918)
					(end 342.990424 -242.294918)
				)
			)
		)
	)
	(zone
		(layers "B.Cu" "In11.Cu" "In13.Cu" "In15.Cu")
		(hatch none 0.5)
		(connect_pads
			(clearance 0)
		)
		(min_thickness 0.25)
		(keepout
			(tracks not_allowed)
			(vias allowed)
			(pads allowed)
			(copperpour not_allowed)
			(footprints allowed)
		)
		(placement
			(enabled no)
			(sheetname "")
		)
		(fill yes
			(thermal_gap 0.5)
			(thermal_bridge_width 0.5)
			(island_removal_mode 0)
		)
		(polygon
			(pts
				(arc
					(start 97.509584 -259.616956)
					(mid 96.856804 -259.616956)
					(end 97.509584 -259.616956)
				)
			)
		)
	)
	(zone
		(layers "B.Cu" "In11.Cu" "In13.Cu" "In15.Cu")
		(hatch none 0.5)
		(connect_pads
			(clearance 0)
		)
		(min_thickness 0.25)
		(keepout
			(tracks not_allowed)
			(vias allowed)
			(pads allowed)
			(copperpour not_allowed)
			(footprints allowed)
		)
		(placement
			(enabled no)
			(sheetname "")
		)
		(fill yes
			(thermal_gap 0.5)
			(thermal_bridge_width 0.5)
			(island_removal_mode 0)
		)
		(polygon
			(pts
				(arc
					(start 32.203136 -222.816674)
					(mid 31.550356 -222.816674)
					(end 32.203136 -222.816674)
				)
			)
		)
	)
	(zone
		(layers "B.Cu" "In11.Cu" "In13.Cu" "In15.Cu")
		(hatch none 0.5)
		(connect_pads
			(clearance 0)
		)
		(min_thickness 0.25)
		(keepout
			(tracks not_allowed)
			(vias allowed)
			(pads allowed)
			(copperpour not_allowed)
			(footprints allowed)
		)
		(placement
			(enabled no)
			(sheetname "")
		)
		(fill yes
			(thermal_gap 0.5)
			(thermal_bridge_width 0.5)
			(island_removal_mode 0)
		)
		(polygon
			(pts
				(arc
					(start 97.399602 -246.364506)
					(mid 96.746822 -246.364506)
					(end 97.399602 -246.364506)
				)
			)
		)
	)
	(zone
		(layers "B.Cu" "In11.Cu" "In13.Cu" "In15.Cu")
		(hatch none 0.5)
		(connect_pads
			(clearance 0)
		)
		(min_thickness 0.25)
		(keepout
			(tracks not_allowed)
			(vias allowed)
			(pads allowed)
			(copperpour not_allowed)
			(footprints allowed)
		)
		(placement
			(enabled no)
			(sheetname "")
		)
		(fill yes
			(thermal_gap 0.5)
			(thermal_bridge_width 0.5)
			(island_removal_mode 0)
		)
		(polygon
			(pts
				(arc
					(start 97.869756 -227.64496)
					(mid 97.216976 -227.64496)
					(end 97.869756 -227.64496)
				)
			)
		)
	)
	(zone
		(layers "B.Cu" "In11.Cu" "In13.Cu" "In15.Cu")
		(hatch none 0.5)
		(connect_pads
			(clearance 0)
		)
		(min_thickness 0.25)
		(keepout
			(tracks not_allowed)
			(vias allowed)
			(pads allowed)
			(copperpour not_allowed)
			(footprints allowed)
		)
		(placement
			(enabled no)
			(sheetname "")
		)
		(fill yes
			(thermal_gap 0.5)
			(thermal_bridge_width 0.5)
			(island_removal_mode 0)
		)
		(polygon
			(pts
				(arc
					(start 143.154908 -438.089802)
					(mid 142.345156 -438.089802)
					(end 143.154908 -438.089802)
				)
			)
		)
	)
	(zone
		(layers "B.Cu" "In11.Cu" "In13.Cu" "In15.Cu")
		(hatch none 0.5)
		(connect_pads
			(clearance 0)
		)
		(min_thickness 0.25)
		(keepout
			(tracks not_allowed)
			(vias allowed)
			(pads allowed)
			(copperpour not_allowed)
			(footprints allowed)
		)
		(placement
			(enabled no)
			(sheetname "")
		)
		(fill yes
			(thermal_gap 0.5)
			(thermal_bridge_width 0.5)
			(island_removal_mode 0)
		)
		(polygon
			(pts
				(arc
					(start 76.054966 -426.089826)
					(mid 75.245214 -426.089826)
					(end 76.054966 -426.089826)
				)
			)
		)
	)
	(zone
		(layers "B.Cu" "In11.Cu" "In13.Cu" "In15.Cu")
		(hatch none 0.5)
		(connect_pads
			(clearance 0)
		)
		(min_thickness 0.25)
		(keepout
			(tracks not_allowed)
			(vias allowed)
			(pads allowed)
			(copperpour not_allowed)
			(footprints allowed)
		)
		(placement
			(enabled no)
			(sheetname "")
		)
		(fill yes
			(thermal_gap 0.5)
			(thermal_bridge_width 0.5)
			(island_removal_mode 0)
		)
		(polygon
			(pts
				(arc
					(start 97.039938 -283.219906)
					(mid 96.387158 -283.219906)
					(end 97.039938 -283.219906)
				)
			)
		)
	)
	(zone
		(layers "B.Cu" "In11.Cu" "In13.Cu" "In15.Cu")
		(hatch none 0.5)
		(connect_pads
			(clearance 0)
		)
		(min_thickness 0.25)
		(keepout
			(tracks not_allowed)
			(vias allowed)
			(pads allowed)
			(copperpour not_allowed)
			(footprints allowed)
		)
		(placement
			(enabled no)
			(sheetname "")
		)
		(fill yes
			(thermal_gap 0.5)
			(thermal_bridge_width 0.5)
			(island_removal_mode 0)
		)
		(polygon
			(pts
				(arc
					(start 362.726478 -227.64496)
					(mid 362.073698 -227.64496)
					(end 362.726478 -227.64496)
				)
			)
		)
	)
	(zone
		(layers "B.Cu" "In11.Cu" "In13.Cu" "In15.Cu")
		(hatch none 0.5)
		(connect_pads
			(clearance 0)
		)
		(min_thickness 0.25)
		(keepout
			(tracks not_allowed)
			(vias allowed)
			(pads allowed)
			(copperpour not_allowed)
			(footprints allowed)
		)
		(placement
			(enabled no)
			(sheetname "")
		)
		(fill yes
			(thermal_gap 0.5)
			(thermal_bridge_width 0.5)
			(island_removal_mode 0)
		)
		(polygon
			(pts
				(arc
					(start 376.823224 -229.272846)
					(mid 376.170444 -229.272846)
					(end 376.823224 -229.272846)
				)
			)
		)
	)
	(zone
		(layers "B.Cu" "In11.Cu" "In13.Cu" "In15.Cu")
		(hatch none 0.5)
		(connect_pads
			(clearance 0)
		)
		(min_thickness 0.25)
		(keepout
			(tracks not_allowed)
			(vias allowed)
			(pads allowed)
			(copperpour not_allowed)
			(footprints allowed)
		)
		(placement
			(enabled no)
			(sheetname "")
		)
		(fill yes
			(thermal_gap 0.5)
			(thermal_bridge_width 0.5)
			(island_removal_mode 0)
		)
		(polygon
			(pts
				(arc
					(start 440.250072 -227.066602)
					(mid 439.597292 -227.066602)
					(end 440.250072 -227.066602)
				)
			)
		)
	)
	(zone
		(layers "B.Cu" "In11.Cu" "In13.Cu" "In15.Cu")
		(hatch none 0.5)
		(connect_pads
			(clearance 0)
		)
		(min_thickness 0.25)
		(keepout
			(tracks not_allowed)
			(vias allowed)
			(pads allowed)
			(copperpour not_allowed)
			(footprints allowed)
		)
		(placement
			(enabled no)
			(sheetname "")
		)
		(fill yes
			(thermal_gap 0.5)
			(thermal_bridge_width 0.5)
			(island_removal_mode 0)
		)
		(polygon
			(pts
				(arc
					(start 451.237604 -207.51673)
					(mid 450.584824 -207.51673)
					(end 451.237604 -207.51673)
				)
			)
		)
	)
	(zone
		(layers "B.Cu" "In11.Cu" "In13.Cu" "In15.Cu")
		(hatch none 0.5)
		(connect_pads
			(clearance 0)
		)
		(min_thickness 0.25)
		(keepout
			(tracks not_allowed)
			(vias allowed)
			(pads allowed)
			(copperpour not_allowed)
			(footprints allowed)
		)
		(placement
			(enabled no)
			(sheetname "")
		)
		(fill yes
			(thermal_gap 0.5)
			(thermal_bridge_width 0.5)
			(island_removal_mode 0)
		)
		(polygon
			(pts
				(arc
					(start 377.29287 -239.853216)
					(mid 376.64009 -239.853216)
					(end 377.29287 -239.853216)
				)
			)
		)
	)
	(zone
		(layers "B.Cu" "In11.Cu" "In13.Cu" "In15.Cu")
		(hatch none 0.5)
		(connect_pads
			(clearance 0)
		)
		(min_thickness 0.25)
		(keepout
			(tracks not_allowed)
			(vias allowed)
			(pads allowed)
			(copperpour not_allowed)
			(footprints allowed)
		)
		(placement
			(enabled no)
			(sheetname "")
		)
		(fill yes
			(thermal_gap 0.5)
			(thermal_bridge_width 0.5)
			(island_removal_mode 0)
		)
		(polygon
			(pts
				(arc
					(start 122.716544 -410.030168)
					(mid 122.012964 -410.030168)
					(end 122.716544 -410.030168)
				)
			)
		)
	)
	(zone
		(layers "B.Cu" "In11.Cu" "In13.Cu" "In15.Cu")
		(hatch none 0.5)
		(connect_pads
			(clearance 0)
		)
		(min_thickness 0.25)
		(keepout
			(tracks not_allowed)
			(vias allowed)
			(pads allowed)
			(copperpour not_allowed)
			(footprints allowed)
		)
		(placement
			(enabled no)
			(sheetname "")
		)
		(fill yes
			(thermal_gap 0.5)
			(thermal_bridge_width 0.5)
			(island_removal_mode 0)
		)
		(polygon
			(pts
				(arc
					(start 355.677724 -213.732618)
					(mid 355.024944 -213.732618)
					(end 355.677724 -213.732618)
				)
			)
		)
	)
	(zone
		(layers "B.Cu" "In11.Cu" "In13.Cu" "In15.Cu")
		(hatch none 0.5)
		(connect_pads
			(clearance 0)
		)
		(min_thickness 0.25)
		(keepout
			(tracks not_allowed)
			(vias allowed)
			(pads allowed)
			(copperpour not_allowed)
			(footprints allowed)
		)
		(placement
			(enabled no)
			(sheetname "")
		)
		(fill yes
			(thermal_gap 0.5)
			(thermal_bridge_width 0.5)
			(island_removal_mode 0)
		)
		(polygon
			(pts
				(arc
					(start 374.943624 -243.922804)
					(mid 374.290844 -243.922804)
					(end 374.943624 -243.922804)
				)
			)
		)
	)
	(zone
		(layers "B.Cu" "In11.Cu" "In13.Cu" "In15.Cu")
		(hatch none 0.5)
		(connect_pads
			(clearance 0)
		)
		(min_thickness 0.25)
		(keepout
			(tracks not_allowed)
			(vias allowed)
			(pads allowed)
			(copperpour not_allowed)
			(footprints allowed)
		)
		(placement
			(enabled no)
			(sheetname "")
		)
		(fill yes
			(thermal_gap 0.5)
			(thermal_bridge_width 0.5)
			(island_removal_mode 0)
		)
		(polygon
			(pts
				(arc
					(start 440.250072 -284.016704)
					(mid 439.597292 -284.016704)
					(end 440.250072 -284.016704)
				)
			)
		)
	)
	(zone
		(layers "B.Cu" "In11.Cu" "In13.Cu" "In15.Cu")
		(hatch none 0.5)
		(connect_pads
			(clearance 0)
		)
		(min_thickness 0.25)
		(keepout
			(tracks not_allowed)
			(vias allowed)
			(pads allowed)
			(copperpour not_allowed)
			(footprints allowed)
		)
		(placement
			(enabled no)
			(sheetname "")
		)
		(fill yes
			(thermal_gap 0.5)
			(thermal_bridge_width 0.5)
			(island_removal_mode 0)
		)
		(polygon
			(pts
				(arc
					(start 365.11103 -55.884572)
					(mid 364.40745 -55.884572)
					(end 365.11103 -55.884572)
				)
			)
		)
	)
	(zone
		(layers "B.Cu" "In11.Cu" "In13.Cu" "In15.Cu")
		(hatch none 0.5)
		(connect_pads
			(clearance 0)
		)
		(min_thickness 0.25)
		(keepout
			(tracks not_allowed)
			(vias allowed)
			(pads allowed)
			(copperpour not_allowed)
			(footprints allowed)
		)
		(placement
			(enabled no)
			(sheetname "")
		)
		(fill yes
			(thermal_gap 0.5)
			(thermal_bridge_width 0.5)
			(island_removal_mode 0)
		)
		(polygon
			(pts
				(arc
					(start 339.70087 -215.436704)
					(mid 339.04809 -215.436704)
					(end 339.70087 -215.436704)
				)
			)
		)
	)
	(zone
		(layers "B.Cu" "In11.Cu" "In13.Cu" "In15.Cu")
		(hatch none 0.5)
		(connect_pads
			(clearance 0)
		)
		(min_thickness 0.25)
		(keepout
			(tracks not_allowed)
			(vias allowed)
			(pads allowed)
			(copperpour not_allowed)
			(footprints allowed)
		)
		(placement
			(enabled no)
			(sheetname "")
		)
		(fill yes
			(thermal_gap 0.5)
			(thermal_bridge_width 0.5)
			(island_removal_mode 0)
		)
		(polygon
			(pts
				(arc
					(start 102.678738 -275.08073)
					(mid 102.025958 -275.08073)
					(end 102.678738 -275.08073)
				)
			)
		)
	)
	(zone
		(layers "B.Cu" "In11.Cu" "In13.Cu" "In15.Cu")
		(hatch none 0.5)
		(connect_pads
			(clearance 0)
		)
		(min_thickness 0.25)
		(keepout
			(tracks not_allowed)
			(vias allowed)
			(pads allowed)
			(copperpour not_allowed)
			(footprints allowed)
		)
		(placement
			(enabled no)
			(sheetname "")
		)
		(fill yes
			(thermal_gap 0.5)
			(thermal_bridge_width 0.5)
			(island_removal_mode 0)
		)
		(polygon
			(pts
				(arc
					(start 128.882648 -214.622634)
					(mid 128.229868 -214.622634)
					(end 128.882648 -214.622634)
				)
			)
		)
	)
	(zone
		(layers "B.Cu" "In11.Cu" "In13.Cu" "In15.Cu")
		(hatch none 0.5)
		(connect_pads
			(clearance 0)
		)
		(min_thickness 0.25)
		(keepout
			(tracks not_allowed)
			(vias allowed)
			(pads allowed)
			(copperpour not_allowed)
			(footprints allowed)
		)
		(placement
			(enabled no)
			(sheetname "")
		)
		(fill yes
			(thermal_gap 0.5)
			(thermal_bridge_width 0.5)
			(island_removal_mode 0)
		)
		(polygon
			(pts
				(arc
					(start 451.237604 -205.816708)
					(mid 450.584824 -205.816708)
					(end 451.237604 -205.816708)
				)
			)
		)
	)
	(zone
		(layers "B.Cu" "In11.Cu" "In13.Cu" "In15.Cu")
		(hatch none 0.5)
		(connect_pads
			(clearance 0)
		)
		(min_thickness 0.25)
		(keepout
			(tracks not_allowed)
			(vias allowed)
			(pads allowed)
			(copperpour not_allowed)
			(footprints allowed)
		)
		(placement
			(enabled no)
			(sheetname "")
		)
		(fill yes
			(thermal_gap 0.5)
			(thermal_bridge_width 0.5)
			(island_removal_mode 0)
		)
		(polygon
			(pts
				(arc
					(start 343.930224 -234.15625)
					(mid 343.277444 -234.15625)
					(end 343.930224 -234.15625)
				)
			)
		)
	)
	(zone
		(layers "B.Cu" "In11.Cu" "In13.Cu" "In15.Cu")
		(hatch none 0.5)
		(connect_pads
			(clearance 0)
		)
		(min_thickness 0.25)
		(keepout
			(tracks not_allowed)
			(vias allowed)
			(pads allowed)
			(copperpour not_allowed)
			(footprints allowed)
		)
		(placement
			(enabled no)
			(sheetname "")
		)
		(fill yes
			(thermal_gap 0.5)
			(thermal_bridge_width 0.5)
			(island_removal_mode 0)
		)
		(polygon
			(pts
				(arc
					(start 295.230804 -244.066568)
					(mid 294.578024 -244.066568)
					(end 295.230804 -244.066568)
				)
			)
		)
	)
	(zone
		(layers "B.Cu" "In11.Cu" "In13.Cu" "In15.Cu")
		(hatch none 0.5)
		(connect_pads
			(clearance 0)
		)
		(min_thickness 0.25)
		(keepout
			(tracks not_allowed)
			(vias allowed)
			(pads allowed)
			(copperpour not_allowed)
			(footprints allowed)
		)
		(placement
			(enabled no)
			(sheetname "")
		)
		(fill yes
			(thermal_gap 0.5)
			(thermal_bridge_width 0.5)
			(island_removal_mode 0)
		)
		(polygon
			(pts
				(arc
					(start 436.150004 -196.466714)
					(mid 435.497224 -196.466714)
					(end 436.150004 -196.466714)
				)
			)
		)
	)
	(zone
		(layers "B.Cu" "In11.Cu" "In13.Cu" "In15.Cu")
		(hatch none 0.5)
		(connect_pads
			(clearance 0)
		)
		(min_thickness 0.25)
		(keepout
			(tracks not_allowed)
			(vias allowed)
			(pads allowed)
			(copperpour not_allowed)
			(footprints allowed)
		)
		(placement
			(enabled no)
			(sheetname "")
		)
		(fill yes
			(thermal_gap 0.5)
			(thermal_bridge_width 0.5)
			(island_removal_mode 0)
		)
		(polygon
			(pts
				(arc
					(start 361.786424 -227.64496)
					(mid 361.133644 -227.64496)
					(end 361.786424 -227.64496)
				)
			)
		)
	)
	(zone
		(layers "B.Cu" "In11.Cu" "In13.Cu" "In15.Cu")
		(hatch none 0.5)
		(connect_pads
			(clearance 0)
		)
		(min_thickness 0.25)
		(keepout
			(tracks not_allowed)
			(vias allowed)
			(pads allowed)
			(copperpour not_allowed)
			(footprints allowed)
		)
		(placement
			(enabled no)
			(sheetname "")
		)
		(fill yes
			(thermal_gap 0.5)
			(thermal_bridge_width 0.5)
			(island_removal_mode 0)
		)
		(polygon
			(pts
				(arc
					(start 354.226114 -168.835832)
					(mid 353.522534 -168.835832)
					(end 354.226114 -168.835832)
				)
			)
		)
	)
	(zone
		(layers "B.Cu" "In11.Cu" "In13.Cu" "In15.Cu")
		(hatch none 0.5)
		(connect_pads
			(clearance 0)
		)
		(min_thickness 0.25)
		(keepout
			(tracks not_allowed)
			(vias allowed)
			(pads allowed)
			(copperpour not_allowed)
			(footprints allowed)
		)
		(placement
			(enabled no)
			(sheetname "")
		)
		(fill yes
			(thermal_gap 0.5)
			(thermal_bridge_width 0.5)
			(island_removal_mode 0)
		)
		(polygon
			(pts
				(arc
					(start 284.243272 -273.816572)
					(mid 283.590492 -273.816572)
					(end 284.243272 -273.816572)
				)
			)
		)
	)
	(zone
		(layers "B.Cu" "In11.Cu" "In13.Cu" "In15.Cu")
		(hatch none 0.5)
		(connect_pads
			(clearance 0)
		)
		(min_thickness 0.25)
		(keepout
			(tracks not_allowed)
			(vias allowed)
			(pads allowed)
			(copperpour not_allowed)
			(footprints allowed)
		)
		(placement
			(enabled no)
			(sheetname "")
		)
		(fill yes
			(thermal_gap 0.5)
			(thermal_bridge_width 0.5)
			(island_removal_mode 0)
		)
		(polygon
			(pts
				(arc
					(start 357.087424 -227.64496)
					(mid 356.434644 -227.64496)
					(end 357.087424 -227.64496)
				)
			)
		)
	)
	(zone
		(layers "B.Cu" "In11.Cu" "In13.Cu" "In15.Cu")
		(hatch none 0.5)
		(connect_pads
			(clearance 0)
		)
		(min_thickness 0.25)
		(keepout
			(tracks not_allowed)
			(vias allowed)
			(pads allowed)
			(copperpour not_allowed)
			(footprints allowed)
		)
		(placement
			(enabled no)
			(sheetname "")
		)
		(fill yes
			(thermal_gap 0.5)
			(thermal_bridge_width 0.5)
			(island_removal_mode 0)
		)
		(polygon
			(pts
				(arc
					(start 138.154918 -438.089802)
					(mid 137.345166 -438.089802)
					(end 138.154918 -438.089802)
				)
			)
		)
	)
	(zone
		(layers "B.Cu" "In11.Cu" "In13.Cu" "In15.Cu")
		(hatch none 0.5)
		(connect_pads
			(clearance 0)
		)
		(min_thickness 0.25)
		(keepout
			(tracks not_allowed)
			(vias allowed)
			(pads allowed)
			(copperpour not_allowed)
			(footprints allowed)
		)
		(placement
			(enabled no)
			(sheetname "")
		)
		(fill yes
			(thermal_gap 0.5)
			(thermal_bridge_width 0.5)
			(island_removal_mode 0)
		)
		(polygon
			(pts
				(arc
					(start 356.61727 -228.45903)
					(mid 355.96449 -228.45903)
					(end 356.61727 -228.45903)
				)
			)
		)
	)
	(zone
		(layers "B.Cu" "In11.Cu" "In13.Cu" "In15.Cu")
		(hatch none 0.5)
		(connect_pads
			(clearance 0)
		)
		(min_thickness 0.25)
		(keepout
			(tracks not_allowed)
			(vias allowed)
			(pads allowed)
			(copperpour not_allowed)
			(footprints allowed)
		)
		(placement
			(enabled no)
			(sheetname "")
		)
		(fill yes
			(thermal_gap 0.5)
			(thermal_bridge_width 0.5)
			(island_removal_mode 0)
		)
		(polygon
			(pts
				(arc
					(start 353.328224 -227.64496)
					(mid 352.675444 -227.64496)
					(end 353.328224 -227.64496)
				)
			)
		)
	)
	(zone
		(layers "B.Cu" "In11.Cu" "In13.Cu" "In15.Cu")
		(hatch none 0.5)
		(connect_pads
			(clearance 0)
		)
		(min_thickness 0.25)
		(keepout
			(tracks not_allowed)
			(vias allowed)
			(pads allowed)
			(copperpour not_allowed)
			(footprints allowed)
		)
		(placement
			(enabled no)
			(sheetname "")
		)
		(fill yes
			(thermal_gap 0.5)
			(thermal_bridge_width 0.5)
			(island_removal_mode 0)
		)
		(polygon
			(pts
				(arc
					(start 328.837798 -403.883876)
					(mid 328.134218 -403.883876)
					(end 328.837798 -403.883876)
				)
			)
		)
	)
	(zone
		(layers "B.Cu" "In11.Cu" "In13.Cu" "In15.Cu")
		(hatch none 0.5)
		(connect_pads
			(clearance 0)
		)
		(min_thickness 0.25)
		(keepout
			(tracks not_allowed)
			(vias allowed)
			(pads allowed)
			(copperpour not_allowed)
			(footprints allowed)
		)
		(placement
			(enabled no)
			(sheetname "")
		)
		(fill yes
			(thermal_gap 0.5)
			(thermal_bridge_width 0.5)
			(island_removal_mode 0)
		)
		(polygon
			(pts
				(arc
					(start 207.397604 -312.066686)
					(mid 206.744824 -312.066686)
					(end 207.397604 -312.066686)
				)
			)
		)
	)
	(zone
		(layers "B.Cu" "In11.Cu" "In13.Cu" "In15.Cu")
		(hatch none 0.5)
		(connect_pads
			(clearance 0)
		)
		(min_thickness 0.25)
		(keepout
			(tracks not_allowed)
			(vias allowed)
			(pads allowed)
			(copperpour not_allowed)
			(footprints allowed)
		)
		(placement
			(enabled no)
			(sheetname "")
		)
		(fill yes
			(thermal_gap 0.5)
			(thermal_bridge_width 0.5)
			(island_removal_mode 0)
		)
		(polygon
			(pts
				(arc
					(start 451.237604 -209.216752)
					(mid 450.584824 -209.216752)
					(end 451.237604 -209.216752)
				)
			)
		)
	)
	(zone
		(layers "B.Cu" "In11.Cu" "In13.Cu" "In15.Cu")
		(hatch none 0.5)
		(connect_pads
			(clearance 0)
		)
		(min_thickness 0.25)
		(keepout
			(tracks not_allowed)
			(vias allowed)
			(pads allowed)
			(copperpour not_allowed)
			(footprints allowed)
		)
		(placement
			(enabled no)
			(sheetname "")
		)
		(fill yes
			(thermal_gap 0.5)
			(thermal_bridge_width 0.5)
			(island_removal_mode 0)
		)
		(polygon
			(pts
				(arc
					(start 128.522984 -254.733552)
					(mid 127.870204 -254.733552)
					(end 128.522984 -254.733552)
				)
			)
		)
	)
	(zone
		(layers "B.Cu" "In11.Cu" "In13.Cu" "In15.Cu")
		(hatch none 0.5)
		(connect_pads
			(clearance 0)
		)
		(min_thickness 0.25)
		(keepout
			(tracks not_allowed)
			(vias allowed)
			(pads allowed)
			(copperpour not_allowed)
			(footprints allowed)
		)
		(placement
			(enabled no)
			(sheetname "")
		)
		(fill yes
			(thermal_gap 0.5)
			(thermal_bridge_width 0.5)
			(island_removal_mode 0)
		)
		(polygon
			(pts
				(arc
					(start 134.154926 -436.889906)
					(mid 133.345174 -436.889906)
					(end 134.154926 -436.889906)
				)
			)
		)
	)
	(zone
		(layers "B.Cu" "In11.Cu" "In13.Cu" "In15.Cu")
		(hatch none 0.5)
		(connect_pads
			(clearance 0)
		)
		(min_thickness 0.25)
		(keepout
			(tracks not_allowed)
			(vias allowed)
			(pads allowed)
			(copperpour not_allowed)
			(footprints allowed)
		)
		(placement
			(enabled no)
			(sheetname "")
		)
		(fill yes
			(thermal_gap 0.5)
			(thermal_bridge_width 0.5)
			(island_removal_mode 0)
		)
		(polygon
			(pts
				(arc
					(start 128.154938 -437.889904)
					(mid 127.345186 -437.889904)
					(end 128.154938 -437.889904)
				)
			)
		)
	)
	(zone
		(layers "B.Cu" "In11.Cu" "In13.Cu" "In15.Cu")
		(hatch none 0.5)
		(connect_pads
			(clearance 0)
		)
		(min_thickness 0.25)
		(keepout
			(tracks not_allowed)
			(vias allowed)
			(pads allowed)
			(copperpour not_allowed)
			(footprints allowed)
		)
		(placement
			(enabled no)
			(sheetname "")
		)
		(fill yes
			(thermal_gap 0.5)
			(thermal_bridge_width 0.5)
			(island_removal_mode 0)
		)
		(polygon
			(pts
				(arc
					(start 352.85807 -215.436704)
					(mid 352.20529 -215.436704)
					(end 352.85807 -215.436704)
				)
			)
		)
	)
	(zone
		(layers "B.Cu" "In11.Cu" "In13.Cu" "In15.Cu")
		(hatch none 0.5)
		(connect_pads
			(clearance 0)
		)
		(min_thickness 0.25)
		(keepout
			(tracks not_allowed)
			(vias allowed)
			(pads allowed)
			(copperpour not_allowed)
			(footprints allowed)
		)
		(placement
			(enabled no)
			(sheetname "")
		)
		(fill yes
			(thermal_gap 0.5)
			(thermal_bridge_width 0.5)
			(island_removal_mode 0)
		)
		(polygon
			(pts
				(arc
					(start 188.209936 -228.766624)
					(mid 187.557156 -228.766624)
					(end 188.209936 -228.766624)
				)
			)
		)
	)
	(zone
		(layers "B.Cu" "In11.Cu" "In13.Cu" "In15.Cu")
		(hatch none 0.5)
		(connect_pads
			(clearance 0)
		)
		(min_thickness 0.25)
		(keepout
			(tracks not_allowed)
			(vias allowed)
			(pads allowed)
			(copperpour not_allowed)
			(footprints allowed)
		)
		(placement
			(enabled no)
			(sheetname "")
		)
		(fill yes
			(thermal_gap 0.5)
			(thermal_bridge_width 0.5)
			(island_removal_mode 0)
		)
		(polygon
			(pts
				(arc
					(start 95.520002 -231.714548)
					(mid 94.867222 -231.714548)
					(end 95.520002 -231.714548)
				)
			)
		)
	)
	(zone
		(layers "B.Cu" "In11.Cu" "In13.Cu" "In15.Cu")
		(hatch none 0.5)
		(connect_pads
			(clearance 0)
		)
		(min_thickness 0.25)
		(keepout
			(tracks not_allowed)
			(vias allowed)
			(pads allowed)
			(copperpour not_allowed)
			(footprints allowed)
		)
		(placement
			(enabled no)
			(sheetname "")
		)
		(fill yes
			(thermal_gap 0.5)
			(thermal_bridge_width 0.5)
			(island_removal_mode 0)
		)
		(polygon
			(pts
				(arc
					(start 214.941404 -244.916706)
					(mid 214.288624 -244.916706)
					(end 214.941404 -244.916706)
				)
			)
		)
	)
	(zone
		(layers "B.Cu" "In11.Cu" "In13.Cu" "In15.Cu")
		(hatch none 0.5)
		(connect_pads
			(clearance 0)
		)
		(min_thickness 0.25)
		(keepout
			(tracks not_allowed)
			(vias allowed)
			(pads allowed)
			(copperpour not_allowed)
			(footprints allowed)
		)
		(placement
			(enabled no)
			(sheetname "")
		)
		(fill yes
			(thermal_gap 0.5)
			(thermal_bridge_width 0.5)
			(island_removal_mode 0)
		)
		(polygon
			(pts
				(arc
					(start 407.68016 -410.030168)
					(mid 406.97658 -410.030168)
					(end 407.68016 -410.030168)
				)
			)
		)
	)
	(zone
		(layers "B.Cu" "In11.Cu" "In13.Cu" "In15.Cu")
		(hatch none 0.5)
		(connect_pads
			(clearance 0)
		)
		(min_thickness 0.25)
		(keepout
			(tracks not_allowed)
			(vias allowed)
			(pads allowed)
			(copperpour not_allowed)
			(footprints allowed)
		)
		(placement
			(enabled no)
			(sheetname "")
		)
		(fill yes
			(thermal_gap 0.5)
			(thermal_bridge_width 0.5)
			(island_removal_mode 0)
		)
		(polygon
			(pts
				(arc
					(start 350.148652 -282.405836)
					(mid 349.495872 -282.405836)
					(end 350.148652 -282.405836)
				)
			)
		)
	)
	(zone
		(layers "B.Cu" "In11.Cu" "In13.Cu" "In15.Cu")
		(hatch none 0.5)
		(connect_pads
			(clearance 0)
		)
		(min_thickness 0.25)
		(keepout
			(tracks not_allowed)
			(vias allowed)
			(pads allowed)
			(copperpour not_allowed)
			(footprints allowed)
		)
		(placement
			(enabled no)
			(sheetname "")
		)
		(fill yes
			(thermal_gap 0.5)
			(thermal_bridge_width 0.5)
			(island_removal_mode 0)
		)
		(polygon
			(pts
				(arc
					(start 340.750906 -280.778204)
					(mid 340.098126 -280.778204)
					(end 340.750906 -280.778204)
				)
			)
		)
	)
	(zone
		(layers "B.Cu" "In11.Cu" "In13.Cu" "In15.Cu")
		(hatch none 0.5)
		(connect_pads
			(clearance 0)
		)
		(min_thickness 0.25)
		(keepout
			(tracks not_allowed)
			(vias allowed)
			(pads allowed)
			(copperpour not_allowed)
			(footprints allowed)
		)
		(placement
			(enabled no)
			(sheetname "")
		)
		(fill yes
			(thermal_gap 0.5)
			(thermal_bridge_width 0.5)
			(island_removal_mode 0)
		)
		(polygon
			(pts
				(arc
					(start 17.115536 -310.366664)
					(mid 16.462756 -310.366664)
					(end 17.115536 -310.366664)
				)
			)
		)
	)
	(zone
		(layers "B.Cu" "In11.Cu" "In13.Cu" "In15.Cu")
		(hatch none 0.5)
		(connect_pads
			(clearance 0)
		)
		(min_thickness 0.25)
		(keepout
			(tracks not_allowed)
			(vias allowed)
			(pads allowed)
			(copperpour not_allowed)
			(footprints allowed)
		)
		(placement
			(enabled no)
			(sheetname "")
		)
		(fill yes
			(thermal_gap 0.5)
			(thermal_bridge_width 0.5)
			(island_removal_mode 0)
		)
		(polygon
			(pts
				(arc
					(start 269.155672 -212.616796)
					(mid 268.502892 -212.616796)
					(end 269.155672 -212.616796)
				)
			)
		)
	)
	(zone
		(layers "B.Cu" "In11.Cu" "In13.Cu" "In15.Cu")
		(hatch none 0.5)
		(connect_pads
			(clearance 0)
		)
		(min_thickness 0.25)
		(keepout
			(tracks not_allowed)
			(vias allowed)
			(pads allowed)
			(copperpour not_allowed)
			(footprints allowed)
		)
		(placement
			(enabled no)
			(sheetname "")
		)
		(fill yes
			(thermal_gap 0.5)
			(thermal_bridge_width 0.5)
			(island_removal_mode 0)
		)
		(polygon
			(pts
				(arc
					(start 284.243272 -214.316564)
					(mid 283.590492 -214.316564)
					(end 284.243272 -214.316564)
				)
			)
		)
	)
	(zone
		(layers "B.Cu" "In11.Cu" "In13.Cu" "In15.Cu")
		(hatch none 0.5)
		(connect_pads
			(clearance 0)
		)
		(min_thickness 0.25)
		(keepout
			(tracks not_allowed)
			(vias allowed)
			(pads allowed)
			(copperpour not_allowed)
			(footprints allowed)
		)
		(placement
			(enabled no)
			(sheetname "")
		)
		(fill yes
			(thermal_gap 0.5)
			(thermal_bridge_width 0.5)
			(island_removal_mode 0)
		)
		(polygon
			(pts
				(arc
					(start 376.933206 -266.941808)
					(mid 376.280426 -266.941808)
					(end 376.933206 -266.941808)
				)
			)
		)
	)
	(zone
		(layers "B.Cu" "In11.Cu" "In13.Cu" "In15.Cu")
		(hatch none 0.5)
		(connect_pads
			(clearance 0)
		)
		(min_thickness 0.25)
		(keepout
			(tracks not_allowed)
			(vias allowed)
			(pads allowed)
			(copperpour not_allowed)
			(footprints allowed)
		)
		(placement
			(enabled no)
			(sheetname "")
		)
		(fill yes
			(thermal_gap 0.5)
			(thermal_bridge_width 0.5)
			(island_removal_mode 0)
		)
		(polygon
			(pts
				(arc
					(start 97.039938 -258.80314)
					(mid 96.387158 -258.80314)
					(end 97.039938 -258.80314)
				)
			)
		)
	)
	(zone
		(layers "B.Cu" "In11.Cu" "In13.Cu" "In15.Cu")
		(hatch none 0.5)
		(connect_pads
			(clearance 0)
		)
		(min_thickness 0.25)
		(keepout
			(tracks not_allowed)
			(vias allowed)
			(pads allowed)
			(copperpour not_allowed)
			(footprints allowed)
		)
		(placement
			(enabled no)
			(sheetname "")
		)
		(fill yes
			(thermal_gap 0.5)
			(thermal_bridge_width 0.5)
			(island_removal_mode 0)
		)
		(polygon
			(pts
				(arc
					(start 440.250072 -227.91674)
					(mid 439.597292 -227.91674)
					(end 440.250072 -227.91674)
				)
			)
		)
	)
	(zone
		(layers "B.Cu" "In11.Cu" "In13.Cu" "In15.Cu")
		(hatch none 0.5)
		(connect_pads
			(clearance 0)
		)
		(min_thickness 0.25)
		(keepout
			(tracks not_allowed)
			(vias allowed)
			(pads allowed)
			(copperpour not_allowed)
			(footprints allowed)
		)
		(placement
			(enabled no)
			(sheetname "")
		)
		(fill yes
			(thermal_gap 0.5)
			(thermal_bridge_width 0.5)
			(island_removal_mode 0)
		)
		(polygon
			(pts
				(arc
					(start 343.570052 -261.244842)
					(mid 342.917272 -261.244842)
					(end 343.570052 -261.244842)
				)
			)
		)
	)
	(zone
		(layers "B.Cu" "In11.Cu" "In13.Cu" "In15.Cu")
		(hatch none 0.5)
		(connect_pads
			(clearance 0)
		)
		(min_thickness 0.25)
		(keepout
			(tracks not_allowed)
			(vias allowed)
			(pads allowed)
			(copperpour not_allowed)
			(footprints allowed)
		)
		(placement
			(enabled no)
			(sheetname "")
		)
		(fill yes
			(thermal_gap 0.5)
			(thermal_bridge_width 0.5)
			(island_removal_mode 0)
		)
		(polygon
			(pts
				(arc
					(start 96.100138 -257.175254)
					(mid 95.447358 -257.175254)
					(end 96.100138 -257.175254)
				)
			)
		)
	)
	(zone
		(layers "B.Cu" "In11.Cu" "In13.Cu" "In15.Cu")
		(hatch none 0.5)
		(connect_pads
			(clearance 0)
		)
		(min_thickness 0.25)
		(keepout
			(tracks not_allowed)
			(vias allowed)
			(pads allowed)
			(copperpour not_allowed)
			(footprints allowed)
		)
		(placement
			(enabled no)
			(sheetname "")
		)
		(fill yes
			(thermal_gap 0.5)
			(thermal_bridge_width 0.5)
			(island_removal_mode 0)
		)
		(polygon
			(pts
				(arc
					(start 341.220552 -283.219906)
					(mid 340.567772 -283.219906)
					(end 341.220552 -283.219906)
				)
			)
		)
	)
	(zone
		(layers "B.Cu" "In11.Cu" "In13.Cu" "In15.Cu")
		(hatch none 0.5)
		(connect_pads
			(clearance 0)
		)
		(min_thickness 0.25)
		(keepout
			(tracks not_allowed)
			(vias allowed)
			(pads allowed)
			(copperpour not_allowed)
			(footprints allowed)
		)
		(placement
			(enabled no)
			(sheetname "")
		)
		(fill yes
			(thermal_gap 0.5)
			(thermal_bridge_width 0.5)
			(island_removal_mode 0)
		)
		(polygon
			(pts
				(arc
					(start 126.154942 -430.889918)
					(mid 125.34519 -430.889918)
					(end 126.154942 -430.889918)
				)
			)
		)
	)
	(zone
		(layers "B.Cu" "In11.Cu" "In13.Cu" "In15.Cu")
		(hatch none 0.5)
		(connect_pads
			(clearance 0)
		)
		(min_thickness 0.25)
		(keepout
			(tracks not_allowed)
			(vias allowed)
			(pads allowed)
			(copperpour not_allowed)
			(footprints allowed)
		)
		(placement
			(enabled no)
			(sheetname "")
		)
		(fill yes
			(thermal_gap 0.5)
			(thermal_bridge_width 0.5)
			(island_removal_mode 0)
		)
		(polygon
			(pts
				(arc
					(start 385.751324 -218.692222)
					(mid 385.098544 -218.692222)
					(end 385.751324 -218.692222)
				)
			)
		)
	)
	(zone
		(layers "B.Cu" "In11.Cu" "In13.Cu" "In15.Cu")
		(hatch none 0.5)
		(connect_pads
			(clearance 0)
		)
		(min_thickness 0.25)
		(keepout
			(tracks not_allowed)
			(vias allowed)
			(pads allowed)
			(copperpour not_allowed)
			(footprints allowed)
		)
		(placement
			(enabled no)
			(sheetname "")
		)
		(fill yes
			(thermal_gap 0.5)
			(thermal_bridge_width 0.5)
			(island_removal_mode 0)
		)
		(polygon
			(pts
				(arc
					(start 377.402852 -262.872474)
					(mid 376.750072 -262.872474)
					(end 377.402852 -262.872474)
				)
			)
		)
	)
	(zone
		(layers "B.Cu" "In11.Cu" "In13.Cu" "In15.Cu")
		(hatch none 0.5)
		(connect_pads
			(clearance 0)
		)
		(min_thickness 0.25)
		(keepout
			(tracks not_allowed)
			(vias allowed)
			(pads allowed)
			(copperpour not_allowed)
			(footprints allowed)
		)
		(placement
			(enabled no)
			(sheetname "")
		)
		(fill yes
			(thermal_gap 0.5)
			(thermal_bridge_width 0.5)
			(island_removal_mode 0)
		)
		(polygon
			(pts
				(arc
					(start 394.154914 -436.889906)
					(mid 393.345162 -436.889906)
					(end 394.154914 -436.889906)
				)
			)
		)
	)
	(zone
		(layers "B.Cu" "In11.Cu" "In13.Cu" "In15.Cu")
		(hatch none 0.5)
		(connect_pads
			(clearance 0)
		)
		(min_thickness 0.25)
		(keepout
			(tracks not_allowed)
			(vias allowed)
			(pads allowed)
			(copperpour not_allowed)
			(footprints allowed)
		)
		(placement
			(enabled no)
			(sheetname "")
		)
		(fill yes
			(thermal_gap 0.5)
			(thermal_bridge_width 0.5)
			(island_removal_mode 0)
		)
		(polygon
			(pts
				(arc
					(start 344.054938 -434.48986)
					(mid 343.245186 -434.48986)
					(end 344.054938 -434.48986)
				)
			)
		)
	)
	(zone
		(layers "B.Cu" "In11.Cu" "In13.Cu" "In15.Cu")
		(hatch none 0.5)
		(connect_pads
			(clearance 0)
		)
		(min_thickness 0.25)
		(keepout
			(tracks not_allowed)
			(vias allowed)
			(pads allowed)
			(copperpour not_allowed)
			(footprints allowed)
		)
		(placement
			(enabled no)
			(sheetname "")
		)
		(fill yes
			(thermal_gap 0.5)
			(thermal_bridge_width 0.5)
			(island_removal_mode 0)
		)
		(polygon
			(pts
				(arc
					(start 128.522984 -274.266914)
					(mid 127.870204 -274.266914)
					(end 128.522984 -274.266914)
				)
			)
		)
	)
	(zone
		(layers "B.Cu" "In11.Cu" "In13.Cu" "In15.Cu")
		(hatch none 0.5)
		(connect_pads
			(clearance 0)
		)
		(min_thickness 0.25)
		(keepout
			(tracks not_allowed)
			(vias allowed)
			(pads allowed)
			(copperpour not_allowed)
			(footprints allowed)
		)
		(placement
			(enabled no)
			(sheetname "")
		)
		(fill yes
			(thermal_gap 0.5)
			(thermal_bridge_width 0.5)
			(island_removal_mode 0)
		)
		(polygon
			(pts
				(arc
					(start 349.679006 -283.219906)
					(mid 349.026226 -283.219906)
					(end 349.679006 -283.219906)
				)
			)
		)
	)
	(zone
		(layers "B.Cu" "In11.Cu" "In13.Cu" "In15.Cu")
		(hatch none 0.5)
		(connect_pads
			(clearance 0)
		)
		(min_thickness 0.25)
		(keepout
			(tracks not_allowed)
			(vias allowed)
			(pads allowed)
			(copperpour not_allowed)
			(footprints allowed)
		)
		(placement
			(enabled no)
			(sheetname "")
		)
		(fill yes
			(thermal_gap 0.5)
			(thermal_bridge_width 0.5)
			(island_removal_mode 0)
		)
		(polygon
			(pts
				(arc
					(start 345.33967 -238.225584)
					(mid 344.68689 -238.225584)
					(end 345.33967 -238.225584)
				)
			)
		)
	)
	(zone
		(layers "B.Cu" "In11.Cu" "In13.Cu" "In15.Cu")
		(hatch none 0.5)
		(connect_pads
			(clearance 0)
		)
		(min_thickness 0.25)
		(keepout
			(tracks not_allowed)
			(vias allowed)
			(pads allowed)
			(copperpour not_allowed)
			(footprints allowed)
		)
		(placement
			(enabled no)
			(sheetname "")
		)
		(fill yes
			(thermal_gap 0.5)
			(thermal_bridge_width 0.5)
			(island_removal_mode 0)
		)
		(polygon
			(pts
				(arc
					(start 149.422104 -410.030168)
					(mid 148.718524 -410.030168)
					(end 149.422104 -410.030168)
				)
			)
		)
	)
	(zone
		(layers "B.Cu" "In11.Cu" "In13.Cu" "In15.Cu")
		(hatch none 0.5)
		(connect_pads
			(clearance 0)
		)
		(min_thickness 0.25)
		(keepout
			(tracks not_allowed)
			(vias allowed)
			(pads allowed)
			(copperpour not_allowed)
			(footprints allowed)
		)
		(placement
			(enabled no)
			(sheetname "")
		)
		(fill yes
			(thermal_gap 0.5)
			(thermal_bridge_width 0.5)
			(island_removal_mode 0)
		)
		(polygon
			(pts
				(arc
					(start 357.086916 -214.622634)
					(mid 356.434136 -214.622634)
					(end 357.086916 -214.622634)
				)
			)
		)
	)
	(zone
		(layers "B.Cu" "In11.Cu" "In13.Cu" "In15.Cu")
		(hatch none 0.5)
		(connect_pads
			(clearance 0)
		)
		(min_thickness 0.25)
		(keepout
			(tracks not_allowed)
			(vias allowed)
			(pads allowed)
			(copperpour not_allowed)
			(footprints allowed)
		)
		(placement
			(enabled no)
			(sheetname "")
		)
		(fill yes
			(thermal_gap 0.5)
			(thermal_bridge_width 0.5)
			(island_removal_mode 0)
		)
		(polygon
			(pts
				(arc
					(start 149.154896 -439.0898)
					(mid 148.345144 -439.0898)
					(end 149.154896 -439.0898)
				)
			)
		)
	)
	(zone
		(layers "B.Cu" "In11.Cu" "In13.Cu" "In15.Cu")
		(hatch none 0.5)
		(connect_pads
			(clearance 0)
		)
		(min_thickness 0.25)
		(keepout
			(tracks not_allowed)
			(vias allowed)
			(pads allowed)
			(copperpour not_allowed)
			(footprints allowed)
		)
		(placement
			(enabled no)
			(sheetname "")
		)
		(fill yes
			(thermal_gap 0.5)
			(thermal_bridge_width 0.5)
			(island_removal_mode 0)
		)
		(polygon
			(pts
				(arc
					(start 371.398546 -172.438568)
					(mid 370.694966 -172.438568)
					(end 371.398546 -172.438568)
				)
			)
		)
	)
	(zone
		(layers "B.Cu" "In11.Cu" "In13.Cu" "In15.Cu")
		(hatch none 0.5)
		(connect_pads
			(clearance 0)
		)
		(min_thickness 0.25)
		(keepout
			(tracks not_allowed)
			(vias allowed)
			(pads allowed)
			(copperpour not_allowed)
			(footprints allowed)
		)
		(placement
			(enabled no)
			(sheetname "")
		)
		(fill yes
			(thermal_gap 0.5)
			(thermal_bridge_width 0.5)
			(island_removal_mode 0)
		)
		(polygon
			(pts
				(arc
					(start 344.979498 -260.430772)
					(mid 344.326718 -260.430772)
					(end 344.979498 -260.430772)
				)
			)
		)
	)
	(zone
		(layers "B.Cu" "In11.Cu" "In13.Cu" "In15.Cu")
		(hatch none 0.5)
		(connect_pads
			(clearance 0)
		)
		(min_thickness 0.25)
		(keepout
			(tracks not_allowed)
			(vias allowed)
			(pads allowed)
			(copperpour not_allowed)
			(footprints allowed)
		)
		(placement
			(enabled no)
			(sheetname "")
		)
		(fill yes
			(thermal_gap 0.5)
			(thermal_bridge_width 0.5)
			(island_removal_mode 0)
		)
		(polygon
			(pts
				(arc
					(start 127.942848 -214.622634)
					(mid 127.290068 -214.622634)
					(end 127.942848 -214.622634)
				)
			)
		)
	)
	(zone
		(layers "B.Cu" "In11.Cu" "In13.Cu" "In15.Cu")
		(hatch none 0.5)
		(connect_pads
			(clearance 0)
		)
		(min_thickness 0.25)
		(keepout
			(tracks not_allowed)
			(vias allowed)
			(pads allowed)
			(copperpour not_allowed)
			(footprints allowed)
		)
		(placement
			(enabled no)
			(sheetname "")
		)
		(fill yes
			(thermal_gap 0.5)
			(thermal_bridge_width 0.5)
			(island_removal_mode 0)
		)
		(polygon
			(pts
				(arc
					(start 436.150004 -198.166736)
					(mid 435.497224 -198.166736)
					(end 436.150004 -198.166736)
				)
			)
		)
	)
	(zone
		(layers "B.Cu" "In11.Cu" "In13.Cu" "In15.Cu")
		(hatch none 0.5)
		(connect_pads
			(clearance 0)
		)
		(min_thickness 0.25)
		(keepout
			(tracks not_allowed)
			(vias allowed)
			(pads allowed)
			(copperpour not_allowed)
			(footprints allowed)
		)
		(placement
			(enabled no)
			(sheetname "")
		)
		(fill yes
			(thermal_gap 0.5)
			(thermal_bridge_width 0.5)
			(island_removal_mode 0)
		)
		(polygon
			(pts
				(arc
					(start 375.523252 -269.38351)
					(mid 374.870472 -269.38351)
					(end 375.523252 -269.38351)
				)
			)
		)
	)
	(zone
		(layers "B.Cu" "In11.Cu" "In13.Cu" "In15.Cu")
		(hatch none 0.5)
		(connect_pads
			(clearance 0)
		)
		(min_thickness 0.25)
		(keepout
			(tracks not_allowed)
			(vias allowed)
			(pads allowed)
			(copperpour not_allowed)
			(footprints allowed)
		)
		(placement
			(enabled no)
			(sheetname "")
		)
		(fill yes
			(thermal_gap 0.5)
			(thermal_bridge_width 0.5)
			(island_removal_mode 0)
		)
		(polygon
			(pts
				(arc
					(start 404.61692 -410.030168)
					(mid 403.91334 -410.030168)
					(end 404.61692 -410.030168)
				)
			)
		)
	)
	(zone
		(layers "B.Cu" "In11.Cu" "In13.Cu" "In15.Cu")
		(hatch none 0.5)
		(connect_pads
			(clearance 0)
		)
		(min_thickness 0.25)
		(keepout
			(tracks not_allowed)
			(vias allowed)
			(pads allowed)
			(copperpour not_allowed)
			(footprints allowed)
		)
		(placement
			(enabled no)
			(sheetname "")
		)
		(fill yes
			(thermal_gap 0.5)
			(thermal_bridge_width 0.5)
			(island_removal_mode 0)
		)
		(polygon
			(pts
				(arc
					(start 130.872738 -253.919736)
					(mid 130.219958 -253.919736)
					(end 130.872738 -253.919736)
				)
			)
		)
	)
	(zone
		(layers "B.Cu" "In11.Cu" "In13.Cu" "In15.Cu")
		(hatch none 0.5)
		(connect_pads
			(clearance 0)
		)
		(min_thickness 0.25)
		(keepout
			(tracks not_allowed)
			(vias allowed)
			(pads allowed)
			(copperpour not_allowed)
			(footprints allowed)
		)
		(placement
			(enabled no)
			(sheetname "")
		)
		(fill yes
			(thermal_gap 0.5)
			(thermal_bridge_width 0.5)
			(island_removal_mode 0)
		)
		(polygon
			(pts
				(arc
					(start 269.155672 -209.216752)
					(mid 268.502892 -209.216752)
					(end 269.155672 -209.216752)
				)
			)
		)
	)
	(zone
		(layers "B.Cu" "In11.Cu" "In13.Cu" "In15.Cu")
		(hatch none 0.5)
		(connect_pads
			(clearance 0)
		)
		(min_thickness 0.25)
		(keepout
			(tracks not_allowed)
			(vias allowed)
			(pads allowed)
			(copperpour not_allowed)
			(footprints allowed)
		)
		(placement
			(enabled no)
			(sheetname "")
		)
		(fill yes
			(thermal_gap 0.5)
			(thermal_bridge_width 0.5)
			(island_removal_mode 0)
		)
		(polygon
			(pts
				(arc
					(start 97.979738 -281.59202)
					(mid 97.326958 -281.59202)
					(end 97.979738 -281.59202)
				)
			)
		)
	)
	(zone
		(layers "B.Cu" "In11.Cu" "In13.Cu" "In15.Cu")
		(hatch none 0.5)
		(connect_pads
			(clearance 0)
		)
		(min_thickness 0.25)
		(keepout
			(tracks not_allowed)
			(vias allowed)
			(pads allowed)
			(copperpour not_allowed)
			(footprints allowed)
		)
		(placement
			(enabled no)
			(sheetname "")
		)
		(fill yes
			(thermal_gap 0.5)
			(thermal_bridge_width 0.5)
			(island_removal_mode 0)
		)
		(polygon
			(pts
				(arc
					(start 390.154922 -430.889918)
					(mid 389.34517 -430.889918)
					(end 390.154922 -430.889918)
				)
			)
		)
	)
	(zone
		(layers "B.Cu" "In11.Cu" "In13.Cu" "In15.Cu")
		(hatch none 0.5)
		(connect_pads
			(clearance 0)
		)
		(min_thickness 0.25)
		(keepout
			(tracks not_allowed)
			(vias allowed)
			(pads allowed)
			(copperpour not_allowed)
			(footprints allowed)
		)
		(placement
			(enabled no)
			(sheetname "")
		)
		(fill yes
			(thermal_gap 0.5)
			(thermal_bridge_width 0.5)
			(island_removal_mode 0)
		)
		(polygon
			(pts
				(arc
					(start 351.918524 -213.732618)
					(mid 351.265744 -213.732618)
					(end 351.918524 -213.732618)
				)
			)
		)
	)
	(zone
		(layers "B.Cu" "In11.Cu" "In13.Cu" "In15.Cu")
		(hatch none 0.5)
		(connect_pads
			(clearance 0)
		)
		(min_thickness 0.25)
		(keepout
			(tracks not_allowed)
			(vias allowed)
			(pads allowed)
			(copperpour not_allowed)
			(footprints allowed)
		)
		(placement
			(enabled no)
			(sheetname "")
		)
		(fill yes
			(thermal_gap 0.5)
			(thermal_bridge_width 0.5)
			(island_removal_mode 0)
		)
		(polygon
			(pts
				(arc
					(start 440.208162 -272.116804)
					(mid 439.555382 -272.116804)
					(end 440.208162 -272.116804)
				)
			)
		)
	)
	(zone
		(layers "B.Cu" "In11.Cu" "In13.Cu" "In15.Cu")
		(hatch none 0.5)
		(connect_pads
			(clearance 0)
		)
		(min_thickness 0.25)
		(keepout
			(tracks not_allowed)
			(vias allowed)
			(pads allowed)
			(copperpour not_allowed)
			(footprints allowed)
		)
		(placement
			(enabled no)
			(sheetname "")
		)
		(fill yes
			(thermal_gap 0.5)
			(thermal_bridge_width 0.5)
			(island_removal_mode 0)
		)
		(polygon
			(pts
				(arc
					(start 88.054942 -434.48986)
					(mid 87.24519 -434.48986)
					(end 88.054942 -434.48986)
				)
			)
		)
	)
	(zone
		(layers "B.Cu" "In11.Cu" "In13.Cu" "In15.Cu")
		(hatch none 0.5)
		(connect_pads
			(clearance 0)
		)
		(min_thickness 0.25)
		(keepout
			(tracks not_allowed)
			(vias allowed)
			(pads allowed)
			(copperpour not_allowed)
			(footprints allowed)
		)
		(placement
			(enabled no)
			(sheetname "")
		)
		(fill yes
			(thermal_gap 0.5)
			(thermal_bridge_width 0.5)
			(island_removal_mode 0)
		)
		(polygon
			(pts
				(arc
					(start 128.843024 -410.030168)
					(mid 128.139444 -410.030168)
					(end 128.843024 -410.030168)
				)
			)
		)
	)
	(zone
		(layers "B.Cu" "In11.Cu" "In13.Cu" "In15.Cu")
		(hatch none 0.5)
		(connect_pads
			(clearance 0)
		)
		(min_thickness 0.25)
		(keepout
			(tracks not_allowed)
			(vias allowed)
			(pads allowed)
			(copperpour not_allowed)
			(footprints allowed)
		)
		(placement
			(enabled no)
			(sheetname "")
		)
		(fill yes
			(thermal_gap 0.5)
			(thermal_bridge_width 0.5)
			(island_removal_mode 0)
		)
		(polygon
			(pts
				(arc
					(start 350.618806 -281.59202)
					(mid 349.966026 -281.59202)
					(end 350.618806 -281.59202)
				)
			)
		)
	)
	(zone
		(layers "B.Cu" "In11.Cu" "In13.Cu" "In15.Cu")
		(hatch none 0.5)
		(connect_pads
			(clearance 0)
		)
		(min_thickness 0.25)
		(keepout
			(tracks not_allowed)
			(vias allowed)
			(pads allowed)
			(copperpour not_allowed)
			(footprints allowed)
		)
		(placement
			(enabled no)
			(sheetname "")
		)
		(fill yes
			(thermal_gap 0.5)
			(thermal_bridge_width 0.5)
			(island_removal_mode 0)
		)
		(polygon
			(pts
				(arc
					(start 36.303204 -285.716726)
					(mid 35.650424 -285.716726)
					(end 36.303204 -285.716726)
				)
			)
		)
	)
	(zone
		(layers "B.Cu" "In11.Cu" "In13.Cu" "In15.Cu")
		(hatch none 0.5)
		(connect_pads
			(clearance 0)
		)
		(min_thickness 0.25)
		(keepout
			(tracks not_allowed)
			(vias allowed)
			(pads allowed)
			(copperpour not_allowed)
			(footprints allowed)
		)
		(placement
			(enabled no)
			(sheetname "")
		)
		(fill yes
			(thermal_gap 0.5)
			(thermal_bridge_width 0.5)
			(island_removal_mode 0)
		)
		(polygon
			(pts
				(arc
					(start 59.055 -426.089826)
					(mid 58.245248 -426.089826)
					(end 59.055 -426.089826)
				)
			)
		)
	)
	(zone
		(layers "B.Cu" "In11.Cu" "In13.Cu" "In15.Cu")
		(hatch none 0.5)
		(connect_pads
			(clearance 0)
		)
		(min_thickness 0.25)
		(keepout
			(tracks not_allowed)
			(vias allowed)
			(pads allowed)
			(copperpour not_allowed)
			(footprints allowed)
		)
		(placement
			(enabled no)
			(sheetname "")
		)
		(fill yes
			(thermal_gap 0.5)
			(thermal_bridge_width 0.5)
			(island_removal_mode 0)
		)
		(polygon
			(pts
				(arc
					(start 375.053606 -271.825212)
					(mid 374.400826 -271.825212)
					(end 375.053606 -271.825212)
				)
			)
		)
	)
	(zone
		(layers "B.Cu" "In11.Cu" "In13.Cu" "In15.Cu")
		(hatch none 0.5)
		(connect_pads
			(clearance 0)
		)
		(min_thickness 0.25)
		(keepout
			(tracks not_allowed)
			(vias allowed)
			(pads allowed)
			(copperpour not_allowed)
			(footprints allowed)
		)
		(placement
			(enabled no)
			(sheetname "")
		)
		(fill yes
			(thermal_gap 0.5)
			(thermal_bridge_width 0.5)
			(island_removal_mode 0)
		)
		(polygon
			(pts
				(arc
					(start 103.978456 -213.732618)
					(mid 103.325676 -213.732618)
					(end 103.978456 -213.732618)
				)
			)
		)
	)
	(zone
		(layers "B.Cu" "In11.Cu" "In13.Cu" "In15.Cu")
		(hatch none 0.5)
		(connect_pads
			(clearance 0)
		)
		(min_thickness 0.25)
		(keepout
			(tracks not_allowed)
			(vias allowed)
			(pads allowed)
			(copperpour not_allowed)
			(footprints allowed)
		)
		(placement
			(enabled no)
			(sheetname "")
		)
		(fill yes
			(thermal_gap 0.5)
			(thermal_bridge_width 0.5)
			(island_removal_mode 0)
		)
		(polygon
			(pts
				(arc
					(start 342.990424 -227.64496)
					(mid 342.337644 -227.64496)
					(end 342.990424 -227.64496)
				)
			)
		)
	)
	(zone
		(layers "B.Cu" "In11.Cu" "In13.Cu" "In15.Cu")
		(hatch none 0.5)
		(connect_pads
			(clearance 0)
		)
		(min_thickness 0.25)
		(keepout
			(tracks not_allowed)
			(vias allowed)
			(pads allowed)
			(copperpour not_allowed)
			(footprints allowed)
		)
		(placement
			(enabled no)
			(sheetname "")
		)
		(fill yes
			(thermal_gap 0.5)
			(thermal_bridge_width 0.5)
			(island_removal_mode 0)
		)
		(polygon
			(pts
				(arc
					(start 120.894856 -213.732618)
					(mid 120.242076 -213.732618)
					(end 120.894856 -213.732618)
				)
			)
		)
	)
	(zone
		(layers "B.Cu" "In11.Cu" "In13.Cu" "In15.Cu")
		(hatch none 0.5)
		(connect_pads
			(clearance 0)
		)
		(min_thickness 0.25)
		(keepout
			(tracks not_allowed)
			(vias allowed)
			(pads allowed)
			(copperpour not_allowed)
			(footprints allowed)
		)
		(placement
			(enabled no)
			(sheetname "")
		)
		(fill yes
			(thermal_gap 0.5)
			(thermal_bridge_width 0.5)
			(island_removal_mode 0)
		)
		(polygon
			(pts
				(arc
					(start 97.039938 -275.08073)
					(mid 96.387158 -275.08073)
					(end 97.039938 -275.08073)
				)
			)
		)
	)
	(zone
		(layers "B.Cu" "In11.Cu" "In13.Cu" "In15.Cu")
		(hatch none 0.5)
		(connect_pads
			(clearance 0)
		)
		(min_thickness 0.25)
		(keepout
			(tracks not_allowed)
			(vias allowed)
			(pads allowed)
			(copperpour not_allowed)
			(footprints allowed)
		)
		(placement
			(enabled no)
			(sheetname "")
		)
		(fill yes
			(thermal_gap 0.5)
			(thermal_bridge_width 0.5)
			(island_removal_mode 0)
		)
		(polygon
			(pts
				(arc
					(start 188.209936 -199.866758)
					(mid 187.557156 -199.866758)
					(end 188.209936 -199.866758)
				)
			)
		)
	)
	(zone
		(layers "B.Cu" "In11.Cu" "In13.Cu" "In15.Cu")
		(hatch none 0.5)
		(connect_pads
			(clearance 0)
		)
		(min_thickness 0.25)
		(keepout
			(tracks not_allowed)
			(vias allowed)
			(pads allowed)
			(copperpour not_allowed)
			(footprints allowed)
		)
		(placement
			(enabled no)
			(sheetname "")
		)
		(fill yes
			(thermal_gap 0.5)
			(thermal_bridge_width 0.5)
			(island_removal_mode 0)
		)
		(polygon
			(pts
				(arc
					(start 342.054942 -428.28972)
					(mid 341.24519 -428.28972)
					(end 342.054942 -428.28972)
				)
			)
		)
	)
	(zone
		(layers "B.Cu" "In11.Cu" "In13.Cu" "In15.Cu")
		(hatch none 0.5)
		(connect_pads
			(clearance 0)
		)
		(min_thickness 0.25)
		(keepout
			(tracks not_allowed)
			(vias allowed)
			(pads allowed)
			(copperpour not_allowed)
			(footprints allowed)
		)
		(placement
			(enabled no)
			(sheetname "")
		)
		(fill yes
			(thermal_gap 0.5)
			(thermal_bridge_width 0.5)
			(island_removal_mode 0)
		)
		(polygon
			(pts
				(arc
					(start 345.919806 -270.19758)
					(mid 345.267026 -270.19758)
					(end 345.919806 -270.19758)
				)
			)
		)
	)
	(zone
		(layers "B.Cu" "In11.Cu" "In13.Cu" "In15.Cu")
		(hatch none 0.5)
		(connect_pads
			(clearance 0)
		)
		(min_thickness 0.25)
		(keepout
			(tracks not_allowed)
			(vias allowed)
			(pads allowed)
			(copperpour not_allowed)
			(footprints allowed)
		)
		(placement
			(enabled no)
			(sheetname "")
		)
		(fill yes
			(thermal_gap 0.5)
			(thermal_bridge_width 0.5)
			(island_removal_mode 0)
		)
		(polygon
			(pts
				(arc
					(start 284.243272 -199.866758)
					(mid 283.590492 -199.866758)
					(end 284.243272 -199.866758)
				)
			)
		)
	)
	(zone
		(layers "B.Cu" "In11.Cu" "In13.Cu" "In15.Cu")
		(hatch none 0.5)
		(connect_pads
			(clearance 0)
		)
		(min_thickness 0.25)
		(keepout
			(tracks not_allowed)
			(vias allowed)
			(pads allowed)
			(copperpour not_allowed)
			(footprints allowed)
		)
		(placement
			(enabled no)
			(sheetname "")
		)
		(fill yes
			(thermal_gap 0.5)
			(thermal_bridge_width 0.5)
			(island_removal_mode 0)
		)
		(polygon
			(pts
				(arc
					(start 280.143204 -222.816674)
					(mid 279.490424 -222.816674)
					(end 280.143204 -222.816674)
				)
			)
		)
	)
	(zone
		(layers "B.Cu" "In11.Cu" "In13.Cu" "In15.Cu")
		(hatch none 0.5)
		(connect_pads
			(clearance 0)
		)
		(min_thickness 0.25)
		(keepout
			(tracks not_allowed)
			(vias allowed)
			(pads allowed)
			(copperpour not_allowed)
			(footprints allowed)
		)
		(placement
			(enabled no)
			(sheetname "")
		)
		(fill yes
			(thermal_gap 0.5)
			(thermal_bridge_width 0.5)
			(island_removal_mode 0)
		)
		(polygon
			(pts
				(arc
					(start 374.47347 -239.853216)
					(mid 373.82069 -239.853216)
					(end 374.47347 -239.853216)
				)
			)
		)
	)
	(zone
		(layers "B.Cu" "In11.Cu" "In13.Cu" "In15.Cu")
		(hatch none 0.5)
		(connect_pads
			(clearance 0)
		)
		(min_thickness 0.25)
		(keepout
			(tracks not_allowed)
			(vias allowed)
			(pads allowed)
			(copperpour not_allowed)
			(footprints allowed)
		)
		(placement
			(enabled no)
			(sheetname "")
		)
		(fill yes
			(thermal_gap 0.5)
			(thermal_bridge_width 0.5)
			(island_removal_mode 0)
		)
		(polygon
			(pts
				(arc
					(start 366.95507 -226.831144)
					(mid 366.30229 -226.831144)
					(end 366.95507 -226.831144)
				)
			)
		)
	)
	(zone
		(layers "B.Cu" "In11.Cu" "In13.Cu" "In15.Cu")
		(hatch none 0.5)
		(connect_pads
			(clearance 0)
		)
		(min_thickness 0.25)
		(keepout
			(tracks not_allowed)
			(vias allowed)
			(pads allowed)
			(copperpour not_allowed)
			(footprints allowed)
		)
		(placement
			(enabled no)
			(sheetname "")
		)
		(fill yes
			(thermal_gap 0.5)
			(thermal_bridge_width 0.5)
			(island_removal_mode 0)
		)
		(polygon
			(pts
				(arc
					(start 91.290648 -214.622634)
					(mid 90.637868 -214.622634)
					(end 91.290648 -214.622634)
				)
			)
		)
	)
	(zone
		(layers "B.Cu" "In11.Cu" "In13.Cu" "In15.Cu")
		(hatch none 0.5)
		(connect_pads
			(clearance 0)
		)
		(min_thickness 0.25)
		(keepout
			(tracks not_allowed)
			(vias allowed)
			(pads allowed)
			(copperpour not_allowed)
			(footprints allowed)
		)
		(placement
			(enabled no)
			(sheetname "")
		)
		(fill yes
			(thermal_gap 0.5)
			(thermal_bridge_width 0.5)
			(island_removal_mode 0)
		)
		(polygon
			(pts
				(arc
					(start 132.15493 -430.689766)
					(mid 131.345178 -430.689766)
					(end 132.15493 -430.689766)
				)
			)
		)
	)
	(zone
		(layers "B.Cu" "In11.Cu" "In13.Cu" "In15.Cu")
		(hatch none 0.5)
		(connect_pads
			(clearance 0)
		)
		(min_thickness 0.25)
		(keepout
			(tracks not_allowed)
			(vias allowed)
			(pads allowed)
			(copperpour not_allowed)
			(footprints allowed)
		)
		(placement
			(enabled no)
			(sheetname "")
		)
		(fill yes
			(thermal_gap 0.5)
			(thermal_bridge_width 0.5)
			(island_removal_mode 0)
		)
		(polygon
			(pts
				(arc
					(start 284.243272 -217.716608)
					(mid 283.590492 -217.716608)
					(end 284.243272 -217.716608)
				)
			)
		)
	)
	(zone
		(layers "B.Cu" "In11.Cu" "In13.Cu" "In15.Cu")
		(hatch none 0.5)
		(connect_pads
			(clearance 0)
		)
		(min_thickness 0.25)
		(keepout
			(tracks not_allowed)
			(vias allowed)
			(pads allowed)
			(copperpour not_allowed)
			(footprints allowed)
		)
		(placement
			(enabled no)
			(sheetname "")
		)
		(fill yes
			(thermal_gap 0.5)
			(thermal_bridge_width 0.5)
			(island_removal_mode 0)
		)
		(polygon
			(pts
				(arc
					(start 375.053606 -262.058658)
					(mid 374.400826 -262.058658)
					(end 375.053606 -262.058658)
				)
			)
		)
	)
	(zone
		(layers "B.Cu" "In11.Cu" "In13.Cu" "In15.Cu")
		(hatch none 0.5)
		(connect_pads
			(clearance 0)
		)
		(min_thickness 0.25)
		(keepout
			(tracks not_allowed)
			(vias allowed)
			(pads allowed)
			(copperpour not_allowed)
			(footprints allowed)
		)
		(placement
			(enabled no)
			(sheetname "")
		)
		(fill yes
			(thermal_gap 0.5)
			(thermal_bridge_width 0.5)
			(island_removal_mode 0)
		)
		(polygon
			(pts
				(arc
					(start 376.35307 -239.853216)
					(mid 375.70029 -239.853216)
					(end 376.35307 -239.853216)
				)
			)
		)
	)
	(zone
		(layers "B.Cu" "In11.Cu" "In13.Cu" "In15.Cu")
		(hatch none 0.5)
		(connect_pads
			(clearance 0)
		)
		(min_thickness 0.25)
		(keepout
			(tracks not_allowed)
			(vias allowed)
			(pads allowed)
			(copperpour not_allowed)
			(footprints allowed)
		)
		(placement
			(enabled no)
			(sheetname "")
		)
		(fill yes
			(thermal_gap 0.5)
			(thermal_bridge_width 0.5)
			(island_removal_mode 0)
		)
		(polygon
			(pts
				(arc
					(start 401.1549 -431.889916)
					(mid 400.345148 -431.889916)
					(end 401.1549 -431.889916)
				)
			)
		)
	)
	(zone
		(layers "B.Cu" "In11.Cu" "In13.Cu" "In15.Cu")
		(hatch none 0.5)
		(connect_pads
			(clearance 0)
		)
		(min_thickness 0.25)
		(keepout
			(tracks not_allowed)
			(vias allowed)
			(pads allowed)
			(copperpour not_allowed)
			(footprints allowed)
		)
		(placement
			(enabled no)
			(sheetname "")
		)
		(fill yes
			(thermal_gap 0.5)
			(thermal_bridge_width 0.5)
			(island_removal_mode 0)
		)
		(polygon
			(pts
				(arc
					(start 343.930224 -240.667286)
					(mid 343.277444 -240.667286)
					(end 343.930224 -240.667286)
				)
			)
		)
	)
	(zone
		(layers "B.Cu" "In11.Cu" "In13.Cu" "In15.Cu")
		(hatch none 0.5)
		(connect_pads
			(clearance 0)
		)
		(min_thickness 0.25)
		(keepout
			(tracks not_allowed)
			(vias allowed)
			(pads allowed)
			(copperpour not_allowed)
			(footprints allowed)
		)
		(placement
			(enabled no)
			(sheetname "")
		)
		(fill yes
			(thermal_gap 0.5)
			(thermal_bridge_width 0.5)
			(island_removal_mode 0)
		)
		(polygon
			(pts
				(arc
					(start 192.268094 -272.116804)
					(mid 191.615314 -272.116804)
					(end 192.268094 -272.116804)
				)
			)
		)
	)
	(zone
		(layers "B.Cu" "In11.Cu" "In13.Cu" "In15.Cu")
		(hatch none 0.5)
		(connect_pads
			(clearance 0)
		)
		(min_thickness 0.25)
		(keepout
			(tracks not_allowed)
			(vias allowed)
			(pads allowed)
			(copperpour not_allowed)
			(footprints allowed)
		)
		(placement
			(enabled no)
			(sheetname "")
		)
		(fill yes
			(thermal_gap 0.5)
			(thermal_bridge_width 0.5)
			(island_removal_mode 0)
		)
		(polygon
			(pts
				(arc
					(start 95.990156 -242.294918)
					(mid 95.337376 -242.294918)
					(end 95.990156 -242.294918)
				)
			)
		)
	)
	(zone
		(layers "B.Cu" "In11.Cu" "In13.Cu" "In15.Cu")
		(hatch none 0.5)
		(connect_pads
			(clearance 0)
		)
		(min_thickness 0.25)
		(keepout
			(tracks not_allowed)
			(vias allowed)
			(pads allowed)
			(copperpour not_allowed)
			(footprints allowed)
		)
		(placement
			(enabled no)
			(sheetname "")
		)
		(fill yes
			(thermal_gap 0.5)
			(thermal_bridge_width 0.5)
			(island_removal_mode 0)
		)
		(polygon
			(pts
				(arc
					(start 351.144078 -403.883876)
					(mid 350.440498 -403.883876)
					(end 351.144078 -403.883876)
				)
			)
		)
	)
	(zone
		(layers "B.Cu" "In11.Cu" "In13.Cu" "In15.Cu")
		(hatch none 0.5)
		(connect_pads
			(clearance 0)
		)
		(min_thickness 0.25)
		(keepout
			(tracks not_allowed)
			(vias allowed)
			(pads allowed)
			(copperpour not_allowed)
			(footprints allowed)
		)
		(placement
			(enabled no)
			(sheetname "")
		)
		(fill yes
			(thermal_gap 0.5)
			(thermal_bridge_width 0.5)
			(island_removal_mode 0)
		)
		(polygon
			(pts
				(arc
					(start 410.7434 -410.030168)
					(mid 410.03982 -410.030168)
					(end 410.7434 -410.030168)
				)
			)
		)
	)
	(zone
		(layers "B.Cu" "In11.Cu" "In13.Cu" "In15.Cu")
		(hatch none 0.5)
		(connect_pads
			(clearance 0)
		)
		(min_thickness 0.25)
		(keepout
			(tracks not_allowed)
			(vias allowed)
			(pads allowed)
			(copperpour not_allowed)
			(footprints allowed)
		)
		(placement
			(enabled no)
			(sheetname "")
		)
		(fill yes
			(thermal_gap 0.5)
			(thermal_bridge_width 0.5)
			(island_removal_mode 0)
		)
		(polygon
			(pts
				(arc
					(start 109.617002 -215.436704)
					(mid 108.964222 -215.436704)
					(end 109.617002 -215.436704)
				)
			)
		)
	)
	(zone
		(layers "B.Cu" "In11.Cu" "In13.Cu" "In15.Cu")
		(hatch none 0.5)
		(connect_pads
			(clearance 0)
		)
		(min_thickness 0.25)
		(keepout
			(tracks not_allowed)
			(vias allowed)
			(pads allowed)
			(copperpour not_allowed)
			(footprints allowed)
		)
		(placement
			(enabled no)
			(sheetname "")
		)
		(fill yes
			(thermal_gap 0.5)
			(thermal_bridge_width 0.5)
			(island_removal_mode 0)
		)
		(polygon
			(pts
				(arc
					(start 150.285704 -410.030168)
					(mid 149.582124 -410.030168)
					(end 150.285704 -410.030168)
				)
			)
		)
	)
	(zone
		(layers "B.Cu" "In11.Cu" "In13.Cu" "In15.Cu")
		(hatch none 0.5)
		(connect_pads
			(clearance 0)
		)
		(min_thickness 0.25)
		(keepout
			(tracks not_allowed)
			(vias allowed)
			(pads allowed)
			(copperpour not_allowed)
			(footprints allowed)
		)
		(placement
			(enabled no)
			(sheetname "")
		)
		(fill yes
			(thermal_gap 0.5)
			(thermal_bridge_width 0.5)
			(island_removal_mode 0)
		)
		(polygon
			(pts
				(arc
					(start 344.870024 -237.411514)
					(mid 344.217244 -237.411514)
					(end 344.870024 -237.411514)
				)
			)
		)
	)
	(zone
		(layers "B.Cu" "In11.Cu" "In13.Cu" "In15.Cu")
		(hatch none 0.5)
		(connect_pads
			(clearance 0)
		)
		(min_thickness 0.25)
		(keepout
			(tracks not_allowed)
			(vias allowed)
			(pads allowed)
			(copperpour not_allowed)
			(footprints allowed)
		)
		(placement
			(enabled no)
			(sheetname "")
		)
		(fill yes
			(thermal_gap 0.5)
			(thermal_bridge_width 0.5)
			(island_removal_mode 0)
		)
		(polygon
			(pts
				(arc
					(start 97.869248 -214.622634)
					(mid 97.216468 -214.622634)
					(end 97.869248 -214.622634)
				)
			)
		)
	)
	(zone
		(layers "B.Cu" "In11.Cu" "In13.Cu" "In15.Cu")
		(hatch none 0.5)
		(connect_pads
			(clearance 0)
		)
		(min_thickness 0.25)
		(keepout
			(tracks not_allowed)
			(vias allowed)
			(pads allowed)
			(copperpour not_allowed)
			(footprints allowed)
		)
		(placement
			(enabled no)
			(sheetname "")
		)
		(fill yes
			(thermal_gap 0.5)
			(thermal_bridge_width 0.5)
			(island_removal_mode 0)
		)
		(polygon
			(pts
				(arc
					(start 375.41327 -239.853216)
					(mid 374.76049 -239.853216)
					(end 375.41327 -239.853216)
				)
			)
		)
	)
	(zone
		(layers "B.Cu" "In11.Cu" "In13.Cu" "In15.Cu")
		(hatch none 0.5)
		(connect_pads
			(clearance 0)
		)
		(min_thickness 0.25)
		(keepout
			(tracks not_allowed)
			(vias allowed)
			(pads allowed)
			(copperpour not_allowed)
			(footprints allowed)
		)
		(placement
			(enabled no)
			(sheetname "")
		)
		(fill yes
			(thermal_gap 0.5)
			(thermal_bridge_width 0.5)
			(island_removal_mode 0)
		)
		(polygon
			(pts
				(arc
					(start 382.31064 -410.030168)
					(mid 381.60706 -410.030168)
					(end 382.31064 -410.030168)
				)
			)
		)
	)
	(zone
		(layers "B.Cu" "In11.Cu" "In13.Cu" "In15.Cu")
		(hatch none 0.5)
		(connect_pads
			(clearance 0)
		)
		(min_thickness 0.25)
		(keepout
			(tracks not_allowed)
			(vias allowed)
			(pads allowed)
			(copperpour not_allowed)
			(footprints allowed)
		)
		(placement
			(enabled no)
			(sheetname "")
		)
		(fill yes
			(thermal_gap 0.5)
			(thermal_bridge_width 0.5)
			(island_removal_mode 0)
		)
		(polygon
			(pts
				(arc
					(start 97.039938 -253.919736)
					(mid 96.387158 -253.919736)
					(end 97.039938 -253.919736)
				)
			)
		)
	)
	(zone
		(layers "B.Cu" "In11.Cu" "In13.Cu" "In15.Cu")
		(hatch none 0.5)
		(connect_pads
			(clearance 0)
		)
		(min_thickness 0.25)
		(keepout
			(tracks not_allowed)
			(vias allowed)
			(pads allowed)
			(copperpour not_allowed)
			(footprints allowed)
		)
		(placement
			(enabled no)
			(sheetname "")
		)
		(fill yes
			(thermal_gap 0.5)
			(thermal_bridge_width 0.5)
			(island_removal_mode 0)
		)
		(polygon
			(pts
				(arc
					(start 127.473202 -230.086662)
					(mid 126.820422 -230.086662)
					(end 127.473202 -230.086662)
				)
			)
		)
	)
	(zone
		(layers "B.Cu" "In11.Cu" "In13.Cu" "In15.Cu")
		(hatch none 0.5)
		(connect_pads
			(clearance 0)
		)
		(min_thickness 0.25)
		(keepout
			(tracks not_allowed)
			(vias allowed)
			(pads allowed)
			(copperpour not_allowed)
			(footprints allowed)
		)
		(placement
			(enabled no)
			(sheetname "")
		)
		(fill yes
			(thermal_gap 0.5)
			(thermal_bridge_width 0.5)
			(island_removal_mode 0)
		)
		(polygon
			(pts
				(arc
					(start 280.143204 -286.56661)
					(mid 279.490424 -286.56661)
					(end 280.143204 -286.56661)
				)
			)
		)
	)
	(zone
		(layers "B.Cu" "In11.Cu" "In13.Cu" "In15.Cu")
		(hatch none 0.5)
		(connect_pads
			(clearance 0)
		)
		(min_thickness 0.25)
		(keepout
			(tracks not_allowed)
			(vias allowed)
			(pads allowed)
			(copperpour not_allowed)
			(footprints allowed)
		)
		(placement
			(enabled no)
			(sheetname "")
		)
		(fill yes
			(thermal_gap 0.5)
			(thermal_bridge_width 0.5)
			(island_removal_mode 0)
		)
		(polygon
			(pts
				(arc
					(start 344.040206 -262.058658)
					(mid 343.387426 -262.058658)
					(end 344.040206 -262.058658)
				)
			)
		)
	)
	(zone
		(layers "B.Cu" "In11.Cu" "In13.Cu" "In15.Cu")
		(hatch none 0.5)
		(connect_pads
			(clearance 0)
		)
		(min_thickness 0.25)
		(keepout
			(tracks not_allowed)
			(vias allowed)
			(pads allowed)
			(copperpour not_allowed)
			(footprints allowed)
		)
		(placement
			(enabled no)
			(sheetname "")
		)
		(fill yes
			(thermal_gap 0.5)
			(thermal_bridge_width 0.5)
			(island_removal_mode 0)
		)
		(polygon
			(pts
				(arc
					(start 344.578686 -72.299576)
					(mid 343.875106 -72.299576)
					(end 344.578686 -72.299576)
				)
			)
		)
	)
	(zone
		(layers "B.Cu" "In11.Cu" "In13.Cu" "In15.Cu")
		(hatch none 0.5)
		(connect_pads
			(clearance 0)
		)
		(min_thickness 0.25)
		(keepout
			(tracks not_allowed)
			(vias allowed)
			(pads allowed)
			(copperpour not_allowed)
			(footprints allowed)
		)
		(placement
			(enabled no)
			(sheetname "")
		)
		(fill yes
			(thermal_gap 0.5)
			(thermal_bridge_width 0.5)
			(island_removal_mode 0)
		)
		(polygon
			(pts
				(arc
					(start 357.55707 -215.436704)
					(mid 356.90429 -215.436704)
					(end 357.55707 -215.436704)
				)
			)
		)
	)
	(zone
		(layers "B.Cu" "In11.Cu" "In13.Cu" "In15.Cu")
		(hatch none 0.5)
		(connect_pads
			(clearance 0)
		)
		(min_thickness 0.25)
		(keepout
			(tracks not_allowed)
			(vias allowed)
			(pads allowed)
			(copperpour not_allowed)
			(footprints allowed)
		)
		(placement
			(enabled no)
			(sheetname "")
		)
		(fill yes
			(thermal_gap 0.5)
			(thermal_bridge_width 0.5)
			(island_removal_mode 0)
		)
		(polygon
			(pts
				(arc
					(start 131.812538 -279.964134)
					(mid 131.159758 -279.964134)
					(end 131.812538 -279.964134)
				)
			)
		)
	)
	(zone
		(layers "B.Cu" "In11.Cu" "In13.Cu" "In15.Cu")
		(hatch none 0.5)
		(connect_pads
			(clearance 0)
		)
		(min_thickness 0.25)
		(keepout
			(tracks not_allowed)
			(vias allowed)
			(pads allowed)
			(copperpour not_allowed)
			(footprints allowed)
		)
		(placement
			(enabled no)
			(sheetname "")
		)
		(fill yes
			(thermal_gap 0.5)
			(thermal_bridge_width 0.5)
			(island_removal_mode 0)
		)
		(polygon
			(pts
				(arc
					(start 98.339656 -213.732618)
					(mid 97.686876 -213.732618)
					(end 98.339656 -213.732618)
				)
			)
		)
	)
	(zone
		(layers "B.Cu" "In11.Cu" "In13.Cu" "In15.Cu")
		(hatch none 0.5)
		(connect_pads
			(clearance 0)
		)
		(min_thickness 0.25)
		(keepout
			(tracks not_allowed)
			(vias allowed)
			(pads allowed)
			(copperpour not_allowed)
			(footprints allowed)
		)
		(placement
			(enabled no)
			(sheetname "")
		)
		(fill yes
			(thermal_gap 0.5)
			(thermal_bridge_width 0.5)
			(island_removal_mode 0)
		)
		(polygon
			(pts
				(arc
					(start 98.919538 -253.919736)
					(mid 98.266758 -253.919736)
					(end 98.919538 -253.919736)
				)
			)
		)
	)
	(zone
		(layers "B.Cu" "In11.Cu" "In13.Cu" "In15.Cu")
		(hatch none 0.5)
		(connect_pads
			(clearance 0)
		)
		(min_thickness 0.25)
		(keepout
			(tracks not_allowed)
			(vias allowed)
			(pads allowed)
			(copperpour not_allowed)
			(footprints allowed)
		)
		(placement
			(enabled no)
			(sheetname "")
		)
		(fill yes
			(thermal_gap 0.5)
			(thermal_bridge_width 0.5)
			(island_removal_mode 0)
		)
		(polygon
			(pts
				(arc
					(start 128.413002 -230.086662)
					(mid 127.760222 -230.086662)
					(end 128.413002 -230.086662)
				)
			)
		)
	)
	(zone
		(layers "B.Cu" "In11.Cu" "In13.Cu" "In15.Cu")
		(hatch none 0.5)
		(connect_pads
			(clearance 0)
		)
		(min_thickness 0.25)
		(keepout
			(tracks not_allowed)
			(vias allowed)
			(pads allowed)
			(copperpour not_allowed)
			(footprints allowed)
		)
		(placement
			(enabled no)
			(sheetname "")
		)
		(fill yes
			(thermal_gap 0.5)
			(thermal_bridge_width 0.5)
			(island_removal_mode 0)
		)
		(polygon
			(pts
				(arc
					(start 149.154896 -431.889916)
					(mid 148.345144 -431.889916)
					(end 149.154896 -431.889916)
				)
			)
		)
	)
	(zone
		(layers "B.Cu" "In11.Cu" "In13.Cu" "In15.Cu")
		(hatch none 0.5)
		(connect_pads
			(clearance 0)
		)
		(min_thickness 0.25)
		(keepout
			(tracks not_allowed)
			(vias allowed)
			(pads allowed)
			(copperpour not_allowed)
			(footprints allowed)
		)
		(placement
			(enabled no)
			(sheetname "")
		)
		(fill yes
			(thermal_gap 0.5)
			(thermal_bridge_width 0.5)
			(island_removal_mode 0)
		)
		(polygon
			(pts
				(arc
					(start 36.303204 -227.91674)
					(mid 35.650424 -227.91674)
					(end 36.303204 -227.91674)
				)
			)
		)
	)
	(zone
		(layers "B.Cu" "In11.Cu" "In13.Cu" "In15.Cu")
		(hatch none 0.5)
		(connect_pads
			(clearance 0)
		)
		(min_thickness 0.25)
		(keepout
			(tracks not_allowed)
			(vias allowed)
			(pads allowed)
			(copperpour not_allowed)
			(footprints allowed)
		)
		(placement
			(enabled no)
			(sheetname "")
		)
		(fill yes
			(thermal_gap 0.5)
			(thermal_bridge_width 0.5)
			(island_removal_mode 0)
		)
		(polygon
			(pts
				(arc
					(start 355.67747 -226.831144)
					(mid 355.02469 -226.831144)
					(end 355.67747 -226.831144)
				)
			)
		)
	)
	(zone
		(layers "B.Cu" "In11.Cu" "In13.Cu" "In15.Cu")
		(hatch none 0.5)
		(connect_pads
			(clearance 0)
		)
		(min_thickness 0.25)
		(keepout
			(tracks not_allowed)
			(vias allowed)
			(pads allowed)
			(copperpour not_allowed)
			(footprints allowed)
		)
		(placement
			(enabled no)
			(sheetname "")
		)
		(fill yes
			(thermal_gap 0.5)
			(thermal_bridge_width 0.5)
			(island_removal_mode 0)
		)
		(polygon
			(pts
				(arc
					(start 108.317538 -275.08073)
					(mid 107.664758 -275.08073)
					(end 108.317538 -275.08073)
				)
			)
		)
	)
	(zone
		(layers "B.Cu" "In11.Cu" "In13.Cu" "In15.Cu")
		(hatch none 0.5)
		(connect_pads
			(clearance 0)
		)
		(min_thickness 0.25)
		(keepout
			(tracks not_allowed)
			(vias allowed)
			(pads allowed)
			(copperpour not_allowed)
			(footprints allowed)
		)
		(placement
			(enabled no)
			(sheetname "")
		)
		(fill yes
			(thermal_gap 0.5)
			(thermal_bridge_width 0.5)
			(island_removal_mode 0)
		)
		(polygon
			(pts
				(arc
					(start 95.990156 -227.64496)
					(mid 95.337376 -227.64496)
					(end 95.990156 -227.64496)
				)
			)
		)
	)
	(zone
		(layers "B.Cu" "In11.Cu" "In13.Cu" "In15.Cu")
		(hatch none 0.5)
		(connect_pads
			(clearance 0)
		)
		(min_thickness 0.25)
		(keepout
			(tracks not_allowed)
			(vias allowed)
			(pads allowed)
			(copperpour not_allowed)
			(footprints allowed)
		)
		(placement
			(enabled no)
			(sheetname "")
		)
		(fill yes
			(thermal_gap 0.5)
			(thermal_bridge_width 0.5)
			(island_removal_mode 0)
		)
		(polygon
			(pts
				(arc
					(start 280.143204 -305.266598)
					(mid 279.490424 -305.266598)
					(end 280.143204 -305.266598)
				)
			)
		)
	)
	(zone
		(layers "B.Cu" "In11.Cu" "In13.Cu" "In15.Cu")
		(hatch none 0.5)
		(connect_pads
			(clearance 0)
		)
		(min_thickness 0.25)
		(keepout
			(tracks not_allowed)
			(vias allowed)
			(pads allowed)
			(copperpour not_allowed)
			(footprints allowed)
		)
		(placement
			(enabled no)
			(sheetname "")
		)
		(fill yes
			(thermal_gap 0.5)
			(thermal_bridge_width 0.5)
			(island_removal_mode 0)
		)
		(polygon
			(pts
				(arc
					(start 451.237604 -308.666642)
					(mid 450.584824 -308.666642)
					(end 451.237604 -308.666642)
				)
			)
		)
	)
	(zone
		(layers "B.Cu" "In11.Cu" "In13.Cu" "In15.Cu")
		(hatch none 0.5)
		(connect_pads
			(clearance 0)
		)
		(min_thickness 0.25)
		(keepout
			(tracks not_allowed)
			(vias allowed)
			(pads allowed)
			(copperpour not_allowed)
			(footprints allowed)
		)
		(placement
			(enabled no)
			(sheetname "")
		)
		(fill yes
			(thermal_gap 0.5)
			(thermal_bridge_width 0.5)
			(island_removal_mode 0)
		)
		(polygon
			(pts
				(arc
					(start 353.095306 -65.329562)
					(mid 352.391726 -65.329562)
					(end 353.095306 -65.329562)
				)
			)
		)
	)
	(zone
		(layers "B.Cu" "In11.Cu" "In13.Cu" "In15.Cu")
		(hatch none 0.5)
		(connect_pads
			(clearance 0)
		)
		(min_thickness 0.25)
		(keepout
			(tracks not_allowed)
			(vias allowed)
			(pads allowed)
			(copperpour not_allowed)
			(footprints allowed)
		)
		(placement
			(enabled no)
			(sheetname "")
		)
		(fill yes
			(thermal_gap 0.5)
			(thermal_bridge_width 0.5)
			(island_removal_mode 0)
		)
		(polygon
			(pts
				(arc
					(start 136.401556 -217.878406)
					(mid 135.748776 -217.878406)
					(end 136.401556 -217.878406)
				)
			)
		)
	)
	(zone
		(layers "B.Cu" "In11.Cu" "In13.Cu" "In15.Cu")
		(hatch none 0.5)
		(connect_pads
			(clearance 0)
		)
		(min_thickness 0.25)
		(keepout
			(tracks not_allowed)
			(vias allowed)
			(pads allowed)
			(copperpour not_allowed)
			(footprints allowed)
		)
		(placement
			(enabled no)
			(sheetname "")
		)
		(fill yes
			(thermal_gap 0.5)
			(thermal_bridge_width 0.5)
			(island_removal_mode 0)
		)
		(polygon
			(pts
				(arc
					(start 343.570052 -254.733552)
					(mid 342.917272 -254.733552)
					(end 343.570052 -254.733552)
				)
			)
		)
	)
	(zone
		(layers "B.Cu" "In11.Cu" "In13.Cu" "In15.Cu")
		(hatch none 0.5)
		(connect_pads
			(clearance 0)
		)
		(min_thickness 0.25)
		(keepout
			(tracks not_allowed)
			(vias allowed)
			(pads allowed)
			(copperpour not_allowed)
			(footprints allowed)
		)
		(placement
			(enabled no)
			(sheetname "")
		)
		(fill yes
			(thermal_gap 0.5)
			(thermal_bridge_width 0.5)
			(island_removal_mode 0)
		)
		(polygon
			(pts
				(arc
					(start 83.373468 -410.030168)
					(mid 82.669888 -410.030168)
					(end 83.373468 -410.030168)
				)
			)
		)
	)
	(zone
		(layers "B.Cu" "In11.Cu" "In13.Cu" "In15.Cu")
		(hatch none 0.5)
		(connect_pads
			(clearance 0)
		)
		(min_thickness 0.25)
		(keepout
			(tracks not_allowed)
			(vias allowed)
			(pads allowed)
			(copperpour not_allowed)
			(footprints allowed)
		)
		(placement
			(enabled no)
			(sheetname "")
		)
		(fill yes
			(thermal_gap 0.5)
			(thermal_bridge_width 0.5)
			(island_removal_mode 0)
		)
		(polygon
			(pts
				(arc
					(start 109.257084 -276.708616)
					(mid 108.604304 -276.708616)
					(end 109.257084 -276.708616)
				)
			)
		)
	)
	(zone
		(layers "B.Cu" "In11.Cu" "In13.Cu" "In15.Cu")
		(hatch none 0.5)
		(connect_pads
			(clearance 0)
		)
		(min_thickness 0.25)
		(keepout
			(tracks not_allowed)
			(vias allowed)
			(pads allowed)
			(copperpour not_allowed)
			(footprints allowed)
		)
		(placement
			(enabled no)
			(sheetname "")
		)
		(fill yes
			(thermal_gap 0.5)
			(thermal_bridge_width 0.5)
			(island_removal_mode 0)
		)
		(polygon
			(pts
				(arc
					(start 125.779784 -410.030168)
					(mid 125.076204 -410.030168)
					(end 125.779784 -410.030168)
				)
			)
		)
	)
	(zone
		(layers "B.Cu" "In11.Cu" "In13.Cu" "In15.Cu")
		(hatch none 0.5)
		(connect_pads
			(clearance 0)
		)
		(min_thickness 0.25)
		(keepout
			(tracks not_allowed)
			(vias allowed)
			(pads allowed)
			(copperpour not_allowed)
			(footprints allowed)
		)
		(placement
			(enabled no)
			(sheetname "")
		)
		(fill yes
			(thermal_gap 0.5)
			(thermal_bridge_width 0.5)
			(island_removal_mode 0)
		)
		(polygon
			(pts
				(arc
					(start 96.929956 -234.15625)
					(mid 96.277176 -234.15625)
					(end 96.929956 -234.15625)
				)
			)
		)
	)
	(zone
		(layers "B.Cu" "In11.Cu" "In13.Cu" "In15.Cu")
		(hatch none 0.5)
		(connect_pads
			(clearance 0)
		)
		(min_thickness 0.25)
		(keepout
			(tracks not_allowed)
			(vias allowed)
			(pads allowed)
			(copperpour not_allowed)
			(footprints allowed)
		)
		(placement
			(enabled no)
			(sheetname "")
		)
		(fill yes
			(thermal_gap 0.5)
			(thermal_bridge_width 0.5)
			(island_removal_mode 0)
		)
		(polygon
			(pts
				(arc
					(start 440.250072 -195.616576)
					(mid 439.597292 -195.616576)
					(end 440.250072 -195.616576)
				)
			)
		)
	)
	(zone
		(layers "B.Cu" "In11.Cu" "In13.Cu" "In15.Cu")
		(hatch none 0.5)
		(connect_pads
			(clearance 0)
		)
		(min_thickness 0.25)
		(keepout
			(tracks not_allowed)
			(vias allowed)
			(pads allowed)
			(copperpour not_allowed)
			(footprints allowed)
		)
		(placement
			(enabled no)
			(sheetname "")
		)
		(fill yes
			(thermal_gap 0.5)
			(thermal_bridge_width 0.5)
			(island_removal_mode 0)
		)
		(polygon
			(pts
				(arc
					(start 188.209936 -226.216718)
					(mid 187.557156 -226.216718)
					(end 188.209936 -226.216718)
				)
			)
		)
	)
	(zone
		(layers "B.Cu" "In11.Cu" "In13.Cu" "In15.Cu")
		(hatch none 0.5)
		(connect_pads
			(clearance 0)
		)
		(min_thickness 0.25)
		(keepout
			(tracks not_allowed)
			(vias allowed)
			(pads allowed)
			(copperpour not_allowed)
			(footprints allowed)
		)
		(placement
			(enabled no)
			(sheetname "")
		)
		(fill yes
			(thermal_gap 0.5)
			(thermal_bridge_width 0.5)
			(island_removal_mode 0)
		)
		(polygon
			(pts
				(arc
					(start 386.15493 -438.089802)
					(mid 385.345178 -438.089802)
					(end 386.15493 -438.089802)
				)
			)
		)
	)
	(zone
		(layers "B.Cu" "In11.Cu" "In13.Cu" "In15.Cu")
		(hatch none 0.5)
		(connect_pads
			(clearance 0)
		)
		(min_thickness 0.25)
		(keepout
			(tracks not_allowed)
			(vias allowed)
			(pads allowed)
			(copperpour not_allowed)
			(footprints allowed)
		)
		(placement
			(enabled no)
			(sheetname "")
		)
		(fill yes
			(thermal_gap 0.5)
			(thermal_bridge_width 0.5)
			(island_removal_mode 0)
		)
		(polygon
			(pts
				(arc
					(start 95.629984 -256.361438)
					(mid 94.977204 -256.361438)
					(end 95.629984 -256.361438)
				)
			)
		)
	)
	(zone
		(layers "B.Cu" "In11.Cu" "In13.Cu" "In15.Cu")
		(hatch none 0.5)
		(connect_pads
			(clearance 0)
		)
		(min_thickness 0.25)
		(keepout
			(tracks not_allowed)
			(vias allowed)
			(pads allowed)
			(copperpour not_allowed)
			(footprints allowed)
		)
		(placement
			(enabled no)
			(sheetname "")
		)
		(fill yes
			(thermal_gap 0.5)
			(thermal_bridge_width 0.5)
			(island_removal_mode 0)
		)
		(polygon
			(pts
				(arc
					(start 127.113538 -266.941808)
					(mid 126.460758 -266.941808)
					(end 127.113538 -266.941808)
				)
			)
		)
	)
	(zone
		(layers "B.Cu" "In11.Cu" "In13.Cu" "In15.Cu")
		(hatch none 0.5)
		(connect_pads
			(clearance 0)
		)
		(min_thickness 0.25)
		(keepout
			(tracks not_allowed)
			(vias allowed)
			(pads allowed)
			(copperpour not_allowed)
			(footprints allowed)
		)
		(placement
			(enabled no)
			(sheetname "")
		)
		(fill yes
			(thermal_gap 0.5)
			(thermal_bridge_width 0.5)
			(island_removal_mode 0)
		)
		(polygon
			(pts
				(arc
					(start 335.827878 -403.883876)
					(mid 335.124298 -403.883876)
					(end 335.827878 -403.883876)
				)
			)
		)
	)
	(zone
		(layers "B.Cu" "In11.Cu" "In13.Cu" "In15.Cu")
		(hatch none 0.5)
		(connect_pads
			(clearance 0)
		)
		(min_thickness 0.25)
		(keepout
			(tracks not_allowed)
			(vias allowed)
			(pads allowed)
			(copperpour not_allowed)
			(footprints allowed)
		)
		(placement
			(enabled no)
			(sheetname "")
		)
		(fill yes
			(thermal_gap 0.5)
			(thermal_bridge_width 0.5)
			(island_removal_mode 0)
		)
		(polygon
			(pts
				(arc
					(start 127.113538 -273.453098)
					(mid 126.460758 -273.453098)
					(end 127.113538 -273.453098)
				)
			)
		)
	)
	(zone
		(layers "B.Cu" "In11.Cu" "In13.Cu" "In15.Cu")
		(hatch none 0.5)
		(connect_pads
			(clearance 0)
		)
		(min_thickness 0.25)
		(keepout
			(tracks not_allowed)
			(vias allowed)
			(pads allowed)
			(copperpour not_allowed)
			(footprints allowed)
		)
		(placement
			(enabled no)
			(sheetname "")
		)
		(fill yes
			(thermal_gap 0.5)
			(thermal_bridge_width 0.5)
			(island_removal_mode 0)
		)
		(polygon
			(pts
				(arc
					(start 100.799138 -253.919736)
					(mid 100.146358 -253.919736)
					(end 100.799138 -253.919736)
				)
			)
		)
	)
	(zone
		(layers "B.Cu" "In11.Cu" "In13.Cu" "In15.Cu")
		(hatch none 0.5)
		(connect_pads
			(clearance 0)
		)
		(min_thickness 0.25)
		(keepout
			(tracks not_allowed)
			(vias allowed)
			(pads allowed)
			(copperpour not_allowed)
			(footprints allowed)
		)
		(placement
			(enabled no)
			(sheetname "")
		)
		(fill yes
			(thermal_gap 0.5)
			(thermal_bridge_width 0.5)
			(island_removal_mode 0)
		)
		(polygon
			(pts
				(arc
					(start 374.583452 -262.872474)
					(mid 373.930672 -262.872474)
					(end 374.583452 -262.872474)
				)
			)
		)
	)
	(zone
		(layers "B.Cu" "In11.Cu" "In13.Cu" "In15.Cu")
		(hatch none 0.5)
		(connect_pads
			(clearance 0)
		)
		(min_thickness 0.25)
		(keepout
			(tracks not_allowed)
			(vias allowed)
			(pads allowed)
			(copperpour not_allowed)
			(footprints allowed)
		)
		(placement
			(enabled no)
			(sheetname "")
		)
		(fill yes
			(thermal_gap 0.5)
			(thermal_bridge_width 0.5)
			(island_removal_mode 0)
		)
		(polygon
			(pts
				(arc
					(start 376.463052 -262.872474)
					(mid 375.810272 -262.872474)
					(end 376.463052 -262.872474)
				)
			)
		)
	)
	(zone
		(layers "B.Cu" "In11.Cu" "In13.Cu" "In15.Cu")
		(hatch none 0.5)
		(connect_pads
			(clearance 0)
		)
		(min_thickness 0.25)
		(keepout
			(tracks not_allowed)
			(vias allowed)
			(pads allowed)
			(copperpour not_allowed)
			(footprints allowed)
		)
		(placement
			(enabled no)
			(sheetname "")
		)
		(fill yes
			(thermal_gap 0.5)
			(thermal_bridge_width 0.5)
			(island_removal_mode 0)
		)
		(polygon
			(pts
				(arc
					(start 128.413002 -231.714548)
					(mid 127.760222 -231.714548)
					(end 128.413002 -231.714548)
				)
			)
		)
	)
	(zone
		(layers "B.Cu" "In11.Cu" "In13.Cu" "In15.Cu")
		(hatch none 0.5)
		(connect_pads
			(clearance 0)
		)
		(min_thickness 0.25)
		(keepout
			(tracks not_allowed)
			(vias allowed)
			(pads allowed)
			(copperpour not_allowed)
			(footprints allowed)
		)
		(placement
			(enabled no)
			(sheetname "")
		)
		(fill yes
			(thermal_gap 0.5)
			(thermal_bridge_width 0.5)
			(island_removal_mode 0)
		)
		(polygon
			(pts
				(arc
					(start 443.693804 -243.216684)
					(mid 443.041024 -243.216684)
					(end 443.693804 -243.216684)
				)
			)
		)
	)
	(zone
		(layers "B.Cu" "In11.Cu" "In13.Cu" "In15.Cu")
		(hatch none 0.5)
		(connect_pads
			(clearance 0)
		)
		(min_thickness 0.25)
		(keepout
			(tracks not_allowed)
			(vias allowed)
			(pads allowed)
			(copperpour not_allowed)
			(footprints allowed)
		)
		(placement
			(enabled no)
			(sheetname "")
		)
		(fill yes
			(thermal_gap 0.5)
			(thermal_bridge_width 0.5)
			(island_removal_mode 0)
		)
		(polygon
			(pts
				(arc
					(start 71.984108 -410.030168)
					(mid 71.280528 -410.030168)
					(end 71.984108 -410.030168)
				)
			)
		)
	)
	(zone
		(layers "B.Cu" "In11.Cu" "In13.Cu" "In15.Cu")
		(hatch none 0.5)
		(connect_pads
			(clearance 0)
		)
		(min_thickness 0.25)
		(keepout
			(tracks not_allowed)
			(vias allowed)
			(pads allowed)
			(copperpour not_allowed)
			(footprints allowed)
		)
		(placement
			(enabled no)
			(sheetname "")
		)
		(fill yes
			(thermal_gap 0.5)
			(thermal_bridge_width 0.5)
			(island_removal_mode 0)
		)
		(polygon
			(pts
				(arc
					(start 132.172456 -213.732618)
					(mid 131.519676 -213.732618)
					(end 132.172456 -213.732618)
				)
			)
		)
	)
	(zone
		(layers "B.Cu" "In11.Cu" "In13.Cu" "In15.Cu")
		(hatch none 0.5)
		(connect_pads
			(clearance 0)
		)
		(min_thickness 0.25)
		(keepout
			(tracks not_allowed)
			(vias allowed)
			(pads allowed)
			(copperpour not_allowed)
			(footprints allowed)
		)
		(placement
			(enabled no)
			(sheetname "")
		)
		(fill yes
			(thermal_gap 0.5)
			(thermal_bridge_width 0.5)
			(island_removal_mode 0)
		)
		(polygon
			(pts
				(arc
					(start 192.310004 -279.766776)
					(mid 191.657224 -279.766776)
					(end 192.310004 -279.766776)
				)
			)
		)
	)
	(zone
		(layers "B.Cu" "In11.Cu" "In13.Cu" "In15.Cu")
		(hatch none 0.5)
		(connect_pads
			(clearance 0)
		)
		(min_thickness 0.25)
		(keepout
			(tracks not_allowed)
			(vias allowed)
			(pads allowed)
			(copperpour not_allowed)
			(footprints allowed)
		)
		(placement
			(enabled no)
			(sheetname "")
		)
		(fill yes
			(thermal_gap 0.5)
			(thermal_bridge_width 0.5)
			(island_removal_mode 0)
		)
		(polygon
			(pts
				(arc
					(start 95.990156 -232.528364)
					(mid 95.337376 -232.528364)
					(end 95.990156 -232.528364)
				)
			)
		)
	)
	(zone
		(layers "B.Cu" "In11.Cu" "In13.Cu" "In15.Cu")
		(hatch none 0.5)
		(connect_pads
			(clearance 0)
		)
		(min_thickness 0.25)
		(keepout
			(tracks not_allowed)
			(vias allowed)
			(pads allowed)
			(copperpour not_allowed)
			(footprints allowed)
		)
		(placement
			(enabled no)
			(sheetname "")
		)
		(fill yes
			(thermal_gap 0.5)
			(thermal_bridge_width 0.5)
			(island_removal_mode 0)
		)
		(polygon
			(pts
				(arc
					(start 349.517462 -170.613832)
					(mid 348.813882 -170.613832)
					(end 349.517462 -170.613832)
				)
			)
		)
	)
	(zone
		(layers "B.Cu" "In11.Cu" "In13.Cu" "In15.Cu")
		(hatch none 0.5)
		(connect_pads
			(clearance 0)
		)
		(min_thickness 0.25)
		(keepout
			(tracks not_allowed)
			(vias allowed)
			(pads allowed)
			(copperpour not_allowed)
			(footprints allowed)
		)
		(placement
			(enabled no)
			(sheetname "")
		)
		(fill yes
			(thermal_gap 0.5)
			(thermal_bridge_width 0.5)
			(island_removal_mode 0)
		)
		(polygon
			(pts
				(arc
					(start 95.990156 -237.411514)
					(mid 95.337376 -237.411514)
					(end 95.990156 -237.411514)
				)
			)
		)
	)
	(zone
		(layers "B.Cu" "In11.Cu" "In13.Cu" "In15.Cu")
		(hatch none 0.5)
		(connect_pads
			(clearance 0)
		)
		(min_thickness 0.25)
		(keepout
			(tracks not_allowed)
			(vias allowed)
			(pads allowed)
			(copperpour not_allowed)
			(footprints allowed)
		)
		(placement
			(enabled no)
			(sheetname "")
		)
		(fill yes
			(thermal_gap 0.5)
			(thermal_bridge_width 0.5)
			(island_removal_mode 0)
		)
		(polygon
			(pts
				(arc
					(start 104.918002 -215.436704)
					(mid 104.265222 -215.436704)
					(end 104.918002 -215.436704)
				)
			)
		)
	)
	(zone
		(layers "B.Cu" "In11.Cu" "In13.Cu" "In15.Cu")
		(hatch none 0.5)
		(connect_pads
			(clearance 0)
		)
		(min_thickness 0.25)
		(keepout
			(tracks not_allowed)
			(vias allowed)
			(pads allowed)
			(copperpour not_allowed)
			(footprints allowed)
		)
		(placement
			(enabled no)
			(sheetname "")
		)
		(fill yes
			(thermal_gap 0.5)
			(thermal_bridge_width 0.5)
			(island_removal_mode 0)
		)
		(polygon
			(pts
				(arc
					(start 95.15983 -260.430772)
					(mid 94.50705 -260.430772)
					(end 95.15983 -260.430772)
				)
			)
		)
	)
	(zone
		(layers "B.Cu" "In11.Cu" "In13.Cu" "In15.Cu")
		(hatch none 0.5)
		(connect_pads
			(clearance 0)
		)
		(min_thickness 0.25)
		(keepout
			(tracks not_allowed)
			(vias allowed)
			(pads allowed)
			(copperpour not_allowed)
			(footprints allowed)
		)
		(placement
			(enabled no)
			(sheetname "")
		)
		(fill yes
			(thermal_gap 0.5)
			(thermal_bridge_width 0.5)
			(island_removal_mode 0)
		)
		(polygon
			(pts
				(arc
					(start 374.943624 -239.0394)
					(mid 374.290844 -239.0394)
					(end 374.943624 -239.0394)
				)
			)
		)
	)
	(zone
		(layers "B.Cu" "In11.Cu" "In13.Cu" "In15.Cu")
		(hatch none 0.5)
		(connect_pads
			(clearance 0)
		)
		(min_thickness 0.25)
		(keepout
			(tracks not_allowed)
			(vias allowed)
			(pads allowed)
			(copperpour not_allowed)
			(footprints allowed)
		)
		(placement
			(enabled no)
			(sheetname "")
		)
		(fill yes
			(thermal_gap 0.5)
			(thermal_bridge_width 0.5)
			(island_removal_mode 0)
		)
		(polygon
			(pts
				(arc
					(start 102.678484 -276.708616)
					(mid 102.025704 -276.708616)
					(end 102.678484 -276.708616)
				)
			)
		)
	)
	(zone
		(layers "B.Cu" "In11.Cu" "In13.Cu" "In15.Cu")
		(hatch none 0.5)
		(connect_pads
			(clearance 0)
		)
		(min_thickness 0.25)
		(keepout
			(tracks not_allowed)
			(vias allowed)
			(pads allowed)
			(copperpour not_allowed)
			(footprints allowed)
		)
		(placement
			(enabled no)
			(sheetname "")
		)
		(fill yes
			(thermal_gap 0.5)
			(thermal_bridge_width 0.5)
			(island_removal_mode 0)
		)
		(polygon
			(pts
				(arc
					(start 122.774456 -213.732618)
					(mid 122.121676 -213.732618)
					(end 122.774456 -213.732618)
				)
			)
		)
	)
	(zone
		(layers "B.Cu" "In11.Cu" "In13.Cu" "In15.Cu")
		(hatch none 0.5)
		(connect_pads
			(clearance 0)
		)
		(min_thickness 0.25)
		(keepout
			(tracks not_allowed)
			(vias allowed)
			(pads allowed)
			(copperpour not_allowed)
			(footprints allowed)
		)
		(placement
			(enabled no)
			(sheetname "")
		)
		(fill yes
			(thermal_gap 0.5)
			(thermal_bridge_width 0.5)
			(island_removal_mode 0)
		)
		(polygon
			(pts
				(arc
					(start 265.055604 -205.816708)
					(mid 264.402824 -205.816708)
					(end 265.055604 -205.816708)
				)
			)
		)
	)
	(zone
		(layers "B.Cu" "In11.Cu" "In13.Cu" "In15.Cu")
		(hatch none 0.5)
		(connect_pads
			(clearance 0)
		)
		(min_thickness 0.25)
		(keepout
			(tracks not_allowed)
			(vias allowed)
			(pads allowed)
			(copperpour not_allowed)
			(footprints allowed)
		)
		(placement
			(enabled no)
			(sheetname "")
		)
		(fill yes
			(thermal_gap 0.5)
			(thermal_bridge_width 0.5)
			(island_removal_mode 0)
		)
		(polygon
			(pts
				(arc
					(start 343.46007 -228.45903)
					(mid 342.80729 -228.45903)
					(end 343.46007 -228.45903)
				)
			)
		)
	)
	(zone
		(layers "B.Cu" "In11.Cu" "In13.Cu" "In15.Cu")
		(hatch none 0.5)
		(connect_pads
			(clearance 0)
		)
		(min_thickness 0.25)
		(keepout
			(tracks not_allowed)
			(vias allowed)
			(pads allowed)
			(copperpour not_allowed)
			(footprints allowed)
		)
		(placement
			(enabled no)
			(sheetname "")
		)
		(fill yes
			(thermal_gap 0.5)
			(thermal_bridge_width 0.5)
			(island_removal_mode 0)
		)
		(polygon
			(pts
				(arc
					(start 336.054954 -426.089826)
					(mid 335.245202 -426.089826)
					(end 336.054954 -426.089826)
				)
			)
		)
	)
	(zone
		(layers "B.Cu" "In11.Cu" "In13.Cu" "In15.Cu")
		(hatch none 0.5)
		(connect_pads
			(clearance 0)
		)
		(min_thickness 0.25)
		(keepout
			(tracks not_allowed)
			(vias allowed)
			(pads allowed)
			(copperpour not_allowed)
			(footprints allowed)
		)
		(placement
			(enabled no)
			(sheetname "")
		)
		(fill yes
			(thermal_gap 0.5)
			(thermal_bridge_width 0.5)
			(island_removal_mode 0)
		)
		(polygon
			(pts
				(arc
					(start 36.303204 -214.316564)
					(mid 35.650424 -214.316564)
					(end 36.303204 -214.316564)
				)
			)
		)
	)
	(zone
		(layers "B.Cu" "In11.Cu" "In13.Cu" "In15.Cu")
		(hatch none 0.5)
		(connect_pads
			(clearance 0)
		)
		(min_thickness 0.25)
		(keepout
			(tracks not_allowed)
			(vias allowed)
			(pads allowed)
			(copperpour not_allowed)
			(footprints allowed)
		)
		(placement
			(enabled no)
			(sheetname "")
		)
		(fill yes
			(thermal_gap 0.5)
			(thermal_bridge_width 0.5)
			(island_removal_mode 0)
		)
		(polygon
			(pts
				(arc
					(start 107.847384 -277.522432)
					(mid 107.194604 -277.522432)
					(end 107.847384 -277.522432)
				)
			)
		)
	)
	(zone
		(layers "B.Cu" "In11.Cu" "In13.Cu" "In15.Cu")
		(hatch none 0.5)
		(connect_pads
			(clearance 0)
		)
		(min_thickness 0.25)
		(keepout
			(tracks not_allowed)
			(vias allowed)
			(pads allowed)
			(copperpour not_allowed)
			(footprints allowed)
		)
		(placement
			(enabled no)
			(sheetname "")
		)
		(fill yes
			(thermal_gap 0.5)
			(thermal_bridge_width 0.5)
			(island_removal_mode 0)
		)
		(polygon
			(pts
				(arc
					(start 95.629984 -269.38351)
					(mid 94.977204 -269.38351)
					(end 95.629984 -269.38351)
				)
			)
		)
	)
	(zone
		(layers "B.Cu" "In11.Cu" "In13.Cu" "In15.Cu")
		(hatch none 0.5)
		(connect_pads
			(clearance 0)
		)
		(min_thickness 0.25)
		(keepout
			(tracks not_allowed)
			(vias allowed)
			(pads allowed)
			(copperpour not_allowed)
			(footprints allowed)
		)
		(placement
			(enabled no)
			(sheetname "")
		)
		(fill yes
			(thermal_gap 0.5)
			(thermal_bridge_width 0.5)
			(island_removal_mode 0)
		)
		(polygon
			(pts
				(arc
					(start 36.303204 -298.466764)
					(mid 35.650424 -298.466764)
					(end 36.303204 -298.466764)
				)
			)
		)
	)
	(zone
		(layers "B.Cu" "In11.Cu" "In13.Cu" "In15.Cu")
		(hatch none 0.5)
		(connect_pads
			(clearance 0)
		)
		(min_thickness 0.25)
		(keepout
			(tracks not_allowed)
			(vias allowed)
			(pads allowed)
			(copperpour not_allowed)
			(footprints allowed)
		)
		(placement
			(enabled no)
			(sheetname "")
		)
		(fill yes
			(thermal_gap 0.5)
			(thermal_bridge_width 0.5)
			(island_removal_mode 0)
		)
		(polygon
			(pts
				(arc
					(start 100.688648 -214.622634)
					(mid 100.035868 -214.622634)
					(end 100.688648 -214.622634)
				)
			)
		)
	)
	(zone
		(layers "B.Cu" "In11.Cu" "In13.Cu" "In15.Cu")
		(hatch none 0.5)
		(connect_pads
			(clearance 0)
		)
		(min_thickness 0.25)
		(keepout
			(tracks not_allowed)
			(vias allowed)
			(pads allowed)
			(copperpour not_allowed)
			(footprints allowed)
		)
		(placement
			(enabled no)
			(sheetname "")
		)
		(fill yes
			(thermal_gap 0.5)
			(thermal_bridge_width 0.5)
			(island_removal_mode 0)
		)
		(polygon
			(pts
				(arc
					(start 123.714002 -247.992138)
					(mid 123.061222 -247.992138)
					(end 123.714002 -247.992138)
				)
			)
		)
	)
	(zone
		(layers "B.Cu" "In11.Cu" "In13.Cu" "In15.Cu")
		(hatch none 0.5)
		(connect_pads
			(clearance 0)
		)
		(min_thickness 0.25)
		(keepout
			(tracks not_allowed)
			(vias allowed)
			(pads allowed)
			(copperpour not_allowed)
			(footprints allowed)
		)
		(placement
			(enabled no)
			(sheetname "")
		)
		(fill yes
			(thermal_gap 0.5)
			(thermal_bridge_width 0.5)
			(island_removal_mode 0)
		)
		(polygon
			(pts
				(arc
					(start 97.979738 -260.430772)
					(mid 97.326958 -260.430772)
					(end 97.979738 -260.430772)
				)
			)
		)
	)
	(zone
		(layers "B.Cu" "In11.Cu" "In13.Cu" "In15.Cu")
		(hatch none 0.5)
		(connect_pads
			(clearance 0)
		)
		(min_thickness 0.25)
		(keepout
			(tracks not_allowed)
			(vias allowed)
			(pads allowed)
			(copperpour not_allowed)
			(footprints allowed)
		)
		(placement
			(enabled no)
			(sheetname "")
		)
		(fill yes
			(thermal_gap 0.5)
			(thermal_bridge_width 0.5)
			(island_removal_mode 0)
		)
		(polygon
			(pts
				(arc
					(start 129.462784 -272.639282)
					(mid 128.810004 -272.639282)
					(end 129.462784 -272.639282)
				)
			)
		)
	)
	(zone
		(layers "B.Cu" "In11.Cu" "In13.Cu" "In15.Cu")
		(hatch none 0.5)
		(connect_pads
			(clearance 0)
		)
		(min_thickness 0.25)
		(keepout
			(tracks not_allowed)
			(vias allowed)
			(pads allowed)
			(copperpour not_allowed)
			(footprints allowed)
		)
		(placement
			(enabled no)
			(sheetname "")
		)
		(fill yes
			(thermal_gap 0.5)
			(thermal_bridge_width 0.5)
			(island_removal_mode 0)
		)
		(polygon
			(pts
				(arc
					(start 128.993138 -266.941808)
					(mid 128.340358 -266.941808)
					(end 128.993138 -266.941808)
				)
			)
		)
	)
	(zone
		(layers "B.Cu" "In11.Cu" "In13.Cu" "In15.Cu")
		(hatch none 0.5)
		(connect_pads
			(clearance 0)
		)
		(min_thickness 0.25)
		(keepout
			(tracks not_allowed)
			(vias allowed)
			(pads allowed)
			(copperpour not_allowed)
			(footprints allowed)
		)
		(placement
			(enabled no)
			(sheetname "")
		)
		(fill yes
			(thermal_gap 0.5)
			(thermal_bridge_width 0.5)
			(island_removal_mode 0)
		)
		(polygon
			(pts
				(arc
					(start 180.640736 -244.066568)
					(mid 179.987956 -244.066568)
					(end 180.640736 -244.066568)
				)
			)
		)
	)
	(zone
		(layers "B.Cu" "In11.Cu" "In13.Cu" "In15.Cu")
		(hatch none 0.5)
		(connect_pads
			(clearance 0)
		)
		(min_thickness 0.25)
		(keepout
			(tracks not_allowed)
			(vias allowed)
			(pads allowed)
			(copperpour not_allowed)
			(footprints allowed)
		)
		(placement
			(enabled no)
			(sheetname "")
		)
		(fill yes
			(thermal_gap 0.5)
			(thermal_bridge_width 0.5)
			(island_removal_mode 0)
		)
		(polygon
			(pts
				(arc
					(start 188.209936 -305.266598)
					(mid 187.557156 -305.266598)
					(end 188.209936 -305.266598)
				)
			)
		)
	)
	(zone
		(layers "B.Cu" "In11.Cu" "In13.Cu" "In15.Cu")
		(hatch none 0.5)
		(connect_pads
			(clearance 0)
		)
		(min_thickness 0.25)
		(keepout
			(tracks not_allowed)
			(vias allowed)
			(pads allowed)
			(copperpour not_allowed)
			(footprints allowed)
		)
		(placement
			(enabled no)
			(sheetname "")
		)
		(fill yes
			(thermal_gap 0.5)
			(thermal_bridge_width 0.5)
			(island_removal_mode 0)
		)
		(polygon
			(pts
				(arc
					(start 108.317538 -278.336502)
					(mid 107.664758 -278.336502)
					(end 108.317538 -278.336502)
				)
			)
		)
	)
	(zone
		(layers "B.Cu" "In11.Cu" "In13.Cu" "In15.Cu")
		(hatch none 0.5)
		(connect_pads
			(clearance 0)
		)
		(min_thickness 0.25)
		(keepout
			(tracks not_allowed)
			(vias allowed)
			(pads allowed)
			(copperpour not_allowed)
			(footprints allowed)
		)
		(placement
			(enabled no)
			(sheetname "")
		)
		(fill yes
			(thermal_gap 0.5)
			(thermal_bridge_width 0.5)
			(island_removal_mode 0)
		)
		(polygon
			(pts
				(arc
					(start 130.154934 -436.889906)
					(mid 129.345182 -436.889906)
					(end 130.154934 -436.889906)
				)
			)
		)
	)
	(zone
		(layers "B.Cu" "In11.Cu" "In13.Cu" "In15.Cu")
		(hatch none 0.5)
		(connect_pads
			(clearance 0)
		)
		(min_thickness 0.25)
		(keepout
			(tracks not_allowed)
			(vias allowed)
			(pads allowed)
			(copperpour not_allowed)
			(footprints allowed)
		)
		(placement
			(enabled no)
			(sheetname "")
		)
		(fill yes
			(thermal_gap 0.5)
			(thermal_bridge_width 0.5)
			(island_removal_mode 0)
		)
		(polygon
			(pts
				(arc
					(start 192.284604 -270.416782)
					(mid 191.631824 -270.416782)
					(end 192.284604 -270.416782)
				)
			)
		)
	)
	(zone
		(layers "B.Cu" "In11.Cu" "In13.Cu" "In15.Cu")
		(hatch none 0.5)
		(connect_pads
			(clearance 0)
		)
		(min_thickness 0.25)
		(keepout
			(tracks not_allowed)
			(vias allowed)
			(pads allowed)
			(copperpour not_allowed)
			(footprints allowed)
		)
		(placement
			(enabled no)
			(sheetname "")
		)
		(fill yes
			(thermal_gap 0.5)
			(thermal_bridge_width 0.5)
			(island_removal_mode 0)
		)
		(polygon
			(pts
				(arc
					(start 376.463052 -267.755878)
					(mid 375.810272 -267.755878)
					(end 376.463052 -267.755878)
				)
			)
		)
	)
	(zone
		(layers "B.Cu" "In11.Cu" "In13.Cu" "In15.Cu")
		(hatch none 0.5)
		(connect_pads
			(clearance 0)
		)
		(min_thickness 0.25)
		(keepout
			(tracks not_allowed)
			(vias allowed)
			(pads allowed)
			(copperpour not_allowed)
			(footprints allowed)
		)
		(placement
			(enabled no)
			(sheetname "")
		)
		(fill yes
			(thermal_gap 0.5)
			(thermal_bridge_width 0.5)
			(island_removal_mode 0)
		)
		(polygon
			(pts
				(arc
					(start 440.208162 -300.166786)
					(mid 439.555382 -300.166786)
					(end 440.208162 -300.166786)
				)
			)
		)
	)
	(zone
		(layers "B.Cu" "In11.Cu" "In13.Cu" "In15.Cu")
		(hatch none 0.5)
		(connect_pads
			(clearance 0)
		)
		(min_thickness 0.25)
		(keepout
			(tracks not_allowed)
			(vias allowed)
			(pads allowed)
			(copperpour not_allowed)
			(footprints allowed)
		)
		(placement
			(enabled no)
			(sheetname "")
		)
		(fill yes
			(thermal_gap 0.5)
			(thermal_bridge_width 0.5)
			(island_removal_mode 0)
		)
		(polygon
			(pts
				(arc
					(start 343.570052 -256.361438)
					(mid 342.917272 -256.361438)
					(end 343.570052 -256.361438)
				)
			)
		)
	)
	(zone
		(layers "B.Cu" "In11.Cu" "In13.Cu" "In15.Cu")
		(hatch none 0.5)
		(connect_pads
			(clearance 0)
		)
		(min_thickness 0.25)
		(keepout
			(tracks not_allowed)
			(vias allowed)
			(pads allowed)
			(copperpour not_allowed)
			(footprints allowed)
		)
		(placement
			(enabled no)
			(sheetname "")
		)
		(fill yes
			(thermal_gap 0.5)
			(thermal_bridge_width 0.5)
			(island_removal_mode 0)
		)
		(polygon
			(pts
				(arc
					(start 405.949404 -243.216684)
					(mid 405.296624 -243.216684)
					(end 405.949404 -243.216684)
				)
			)
		)
	)
	(zone
		(layers "B.Cu" "In11.Cu" "In13.Cu" "In15.Cu")
		(hatch none 0.5)
		(connect_pads
			(clearance 0)
		)
		(min_thickness 0.25)
		(keepout
			(tracks not_allowed)
			(vias allowed)
			(pads allowed)
			(copperpour not_allowed)
			(footprints allowed)
		)
		(placement
			(enabled no)
			(sheetname "")
		)
		(fill yes
			(thermal_gap 0.5)
			(thermal_bridge_width 0.5)
			(island_removal_mode 0)
		)
		(polygon
			(pts
				(arc
					(start 188.209936 -274.66671)
					(mid 187.557156 -274.66671)
					(end 188.209936 -274.66671)
				)
			)
		)
	)
	(zone
		(layers "B.Cu" "In11.Cu" "In13.Cu" "In15.Cu")
		(hatch none 0.5)
		(connect_pads
			(clearance 0)
		)
		(min_thickness 0.25)
		(keepout
			(tracks not_allowed)
			(vias allowed)
			(pads allowed)
			(copperpour not_allowed)
			(footprints allowed)
		)
		(placement
			(enabled no)
			(sheetname "")
		)
		(fill yes
			(thermal_gap 0.5)
			(thermal_bridge_width 0.5)
			(island_removal_mode 0)
		)
		(polygon
			(pts
				(arc
					(start 340.280752 -281.59202)
					(mid 339.627972 -281.59202)
					(end 340.280752 -281.59202)
				)
			)
		)
	)
	(zone
		(layers "B.Cu" "In11.Cu" "In13.Cu" "In15.Cu")
		(hatch none 0.5)
		(connect_pads
			(clearance 0)
		)
		(min_thickness 0.25)
		(keepout
			(tracks not_allowed)
			(vias allowed)
			(pads allowed)
			(copperpour not_allowed)
			(footprints allowed)
		)
		(placement
			(enabled no)
			(sheetname "")
		)
		(fill yes
			(thermal_gap 0.5)
			(thermal_bridge_width 0.5)
			(island_removal_mode 0)
		)
		(polygon
			(pts
				(arc
					(start 97.509584 -282.405836)
					(mid 96.856804 -282.405836)
					(end 97.509584 -282.405836)
				)
			)
		)
	)
	(zone
		(layers "B.Cu" "In11.Cu" "In13.Cu" "In15.Cu")
		(hatch none 0.5)
		(connect_pads
			(clearance 0)
		)
		(min_thickness 0.25)
		(keepout
			(tracks not_allowed)
			(vias allowed)
			(pads allowed)
			(copperpour not_allowed)
			(footprints allowed)
		)
		(placement
			(enabled no)
			(sheetname "")
		)
		(fill yes
			(thermal_gap 0.5)
			(thermal_bridge_width 0.5)
			(island_removal_mode 0)
		)
		(polygon
			(pts
				(arc
					(start 108.207048 -214.622634)
					(mid 107.554268 -214.622634)
					(end 108.207048 -214.622634)
				)
			)
		)
	)
	(zone
		(layers "B.Cu" "In11.Cu" "In13.Cu" "In15.Cu")
		(hatch none 0.5)
		(connect_pads
			(clearance 0)
		)
		(min_thickness 0.25)
		(keepout
			(tracks not_allowed)
			(vias allowed)
			(pads allowed)
			(copperpour not_allowed)
			(footprints allowed)
		)
		(placement
			(enabled no)
			(sheetname "")
		)
		(fill yes
			(thermal_gap 0.5)
			(thermal_bridge_width 0.5)
			(island_removal_mode 0)
		)
		(polygon
			(pts
				(arc
					(start 128.413002 -241.481102)
					(mid 127.760222 -241.481102)
					(end 128.413002 -241.481102)
				)
			)
		)
	)
	(zone
		(layers "B.Cu" "In11.Cu" "In13.Cu" "In15.Cu")
		(hatch none 0.5)
		(connect_pads
			(clearance 0)
		)
		(min_thickness 0.25)
		(keepout
			(tracks not_allowed)
			(vias allowed)
			(pads allowed)
			(copperpour not_allowed)
			(footprints allowed)
		)
		(placement
			(enabled no)
			(sheetname "")
		)
		(fill yes
			(thermal_gap 0.5)
			(thermal_bridge_width 0.5)
			(island_removal_mode 0)
		)
		(polygon
			(pts
				(arc
					(start 265.055604 -211.766658)
					(mid 264.402824 -211.766658)
					(end 265.055604 -211.766658)
				)
			)
		)
	)
	(zone
		(layers "B.Cu" "In11.Cu" "In13.Cu" "In15.Cu")
		(hatch none 0.5)
		(connect_pads
			(clearance 0)
		)
		(min_thickness 0.25)
		(keepout
			(tracks not_allowed)
			(vias allowed)
			(pads allowed)
			(copperpour not_allowed)
			(footprints allowed)
		)
		(placement
			(enabled no)
			(sheetname "")
		)
		(fill yes
			(thermal_gap 0.5)
			(thermal_bridge_width 0.5)
			(island_removal_mode 0)
		)
		(polygon
			(pts
				(arc
					(start 341.090758 -403.883876)
					(mid 340.387178 -403.883876)
					(end 341.090758 -403.883876)
				)
			)
		)
	)
	(zone
		(layers "B.Cu" "In11.Cu" "In13.Cu" "In15.Cu")
		(hatch none 0.5)
		(connect_pads
			(clearance 0)
		)
		(min_thickness 0.25)
		(keepout
			(tracks not_allowed)
			(vias allowed)
			(pads allowed)
			(copperpour not_allowed)
			(footprints allowed)
		)
		(placement
			(enabled no)
			(sheetname "")
		)
		(fill yes
			(thermal_gap 0.5)
			(thermal_bridge_width 0.5)
			(island_removal_mode 0)
		)
		(polygon
			(pts
				(arc
					(start 345.33967 -243.108988)
					(mid 344.68689 -243.108988)
					(end 345.33967 -243.108988)
				)
			)
		)
	)
	(zone
		(layers "B.Cu" "In11.Cu" "In13.Cu" "In15.Cu")
		(hatch none 0.5)
		(connect_pads
			(clearance 0)
		)
		(min_thickness 0.25)
		(keepout
			(tracks not_allowed)
			(vias allowed)
			(pads allowed)
			(copperpour not_allowed)
			(footprints allowed)
		)
		(placement
			(enabled no)
			(sheetname "")
		)
		(fill yes
			(thermal_gap 0.5)
			(thermal_bridge_width 0.5)
			(island_removal_mode 0)
		)
		(polygon
			(pts
				(arc
					(start 104.447848 -214.622634)
					(mid 103.795068 -214.622634)
					(end 104.447848 -214.622634)
				)
			)
		)
	)
	(zone
		(layers "B.Cu" "In11.Cu" "In13.Cu" "In15.Cu")
		(hatch none 0.5)
		(connect_pads
			(clearance 0)
		)
		(min_thickness 0.25)
		(keepout
			(tracks not_allowed)
			(vias allowed)
			(pads allowed)
			(copperpour not_allowed)
			(footprints allowed)
		)
		(placement
			(enabled no)
			(sheetname "")
		)
		(fill yes
			(thermal_gap 0.5)
			(thermal_bridge_width 0.5)
			(island_removal_mode 0)
		)
		(polygon
			(pts
				(arc
					(start 32.203136 -224.516696)
					(mid 31.550356 -224.516696)
					(end 32.203136 -224.516696)
				)
			)
		)
	)
	(zone
		(layers "B.Cu" "In11.Cu" "In13.Cu" "In15.Cu")
		(hatch none 0.5)
		(connect_pads
			(clearance 0)
		)
		(min_thickness 0.25)
		(keepout
			(tracks not_allowed)
			(vias allowed)
			(pads allowed)
			(copperpour not_allowed)
			(footprints allowed)
		)
		(placement
			(enabled no)
			(sheetname "")
		)
		(fill yes
			(thermal_gap 0.5)
			(thermal_bridge_width 0.5)
			(island_removal_mode 0)
		)
		(polygon
			(pts
				(arc
					(start 436.150004 -271.266666)
					(mid 435.497224 -271.266666)
					(end 436.150004 -271.266666)
				)
			)
		)
	)
	(zone
		(layers "B.Cu" "In11.Cu" "In13.Cu" "In15.Cu")
		(hatch none 0.5)
		(connect_pads
			(clearance 0)
		)
		(min_thickness 0.25)
		(keepout
			(tracks not_allowed)
			(vias allowed)
			(pads allowed)
			(copperpour not_allowed)
			(footprints allowed)
		)
		(placement
			(enabled no)
			(sheetname "")
		)
		(fill yes
			(thermal_gap 0.5)
			(thermal_bridge_width 0.5)
			(island_removal_mode 0)
		)
		(polygon
			(pts
				(arc
					(start 134.154926 -430.889918)
					(mid 133.345174 -430.889918)
					(end 134.154926 -430.889918)
				)
			)
		)
	)
	(zone
		(layers "B.Cu" "In11.Cu" "In13.Cu" "In15.Cu")
		(hatch none 0.5)
		(connect_pads
			(clearance 0)
		)
		(min_thickness 0.25)
		(keepout
			(tracks not_allowed)
			(vias allowed)
			(pads allowed)
			(copperpour not_allowed)
			(footprints allowed)
		)
		(placement
			(enabled no)
			(sheetname "")
		)
		(fill yes
			(thermal_gap 0.5)
			(thermal_bridge_width 0.5)
			(island_removal_mode 0)
		)
		(polygon
			(pts
				(arc
					(start 39.746936 -244.066568)
					(mid 39.094156 -244.066568)
					(end 39.746936 -244.066568)
				)
			)
		)
	)
	(zone
		(layers "B.Cu" "In11.Cu" "In13.Cu" "In15.Cu")
		(hatch none 0.5)
		(connect_pads
			(clearance 0)
		)
		(min_thickness 0.25)
		(keepout
			(tracks not_allowed)
			(vias allowed)
			(pads allowed)
			(copperpour not_allowed)
			(footprints allowed)
		)
		(placement
			(enabled no)
			(sheetname "")
		)
		(fill yes
			(thermal_gap 0.5)
			(thermal_bridge_width 0.5)
			(island_removal_mode 0)
		)
		(polygon
			(pts
				(arc
					(start 344.040206 -260.430772)
					(mid 343.387426 -260.430772)
					(end 344.040206 -260.430772)
				)
			)
		)
	)
	(zone
		(layers "B.Cu" "In11.Cu" "In13.Cu" "In15.Cu")
		(hatch none 0.5)
		(connect_pads
			(clearance 0)
		)
		(min_thickness 0.25)
		(keepout
			(tracks not_allowed)
			(vias allowed)
			(pads allowed)
			(copperpour not_allowed)
			(footprints allowed)
		)
		(placement
			(enabled no)
			(sheetname "")
		)
		(fill yes
			(thermal_gap 0.5)
			(thermal_bridge_width 0.5)
			(island_removal_mode 0)
		)
		(polygon
			(pts
				(arc
					(start 284.243272 -197.316598)
					(mid 283.590492 -197.316598)
					(end 284.243272 -197.316598)
				)
			)
		)
	)
	(zone
		(layers "B.Cu" "In11.Cu" "In13.Cu" "In15.Cu")
		(hatch none 0.5)
		(connect_pads
			(clearance 0)
		)
		(min_thickness 0.25)
		(keepout
			(tracks not_allowed)
			(vias allowed)
			(pads allowed)
			(copperpour not_allowed)
			(footprints allowed)
		)
		(placement
			(enabled no)
			(sheetname "")
		)
		(fill yes
			(thermal_gap 0.5)
			(thermal_bridge_width 0.5)
			(island_removal_mode 0)
		)
		(polygon
			(pts
				(arc
					(start 344.870024 -242.294918)
					(mid 344.217244 -242.294918)
					(end 344.870024 -242.294918)
				)
			)
		)
	)
	(zone
		(layers "B.Cu" "In11.Cu" "In13.Cu" "In15.Cu")
		(hatch none 0.5)
		(connect_pads
			(clearance 0)
		)
		(min_thickness 0.25)
		(keepout
			(tracks not_allowed)
			(vias allowed)
			(pads allowed)
			(copperpour not_allowed)
			(footprints allowed)
		)
		(placement
			(enabled no)
			(sheetname "")
		)
		(fill yes
			(thermal_gap 0.5)
			(thermal_bridge_width 0.5)
			(island_removal_mode 0)
		)
		(polygon
			(pts
				(arc
					(start 280.143204 -278.916638)
					(mid 279.490424 -278.916638)
					(end 280.143204 -278.916638)
				)
			)
		)
	)
	(zone
		(layers "B.Cu" "In11.Cu" "In13.Cu" "In15.Cu")
		(hatch none 0.5)
		(connect_pads
			(clearance 0)
		)
		(min_thickness 0.25)
		(keepout
			(tracks not_allowed)
			(vias allowed)
			(pads allowed)
			(copperpour not_allowed)
			(footprints allowed)
		)
		(placement
			(enabled no)
			(sheetname "")
		)
		(fill yes
			(thermal_gap 0.5)
			(thermal_bridge_width 0.5)
			(island_removal_mode 0)
		)
		(polygon
			(pts
				(arc
					(start 436.150004 -221.116652)
					(mid 435.497224 -221.116652)
					(end 436.150004 -221.116652)
				)
			)
		)
	)
	(zone
		(layers "B.Cu" "In11.Cu" "In13.Cu" "In15.Cu")
		(hatch none 0.5)
		(connect_pads
			(clearance 0)
		)
		(min_thickness 0.25)
		(keepout
			(tracks not_allowed)
			(vias allowed)
			(pads allowed)
			(copperpour not_allowed)
			(footprints allowed)
		)
		(placement
			(enabled no)
			(sheetname "")
		)
		(fill yes
			(thermal_gap 0.5)
			(thermal_bridge_width 0.5)
			(island_removal_mode 0)
		)
		(polygon
			(pts
				(arc
					(start 80.054958 -426.089826)
					(mid 79.245206 -426.089826)
					(end 80.054958 -426.089826)
				)
			)
		)
	)
	(zone
		(layers "B.Cu" "In11.Cu" "In13.Cu" "In15.Cu")
		(hatch none 0.5)
		(connect_pads
			(clearance 0)
		)
		(min_thickness 0.25)
		(keepout
			(tracks not_allowed)
			(vias allowed)
			(pads allowed)
			(copperpour not_allowed)
			(footprints allowed)
		)
		(placement
			(enabled no)
			(sheetname "")
		)
		(fill yes
			(thermal_gap 0.5)
			(thermal_bridge_width 0.5)
			(island_removal_mode 0)
		)
		(polygon
			(pts
				(arc
					(start 127.583184 -264.50036)
					(mid 126.930404 -264.50036)
					(end 127.583184 -264.50036)
				)
			)
		)
	)
	(zone
		(layers "B.Cu" "In11.Cu" "In13.Cu" "In15.Cu")
		(hatch none 0.5)
		(connect_pads
			(clearance 0)
		)
		(min_thickness 0.25)
		(keepout
			(tracks not_allowed)
			(vias allowed)
			(pads allowed)
			(copperpour not_allowed)
			(footprints allowed)
		)
		(placement
			(enabled no)
			(sheetname "")
		)
		(fill yes
			(thermal_gap 0.5)
			(thermal_bridge_width 0.5)
			(island_removal_mode 0)
		)
		(polygon
			(pts
				(arc
					(start 339.340952 -283.219906)
					(mid 338.688172 -283.219906)
					(end 339.340952 -283.219906)
				)
			)
		)
	)
	(zone
		(layers "B.Cu" "In11.Cu" "In13.Cu" "In15.Cu")
		(hatch none 0.5)
		(connect_pads
			(clearance 0)
		)
		(min_thickness 0.25)
		(keepout
			(tracks not_allowed)
			(vias allowed)
			(pads allowed)
			(copperpour not_allowed)
			(footprints allowed)
		)
		(placement
			(enabled no)
			(sheetname "")
		)
		(fill yes
			(thermal_gap 0.5)
			(thermal_bridge_width 0.5)
			(island_removal_mode 0)
		)
		(polygon
			(pts
				(arc
					(start 21.215604 -309.51678)
					(mid 20.562824 -309.51678)
					(end 21.215604 -309.51678)
				)
			)
		)
	)
	(zone
		(layers "B.Cu" "In11.Cu" "In13.Cu" "In15.Cu")
		(hatch none 0.5)
		(connect_pads
			(clearance 0)
		)
		(min_thickness 0.25)
		(keepout
			(tracks not_allowed)
			(vias allowed)
			(pads allowed)
			(copperpour not_allowed)
			(footprints allowed)
		)
		(placement
			(enabled no)
			(sheetname "")
		)
		(fill yes
			(thermal_gap 0.5)
			(thermal_bridge_width 0.5)
			(island_removal_mode 0)
		)
		(polygon
			(pts
				(arc
					(start 353.302062 -179.351432)
					(mid 352.598482 -179.351432)
					(end 353.302062 -179.351432)
				)
			)
		)
	)
	(zone
		(layers "B.Cu" "In11.Cu" "In13.Cu" "In15.Cu")
		(hatch none 0.5)
		(connect_pads
			(clearance 0)
		)
		(min_thickness 0.25)
		(keepout
			(tracks not_allowed)
			(vias allowed)
			(pads allowed)
			(copperpour not_allowed)
			(footprints allowed)
		)
		(placement
			(enabled no)
			(sheetname "")
		)
		(fill yes
			(thermal_gap 0.5)
			(thermal_bridge_width 0.5)
			(island_removal_mode 0)
		)
		(polygon
			(pts
				(arc
					(start 347.799406 -281.59202)
					(mid 347.146626 -281.59202)
					(end 347.799406 -281.59202)
				)
			)
		)
	)
	(zone
		(layers "B.Cu" "In11.Cu" "In13.Cu" "In15.Cu")
		(hatch none 0.5)
		(connect_pads
			(clearance 0)
		)
		(min_thickness 0.25)
		(keepout
			(tracks not_allowed)
			(vias allowed)
			(pads allowed)
			(copperpour not_allowed)
			(footprints allowed)
		)
		(placement
			(enabled no)
			(sheetname "")
		)
		(fill yes
			(thermal_gap 0.5)
			(thermal_bridge_width 0.5)
			(island_removal_mode 0)
		)
		(polygon
			(pts
				(arc
					(start 353.151694 -187.248292)
					(mid 352.448114 -187.248292)
					(end 353.151694 -187.248292)
				)
			)
		)
	)
	(zone
		(layers "B.Cu" "In11.Cu" "In13.Cu" "In15.Cu")
		(hatch none 0.5)
		(connect_pads
			(clearance 0)
		)
		(min_thickness 0.25)
		(keepout
			(tracks not_allowed)
			(vias allowed)
			(pads allowed)
			(copperpour not_allowed)
			(footprints allowed)
		)
		(placement
			(enabled no)
			(sheetname "")
		)
		(fill yes
			(thermal_gap 0.5)
			(thermal_bridge_width 0.5)
			(island_removal_mode 0)
		)
		(polygon
			(pts
				(arc
					(start 351.033842 -62.406276)
					(mid 350.330262 -62.406276)
					(end 351.033842 -62.406276)
				)
			)
		)
	)
	(zone
		(layers "B.Cu" "In11.Cu" "In13.Cu" "In15.Cu")
		(hatch none 0.5)
		(connect_pads
			(clearance 0)
		)
		(min_thickness 0.25)
		(keepout
			(tracks not_allowed)
			(vias allowed)
			(pads allowed)
			(copperpour not_allowed)
			(footprints allowed)
		)
		(placement
			(enabled no)
			(sheetname "")
		)
		(fill yes
			(thermal_gap 0.5)
			(thermal_bridge_width 0.5)
			(island_removal_mode 0)
		)
		(polygon
			(pts
				(arc
					(start 97.039938 -273.453098)
					(mid 96.387158 -273.453098)
					(end 97.039938 -273.453098)
				)
			)
		)
	)
	(zone
		(layers "B.Cu" "In11.Cu" "In13.Cu" "In15.Cu")
		(hatch none 0.5)
		(connect_pads
			(clearance 0)
		)
		(min_thickness 0.25)
		(keepout
			(tracks not_allowed)
			(vias allowed)
			(pads allowed)
			(copperpour not_allowed)
			(footprints allowed)
		)
		(placement
			(enabled no)
			(sheetname "")
		)
		(fill yes
			(thermal_gap 0.5)
			(thermal_bridge_width 0.5)
			(island_removal_mode 0)
		)
		(polygon
			(pts
				(arc
					(start 95.520002 -238.225584)
					(mid 94.867222 -238.225584)
					(end 95.520002 -238.225584)
				)
			)
		)
	)
	(zone
		(layers "B.Cu" "In11.Cu" "In13.Cu" "In15.Cu")
		(hatch none 0.5)
		(connect_pads
			(clearance 0)
		)
		(min_thickness 0.25)
		(keepout
			(tracks not_allowed)
			(vias allowed)
			(pads allowed)
			(copperpour not_allowed)
			(footprints allowed)
		)
		(placement
			(enabled no)
			(sheetname "")
		)
		(fill yes
			(thermal_gap 0.5)
			(thermal_bridge_width 0.5)
			(island_removal_mode 0)
		)
		(polygon
			(pts
				(arc
					(start 440.250072 -278.066754)
					(mid 439.597292 -278.066754)
					(end 440.250072 -278.066754)
				)
			)
		)
	)
	(zone
		(layers "B.Cu" "In11.Cu" "In13.Cu" "In15.Cu")
		(hatch none 0.5)
		(connect_pads
			(clearance 0)
		)
		(min_thickness 0.25)
		(keepout
			(tracks not_allowed)
			(vias allowed)
			(pads allowed)
			(copperpour not_allowed)
			(footprints allowed)
		)
		(placement
			(enabled no)
			(sheetname "")
		)
		(fill yes
			(thermal_gap 0.5)
			(thermal_bridge_width 0.5)
			(island_removal_mode 0)
		)
		(polygon
			(pts
				(arc
					(start 36.303204 -283.166566)
					(mid 35.650424 -283.166566)
					(end 36.303204 -283.166566)
				)
			)
		)
	)
	(zone
		(layers "B.Cu" "In11.Cu" "In13.Cu" "In15.Cu")
		(hatch none 0.5)
		(connect_pads
			(clearance 0)
		)
		(min_thickness 0.25)
		(keepout
			(tracks not_allowed)
			(vias allowed)
			(pads allowed)
			(copperpour not_allowed)
			(footprints allowed)
		)
		(placement
			(enabled no)
			(sheetname "")
		)
		(fill yes
			(thermal_gap 0.5)
			(thermal_bridge_width 0.5)
			(island_removal_mode 0)
		)
		(polygon
			(pts
				(arc
					(start 383.871724 -217.064336)
					(mid 383.218944 -217.064336)
					(end 383.871724 -217.064336)
				)
			)
		)
	)
	(zone
		(layers "B.Cu" "In11.Cu" "In13.Cu" "In15.Cu")
		(hatch none 0.5)
		(connect_pads
			(clearance 0)
		)
		(min_thickness 0.25)
		(keepout
			(tracks not_allowed)
			(vias allowed)
			(pads allowed)
			(copperpour not_allowed)
			(footprints allowed)
		)
		(placement
			(enabled no)
			(sheetname "")
		)
		(fill yes
			(thermal_gap 0.5)
			(thermal_bridge_width 0.5)
			(island_removal_mode 0)
		)
		(polygon
			(pts
				(arc
					(start 54.834536 -243.216684)
					(mid 54.181756 -243.216684)
					(end 54.834536 -243.216684)
				)
			)
		)
	)
	(zone
		(layers "B.Cu" "In11.Cu" "In13.Cu" "In15.Cu")
		(hatch none 0.5)
		(connect_pads
			(clearance 0)
		)
		(min_thickness 0.25)
		(keepout
			(tracks not_allowed)
			(vias allowed)
			(pads allowed)
			(copperpour not_allowed)
			(footprints allowed)
		)
		(placement
			(enabled no)
			(sheetname "")
		)
		(fill yes
			(thermal_gap 0.5)
			(thermal_bridge_width 0.5)
			(island_removal_mode 0)
		)
		(polygon
			(pts
				(arc
					(start 95.990156 -243.922804)
					(mid 95.337376 -243.922804)
					(end 95.990156 -243.922804)
				)
			)
		)
	)
	(zone
		(layers "B.Cu" "In11.Cu" "In13.Cu" "In15.Cu")
		(hatch none 0.5)
		(connect_pads
			(clearance 0)
		)
		(min_thickness 0.25)
		(keepout
			(tracks not_allowed)
			(vias allowed)
			(pads allowed)
			(copperpour not_allowed)
			(footprints allowed)
		)
		(placement
			(enabled no)
			(sheetname "")
		)
		(fill yes
			(thermal_gap 0.5)
			(thermal_bridge_width 0.5)
			(island_removal_mode 0)
		)
		(polygon
			(pts
				(arc
					(start 405.154892 -430.689766)
					(mid 404.34514 -430.689766)
					(end 405.154892 -430.689766)
				)
			)
		)
	)
	(zone
		(layers "B.Cu" "In11.Cu" "In13.Cu" "In15.Cu")
		(hatch none 0.5)
		(connect_pads
			(clearance 0)
		)
		(min_thickness 0.25)
		(keepout
			(tracks not_allowed)
			(vias allowed)
			(pads allowed)
			(copperpour not_allowed)
			(footprints allowed)
		)
		(placement
			(enabled no)
			(sheetname "")
		)
		(fill yes
			(thermal_gap 0.5)
			(thermal_bridge_width 0.5)
			(island_removal_mode 0)
		)
		(polygon
			(pts
				(arc
					(start 36.303204 -223.666558)
					(mid 35.650424 -223.666558)
					(end 36.303204 -223.666558)
				)
			)
		)
	)
	(zone
		(layers "B.Cu" "In11.Cu" "In13.Cu" "In15.Cu")
		(hatch none 0.5)
		(connect_pads
			(clearance 0)
		)
		(min_thickness 0.25)
		(keepout
			(tracks not_allowed)
			(vias allowed)
			(pads allowed)
			(copperpour not_allowed)
			(footprints allowed)
		)
		(placement
			(enabled no)
			(sheetname "")
		)
		(fill yes
			(thermal_gap 0.5)
			(thermal_bridge_width 0.5)
			(island_removal_mode 0)
		)
		(polygon
			(pts
				(arc
					(start 325.054976 -435.489858)
					(mid 324.245224 -435.489858)
					(end 325.054976 -435.489858)
				)
			)
		)
	)
	(zone
		(layers "B.Cu" "In11.Cu" "In13.Cu" "In15.Cu")
		(hatch none 0.5)
		(connect_pads
			(clearance 0)
		)
		(min_thickness 0.25)
		(keepout
			(tracks not_allowed)
			(vias allowed)
			(pads allowed)
			(copperpour not_allowed)
			(footprints allowed)
		)
		(placement
			(enabled no)
			(sheetname "")
		)
		(fill yes
			(thermal_gap 0.5)
			(thermal_bridge_width 0.5)
			(island_removal_mode 0)
		)
		(polygon
			(pts
				(arc
					(start 358.49687 -228.45903)
					(mid 357.84409 -228.45903)
					(end 358.49687 -228.45903)
				)
			)
		)
	)
	(zone
		(layers "B.Cu" "In11.Cu" "In13.Cu" "In15.Cu")
		(hatch none 0.5)
		(connect_pads
			(clearance 0)
		)
		(min_thickness 0.25)
		(keepout
			(tracks not_allowed)
			(vias allowed)
			(pads allowed)
			(copperpour not_allowed)
			(footprints allowed)
		)
		(placement
			(enabled no)
			(sheetname "")
		)
		(fill yes
			(thermal_gap 0.5)
			(thermal_bridge_width 0.5)
			(island_removal_mode 0)
		)
		(polygon
			(pts
				(arc
					(start 76.054966 -433.289964)
					(mid 75.245214 -433.289964)
					(end 76.054966 -433.289964)
				)
			)
		)
	)
	(zone
		(layers "B.Cu" "In11.Cu" "In13.Cu" "In15.Cu")
		(hatch none 0.5)
		(connect_pads
			(clearance 0)
		)
		(min_thickness 0.25)
		(keepout
			(tracks not_allowed)
			(vias allowed)
			(pads allowed)
			(copperpour not_allowed)
			(footprints allowed)
		)
		(placement
			(enabled no)
			(sheetname "")
		)
		(fill yes
			(thermal_gap 0.5)
			(thermal_bridge_width 0.5)
			(island_removal_mode 0)
		)
		(polygon
			(pts
				(arc
					(start 98.449384 -280.778204)
					(mid 97.796604 -280.778204)
					(end 98.449384 -280.778204)
				)
			)
		)
	)
	(zone
		(layers "B.Cu" "In11.Cu" "In13.Cu" "In15.Cu")
		(hatch none 0.5)
		(connect_pads
			(clearance 0)
		)
		(min_thickness 0.25)
		(keepout
			(tracks not_allowed)
			(vias allowed)
			(pads allowed)
			(copperpour not_allowed)
			(footprints allowed)
		)
		(placement
			(enabled no)
			(sheetname "")
		)
		(fill yes
			(thermal_gap 0.5)
			(thermal_bridge_width 0.5)
			(island_removal_mode 0)
		)
		(polygon
			(pts
				(arc
					(start 357.675434 -50.207672)
					(mid 356.971854 -50.207672)
					(end 357.675434 -50.207672)
				)
			)
		)
	)
	(zone
		(layers "B.Cu" "In11.Cu" "In13.Cu" "In15.Cu")
		(hatch none 0.5)
		(connect_pads
			(clearance 0)
		)
		(min_thickness 0.25)
		(keepout
			(tracks not_allowed)
			(vias allowed)
			(pads allowed)
			(copperpour not_allowed)
			(footprints allowed)
		)
		(placement
			(enabled no)
			(sheetname "")
		)
		(fill yes
			(thermal_gap 0.5)
			(thermal_bridge_width 0.5)
			(island_removal_mode 0)
		)
		(polygon
			(pts
				(arc
					(start 280.143204 -226.216718)
					(mid 279.490424 -226.216718)
					(end 280.143204 -226.216718)
				)
			)
		)
	)
	(zone
		(layers "B.Cu" "In11.Cu" "In13.Cu" "In15.Cu")
		(hatch none 0.5)
		(connect_pads
			(clearance 0)
		)
		(min_thickness 0.25)
		(keepout
			(tracks not_allowed)
			(vias allowed)
			(pads allowed)
			(copperpour not_allowed)
			(footprints allowed)
		)
		(placement
			(enabled no)
			(sheetname "")
		)
		(fill yes
			(thermal_gap 0.5)
			(thermal_bridge_width 0.5)
			(island_removal_mode 0)
		)
		(polygon
			(pts
				(arc
					(start 385.281424 -217.878406)
					(mid 384.628644 -217.878406)
					(end 385.281424 -217.878406)
				)
			)
		)
	)
	(zone
		(layers "B.Cu" "In11.Cu" "In13.Cu" "In15.Cu")
		(hatch none 0.5)
		(connect_pads
			(clearance 0)
		)
		(min_thickness 0.25)
		(keepout
			(tracks not_allowed)
			(vias allowed)
			(pads allowed)
			(copperpour not_allowed)
			(footprints allowed)
		)
		(placement
			(enabled no)
			(sheetname "")
		)
		(fill yes
			(thermal_gap 0.5)
			(thermal_bridge_width 0.5)
			(island_removal_mode 0)
		)
		(polygon
			(pts
				(arc
					(start 106.907584 -275.8948)
					(mid 106.254804 -275.8948)
					(end 106.907584 -275.8948)
				)
			)
		)
	)
	(zone
		(layers "B.Cu" "In11.Cu" "In13.Cu" "In15.Cu")
		(hatch none 0.5)
		(connect_pads
			(clearance 0)
		)
		(min_thickness 0.25)
		(keepout
			(tracks not_allowed)
			(vias allowed)
			(pads allowed)
			(copperpour not_allowed)
			(footprints allowed)
		)
		(placement
			(enabled no)
			(sheetname "")
		)
		(fill yes
			(thermal_gap 0.5)
			(thermal_bridge_width 0.5)
			(island_removal_mode 0)
		)
		(polygon
			(pts
				(arc
					(start 419.93312 -410.030168)
					(mid 419.22954 -410.030168)
					(end 419.93312 -410.030168)
				)
			)
		)
	)
	(zone
		(layers "B.Cu" "In11.Cu" "In13.Cu" "In15.Cu")
		(hatch none 0.5)
		(connect_pads
			(clearance 0)
		)
		(min_thickness 0.25)
		(keepout
			(tracks not_allowed)
			(vias allowed)
			(pads allowed)
			(copperpour not_allowed)
			(footprints allowed)
		)
		(placement
			(enabled no)
			(sheetname "")
		)
		(fill yes
			(thermal_gap 0.5)
			(thermal_bridge_width 0.5)
			(island_removal_mode 0)
		)
		(polygon
			(pts
				(arc
					(start 95.050356 -232.528364)
					(mid 94.397576 -232.528364)
					(end 95.050356 -232.528364)
				)
			)
		)
	)
	(zone
		(layers "B.Cu" "In11.Cu" "In13.Cu" "In15.Cu")
		(hatch none 0.5)
		(connect_pads
			(clearance 0)
		)
		(min_thickness 0.25)
		(keepout
			(tracks not_allowed)
			(vias allowed)
			(pads allowed)
			(copperpour not_allowed)
			(footprints allowed)
		)
		(placement
			(enabled no)
			(sheetname "")
		)
		(fill yes
			(thermal_gap 0.5)
			(thermal_bridge_width 0.5)
			(island_removal_mode 0)
		)
		(polygon
			(pts
				(arc
					(start 436.150004 -230.466646)
					(mid 435.497224 -230.466646)
					(end 436.150004 -230.466646)
				)
			)
		)
	)
	(zone
		(layers "B.Cu" "In11.Cu" "In13.Cu" "In15.Cu")
		(hatch none 0.5)
		(connect_pads
			(clearance 0)
		)
		(min_thickness 0.25)
		(keepout
			(tracks not_allowed)
			(vias allowed)
			(pads allowed)
			(copperpour not_allowed)
			(footprints allowed)
		)
		(placement
			(enabled no)
			(sheetname "")
		)
		(fill yes
			(thermal_gap 0.5)
			(thermal_bridge_width 0.5)
			(island_removal_mode 0)
		)
		(polygon
			(pts
				(arc
					(start 376.933206 -262.058658)
					(mid 376.280426 -262.058658)
					(end 376.933206 -262.058658)
				)
			)
		)
	)
	(zone
		(layers "B.Cu" "In11.Cu" "In13.Cu" "In15.Cu")
		(hatch none 0.5)
		(connect_pads
			(clearance 0)
		)
		(min_thickness 0.25)
		(keepout
			(tracks not_allowed)
			(vias allowed)
			(pads allowed)
			(copperpour not_allowed)
			(footprints allowed)
		)
		(placement
			(enabled no)
			(sheetname "")
		)
		(fill yes
			(thermal_gap 0.5)
			(thermal_bridge_width 0.5)
			(island_removal_mode 0)
		)
		(polygon
			(pts
				(arc
					(start 351.448116 -214.622634)
					(mid 350.795336 -214.622634)
					(end 351.448116 -214.622634)
				)
			)
		)
	)
	(zone
		(layers "B.Cu" "In11.Cu" "In13.Cu" "In15.Cu")
		(hatch none 0.5)
		(connect_pads
			(clearance 0)
		)
		(min_thickness 0.25)
		(keepout
			(tracks not_allowed)
			(vias allowed)
			(pads allowed)
			(copperpour not_allowed)
			(footprints allowed)
		)
		(placement
			(enabled no)
			(sheetname "")
		)
		(fill yes
			(thermal_gap 0.5)
			(thermal_bridge_width 0.5)
			(island_removal_mode 0)
		)
		(polygon
			(pts
				(arc
					(start 343.46007 -241.481102)
					(mid 342.80729 -241.481102)
					(end 343.46007 -241.481102)
				)
			)
		)
	)
	(zone
		(layers "B.Cu" "In11.Cu" "In13.Cu" "In15.Cu")
		(hatch none 0.5)
		(connect_pads
			(clearance 0)
		)
		(min_thickness 0.25)
		(keepout
			(tracks not_allowed)
			(vias allowed)
			(pads allowed)
			(copperpour not_allowed)
			(footprints allowed)
		)
		(placement
			(enabled no)
			(sheetname "")
		)
		(fill yes
			(thermal_gap 0.5)
			(thermal_bridge_width 0.5)
			(island_removal_mode 0)
		)
		(polygon
			(pts
				(arc
					(start 345.449652 -254.733552)
					(mid 344.796872 -254.733552)
					(end 345.449652 -254.733552)
				)
			)
		)
	)
	(zone
		(layers "B.Cu" "In11.Cu" "In13.Cu" "In15.Cu")
		(hatch none 0.5)
		(connect_pads
			(clearance 0)
		)
		(min_thickness 0.25)
		(keepout
			(tracks not_allowed)
			(vias allowed)
			(pads allowed)
			(copperpour not_allowed)
			(footprints allowed)
		)
		(placement
			(enabled no)
			(sheetname "")
		)
		(fill yes
			(thermal_gap 0.5)
			(thermal_bridge_width 0.5)
			(island_removal_mode 0)
		)
		(polygon
			(pts
				(arc
					(start 329.054968 -427.089824)
					(mid 328.245216 -427.089824)
					(end 329.054968 -427.089824)
				)
			)
		)
	)
	(zone
		(layers "B.Cu" "In11.Cu" "In13.Cu" "In15.Cu")
		(hatch none 0.5)
		(connect_pads
			(clearance 0)
		)
		(min_thickness 0.25)
		(keepout
			(tracks not_allowed)
			(vias allowed)
			(pads allowed)
			(copperpour not_allowed)
			(footprints allowed)
		)
		(placement
			(enabled no)
			(sheetname "")
		)
		(fill yes
			(thermal_gap 0.5)
			(thermal_bridge_width 0.5)
			(island_removal_mode 0)
		)
		(polygon
			(pts
				(arc
					(start 192.310004 -199.866758)
					(mid 191.657224 -199.866758)
					(end 192.310004 -199.866758)
				)
			)
		)
	)
	(zone
		(layers "B.Cu" "In11.Cu" "In13.Cu" "In15.Cu")
		(hatch none 0.5)
		(connect_pads
			(clearance 0)
		)
		(min_thickness 0.25)
		(keepout
			(tracks not_allowed)
			(vias allowed)
			(pads allowed)
			(copperpour not_allowed)
			(footprints allowed)
		)
		(placement
			(enabled no)
			(sheetname "")
		)
		(fill yes
			(thermal_gap 0.5)
			(thermal_bridge_width 0.5)
			(island_removal_mode 0)
		)
		(polygon
			(pts
				(arc
					(start 47.290736 -244.066568)
					(mid 46.637956 -244.066568)
					(end 47.290736 -244.066568)
				)
			)
		)
	)
	(zone
		(layers "B.Cu" "In11.Cu" "In13.Cu" "In15.Cu")
		(hatch none 0.5)
		(connect_pads
			(clearance 0)
		)
		(min_thickness 0.25)
		(keepout
			(tracks not_allowed)
			(vias allowed)
			(pads allowed)
			(copperpour not_allowed)
			(footprints allowed)
		)
		(placement
			(enabled no)
			(sheetname "")
		)
		(fill yes
			(thermal_gap 0.5)
			(thermal_bridge_width 0.5)
			(island_removal_mode 0)
		)
		(polygon
			(pts
				(arc
					(start 323.05498 -426.089826)
					(mid 322.245228 -426.089826)
					(end 323.05498 -426.089826)
				)
			)
		)
	)
	(zone
		(layers "B.Cu" "In11.Cu" "In13.Cu" "In15.Cu")
		(hatch none 0.5)
		(connect_pads
			(clearance 0)
		)
		(min_thickness 0.25)
		(keepout
			(tracks not_allowed)
			(vias allowed)
			(pads allowed)
			(copperpour not_allowed)
			(footprints allowed)
		)
		(placement
			(enabled no)
			(sheetname "")
		)
		(fill yes
			(thermal_gap 0.5)
			(thermal_bridge_width 0.5)
			(island_removal_mode 0)
		)
		(polygon
			(pts
				(arc
					(start 339.340952 -281.59202)
					(mid 338.688172 -281.59202)
					(end 339.340952 -281.59202)
				)
			)
		)
	)
	(zone
		(layers "B.Cu" "In11.Cu" "In13.Cu" "In15.Cu")
		(hatch none 0.5)
		(connect_pads
			(clearance 0)
		)
		(min_thickness 0.25)
		(keepout
			(tracks not_allowed)
			(vias allowed)
			(pads allowed)
			(copperpour not_allowed)
			(footprints allowed)
		)
		(placement
			(enabled no)
			(sheetname "")
		)
		(fill yes
			(thermal_gap 0.5)
			(thermal_bridge_width 0.5)
			(island_removal_mode 0)
		)
		(polygon
			(pts
				(arc
					(start 375.41327 -241.481102)
					(mid 374.76049 -241.481102)
					(end 375.41327 -241.481102)
				)
			)
		)
	)
	(zone
		(layers "B.Cu" "In11.Cu" "In13.Cu" "In15.Cu")
		(hatch none 0.5)
		(connect_pads
			(clearance 0)
		)
		(min_thickness 0.25)
		(keepout
			(tracks not_allowed)
			(vias allowed)
			(pads allowed)
			(copperpour not_allowed)
			(footprints allowed)
		)
		(placement
			(enabled no)
			(sheetname "")
		)
		(fill yes
			(thermal_gap 0.5)
			(thermal_bridge_width 0.5)
			(island_removal_mode 0)
		)
		(polygon
			(pts
				(arc
					(start 129.822448 -214.622634)
					(mid 129.169668 -214.622634)
					(end 129.822448 -214.622634)
				)
			)
		)
	)
	(zone
		(layers "B.Cu" "In11.Cu" "In13.Cu" "In15.Cu")
		(hatch none 0.5)
		(connect_pads
			(clearance 0)
		)
		(min_thickness 0.25)
		(keepout
			(tracks not_allowed)
			(vias allowed)
			(pads allowed)
			(copperpour not_allowed)
			(footprints allowed)
		)
		(placement
			(enabled no)
			(sheetname "")
		)
		(fill yes
			(thermal_gap 0.5)
			(thermal_bridge_width 0.5)
			(island_removal_mode 0)
		)
		(polygon
			(pts
				(arc
					(start 94.580456 -213.732618)
					(mid 93.927676 -213.732618)
					(end 94.580456 -213.732618)
				)
			)
		)
	)
	(zone
		(layers "B.Cu" "In11.Cu" "In13.Cu" "In15.Cu")
		(hatch none 0.5)
		(connect_pads
			(clearance 0)
		)
		(min_thickness 0.25)
		(keepout
			(tracks not_allowed)
			(vias allowed)
			(pads allowed)
			(copperpour not_allowed)
			(footprints allowed)
		)
		(placement
			(enabled no)
			(sheetname "")
		)
		(fill yes
			(thermal_gap 0.5)
			(thermal_bridge_width 0.5)
			(island_removal_mode 0)
		)
		(polygon
			(pts
				(arc
					(start 374.583452 -267.755878)
					(mid 373.930672 -267.755878)
					(end 374.583452 -267.755878)
				)
			)
		)
	)
	(zone
		(layers "B.Cu" "In11.Cu" "In13.Cu" "In15.Cu")
		(hatch none 0.5)
		(connect_pads
			(clearance 0)
		)
		(min_thickness 0.25)
		(keepout
			(tracks not_allowed)
			(vias allowed)
			(pads allowed)
			(copperpour not_allowed)
			(footprints allowed)
		)
		(placement
			(enabled no)
			(sheetname "")
		)
		(fill yes
			(thermal_gap 0.5)
			(thermal_bridge_width 0.5)
			(island_removal_mode 0)
		)
		(polygon
			(pts
				(arc
					(start 135.461756 -219.506038)
					(mid 134.808976 -219.506038)
					(end 135.461756 -219.506038)
				)
			)
		)
	)
	(zone
		(layers "B.Cu" "In11.Cu" "In13.Cu" "In15.Cu")
		(hatch none 0.5)
		(connect_pads
			(clearance 0)
		)
		(min_thickness 0.25)
		(keepout
			(tracks not_allowed)
			(vias allowed)
			(pads allowed)
			(copperpour not_allowed)
			(footprints allowed)
		)
		(placement
			(enabled no)
			(sheetname "")
		)
		(fill yes
			(thermal_gap 0.5)
			(thermal_bridge_width 0.5)
			(island_removal_mode 0)
		)
		(polygon
			(pts
				(arc
					(start 436.150004 -204.116686)
					(mid 435.497224 -204.116686)
					(end 436.150004 -204.116686)
				)
			)
		)
	)
	(zone
		(layers "B.Cu" "In11.Cu" "In13.Cu" "In15.Cu")
		(hatch none 0.5)
		(connect_pads
			(clearance 0)
		)
		(min_thickness 0.25)
		(keepout
			(tracks not_allowed)
			(vias allowed)
			(pads allowed)
			(copperpour not_allowed)
			(footprints allowed)
		)
		(placement
			(enabled no)
			(sheetname "")
		)
		(fill yes
			(thermal_gap 0.5)
			(thermal_bridge_width 0.5)
			(island_removal_mode 0)
		)
		(polygon
			(pts
				(arc
					(start 127.979424 -410.030168)
					(mid 127.275844 -410.030168)
					(end 127.979424 -410.030168)
				)
			)
		)
	)
	(zone
		(layers "B.Cu" "In11.Cu" "In13.Cu" "In15.Cu")
		(hatch none 0.5)
		(connect_pads
			(clearance 0)
		)
		(min_thickness 0.25)
		(keepout
			(tracks not_allowed)
			(vias allowed)
			(pads allowed)
			(copperpour not_allowed)
			(footprints allowed)
		)
		(placement
			(enabled no)
			(sheetname "")
		)
		(fill yes
			(thermal_gap 0.5)
			(thermal_bridge_width 0.5)
			(island_removal_mode 0)
		)
		(polygon
			(pts
				(arc
					(start 376.463052 -261.244842)
					(mid 375.810272 -261.244842)
					(end 376.463052 -261.244842)
				)
			)
		)
	)
	(zone
		(layers "B.Cu" "In11.Cu" "In13.Cu" "In15.Cu")
		(hatch none 0.5)
		(connect_pads
			(clearance 0)
		)
		(min_thickness 0.25)
		(keepout
			(tracks not_allowed)
			(vias allowed)
			(pads allowed)
			(copperpour not_allowed)
			(footprints allowed)
		)
		(placement
			(enabled no)
			(sheetname "")
		)
		(fill yes
			(thermal_gap 0.5)
			(thermal_bridge_width 0.5)
			(island_removal_mode 0)
		)
		(polygon
			(pts
				(arc
					(start 436.150004 -299.316648)
					(mid 435.497224 -299.316648)
					(end 436.150004 -299.316648)
				)
			)
		)
	)
	(zone
		(layers "B.Cu" "In11.Cu" "In13.Cu" "In15.Cu")
		(hatch none 0.5)
		(connect_pads
			(clearance 0)
		)
		(min_thickness 0.25)
		(keepout
			(tracks not_allowed)
			(vias allowed)
			(pads allowed)
			(copperpour not_allowed)
			(footprints allowed)
		)
		(placement
			(enabled no)
			(sheetname "")
		)
		(fill yes
			(thermal_gap 0.5)
			(thermal_bridge_width 0.5)
			(island_removal_mode 0)
		)
		(polygon
			(pts
				(arc
					(start 343.930224 -243.922804)
					(mid 343.277444 -243.922804)
					(end 343.930224 -243.922804)
				)
			)
		)
	)
	(zone
		(layers "B.Cu" "In11.Cu" "In13.Cu" "In15.Cu")
		(hatch none 0.5)
		(connect_pads
			(clearance 0)
		)
		(min_thickness 0.25)
		(keepout
			(tracks not_allowed)
			(vias allowed)
			(pads allowed)
			(copperpour not_allowed)
			(footprints allowed)
		)
		(placement
			(enabled no)
			(sheetname "")
		)
		(fill yes
			(thermal_gap 0.5)
			(thermal_bridge_width 0.5)
			(island_removal_mode 0)
		)
		(polygon
			(pts
				(arc
					(start 91.760802 -215.436704)
					(mid 91.108022 -215.436704)
					(end 91.760802 -215.436704)
				)
			)
		)
	)
	(zone
		(layers "B.Cu" "In11.Cu" "In13.Cu" "In15.Cu")
		(hatch none 0.5)
		(connect_pads
			(clearance 0)
		)
		(min_thickness 0.25)
		(keepout
			(tracks not_allowed)
			(vias allowed)
			(pads allowed)
			(copperpour not_allowed)
			(footprints allowed)
		)
		(placement
			(enabled no)
			(sheetname "")
		)
		(fill yes
			(thermal_gap 0.5)
			(thermal_bridge_width 0.5)
			(island_removal_mode 0)
		)
		(polygon
			(pts
				(arc
					(start 127.473202 -239.853216)
					(mid 126.820422 -239.853216)
					(end 127.473202 -239.853216)
				)
			)
		)
	)
	(zone
		(layers "B.Cu" "In11.Cu" "In13.Cu" "In15.Cu")
		(hatch none 0.5)
		(connect_pads
			(clearance 0)
		)
		(min_thickness 0.25)
		(keepout
			(tracks not_allowed)
			(vias allowed)
			(pads allowed)
			(copperpour not_allowed)
			(footprints allowed)
		)
		(placement
			(enabled no)
			(sheetname "")
		)
		(fill yes
			(thermal_gap 0.5)
			(thermal_bridge_width 0.5)
			(island_removal_mode 0)
		)
		(polygon
			(pts
				(arc
					(start 376.932952 -278.336502)
					(mid 376.280172 -278.336502)
					(end 376.932952 -278.336502)
				)
			)
		)
	)
	(zone
		(layers "B.Cu" "In11.Cu" "In13.Cu" "In15.Cu")
		(hatch none 0.5)
		(connect_pads
			(clearance 0)
		)
		(min_thickness 0.25)
		(keepout
			(tracks not_allowed)
			(vias allowed)
			(pads allowed)
			(copperpour not_allowed)
			(footprints allowed)
		)
		(placement
			(enabled no)
			(sheetname "")
		)
		(fill yes
			(thermal_gap 0.5)
			(thermal_bridge_width 0.5)
			(island_removal_mode 0)
		)
		(polygon
			(pts
				(arc
					(start 269.155672 -315.46673)
					(mid 268.502892 -315.46673)
					(end 269.155672 -315.46673)
				)
			)
		)
	)
	(zone
		(layers "B.Cu" "In11.Cu" "In13.Cu" "In15.Cu")
		(hatch none 0.5)
		(connect_pads
			(clearance 0)
		)
		(min_thickness 0.25)
		(keepout
			(tracks not_allowed)
			(vias allowed)
			(pads allowed)
			(copperpour not_allowed)
			(footprints allowed)
		)
		(placement
			(enabled no)
			(sheetname "")
		)
		(fill yes
			(thermal_gap 0.5)
			(thermal_bridge_width 0.5)
			(island_removal_mode 0)
		)
		(polygon
			(pts
				(arc
					(start 329.054968 -428.28972)
					(mid 328.245216 -428.28972)
					(end 329.054968 -428.28972)
				)
			)
		)
	)
	(zone
		(layers "B.Cu" "In11.Cu" "In13.Cu" "In15.Cu")
		(hatch none 0.5)
		(connect_pads
			(clearance 0)
		)
		(min_thickness 0.25)
		(keepout
			(tracks not_allowed)
			(vias allowed)
			(pads allowed)
			(copperpour not_allowed)
			(footprints allowed)
		)
		(placement
			(enabled no)
			(sheetname "")
		)
		(fill yes
			(thermal_gap 0.5)
			(thermal_bridge_width 0.5)
			(island_removal_mode 0)
		)
		(polygon
			(pts
				(arc
					(start 344.869516 -214.622634)
					(mid 344.216736 -214.622634)
					(end 344.869516 -214.622634)
				)
			)
		)
	)
	(zone
		(layers "B.Cu" "In11.Cu" "In13.Cu" "In15.Cu")
		(hatch none 0.5)
		(connect_pads
			(clearance 0)
		)
		(min_thickness 0.25)
		(keepout
			(tracks not_allowed)
			(vias allowed)
			(pads allowed)
			(copperpour not_allowed)
			(footprints allowed)
		)
		(placement
			(enabled no)
			(sheetname "")
		)
		(fill yes
			(thermal_gap 0.5)
			(thermal_bridge_width 0.5)
			(island_removal_mode 0)
		)
		(polygon
			(pts
				(arc
					(start 455.337672 -312.066686)
					(mid 454.684892 -312.066686)
					(end 455.337672 -312.066686)
				)
			)
		)
	)
	(zone
		(layers "B.Cu" "In11.Cu" "In13.Cu" "In15.Cu")
		(hatch none 0.5)
		(connect_pads
			(clearance 0)
		)
		(min_thickness 0.25)
		(keepout
			(tracks not_allowed)
			(vias allowed)
			(pads allowed)
			(copperpour not_allowed)
			(footprints allowed)
		)
		(placement
			(enabled no)
			(sheetname "")
		)
		(fill yes
			(thermal_gap 0.5)
			(thermal_bridge_width 0.5)
			(island_removal_mode 0)
		)
		(polygon
			(pts
				(arc
					(start 340.640924 -213.732618)
					(mid 339.988144 -213.732618)
					(end 340.640924 -213.732618)
				)
			)
		)
	)
	(zone
		(layers "B.Cu" "In11.Cu" "In13.Cu" "In15.Cu")
		(hatch none 0.5)
		(connect_pads
			(clearance 0)
		)
		(min_thickness 0.25)
		(keepout
			(tracks not_allowed)
			(vias allowed)
			(pads allowed)
			(copperpour not_allowed)
			(footprints allowed)
		)
		(placement
			(enabled no)
			(sheetname "")
		)
		(fill yes
			(thermal_gap 0.5)
			(thermal_bridge_width 0.5)
			(island_removal_mode 0)
		)
		(polygon
			(pts
				(arc
					(start 119.015256 -213.732618)
					(mid 118.362476 -213.732618)
					(end 119.015256 -213.732618)
				)
			)
		)
	)
	(zone
		(layers "B.Cu" "In11.Cu" "In13.Cu" "In15.Cu")
		(hatch none 0.5)
		(connect_pads
			(clearance 0)
		)
		(min_thickness 0.25)
		(keepout
			(tracks not_allowed)
			(vias allowed)
			(pads allowed)
			(copperpour not_allowed)
			(footprints allowed)
		)
		(placement
			(enabled no)
			(sheetname "")
		)
		(fill yes
			(thermal_gap 0.5)
			(thermal_bridge_width 0.5)
			(island_removal_mode 0)
		)
		(polygon
			(pts
				(arc
					(start 105.387648 -214.622634)
					(mid 104.734868 -214.622634)
					(end 105.387648 -214.622634)
				)
			)
		)
	)
	(zone
		(layers "B.Cu" "In11.Cu" "In13.Cu" "In15.Cu")
		(hatch none 0.5)
		(connect_pads
			(clearance 0)
		)
		(min_thickness 0.25)
		(keepout
			(tracks not_allowed)
			(vias allowed)
			(pads allowed)
			(copperpour not_allowed)
			(footprints allowed)
		)
		(placement
			(enabled no)
			(sheetname "")
		)
		(fill yes
			(thermal_gap 0.5)
			(thermal_bridge_width 0.5)
			(island_removal_mode 0)
		)
		(polygon
			(pts
				(arc
					(start 137.811256 -218.692222)
					(mid 137.158476 -218.692222)
					(end 137.811256 -218.692222)
				)
			)
		)
	)
	(zone
		(layers "B.Cu" "In11.Cu" "In13.Cu" "In15.Cu")
		(hatch none 0.5)
		(connect_pads
			(clearance 0)
		)
		(min_thickness 0.25)
		(keepout
			(tracks not_allowed)
			(vias allowed)
			(pads allowed)
			(copperpour not_allowed)
			(footprints allowed)
		)
		(placement
			(enabled no)
			(sheetname "")
		)
		(fill yes
			(thermal_gap 0.5)
			(thermal_bridge_width 0.5)
			(island_removal_mode 0)
		)
		(polygon
			(pts
				(arc
					(start 165.553136 -243.216684)
					(mid 164.900356 -243.216684)
					(end 165.553136 -243.216684)
				)
			)
		)
	)
	(zone
		(layers "B.Cu" "In11.Cu" "In13.Cu" "In15.Cu")
		(hatch none 0.5)
		(connect_pads
			(clearance 0)
		)
		(min_thickness 0.25)
		(keepout
			(tracks not_allowed)
			(vias allowed)
			(pads allowed)
			(copperpour not_allowed)
			(footprints allowed)
		)
		(placement
			(enabled no)
			(sheetname "")
		)
		(fill yes
			(thermal_gap 0.5)
			(thermal_bridge_width 0.5)
			(island_removal_mode 0)
		)
		(polygon
			(pts
				(arc
					(start 376.933206 -273.453098)
					(mid 376.280426 -273.453098)
					(end 376.933206 -273.453098)
				)
			)
		)
	)
	(zone
		(layers "B.Cu" "In11.Cu" "In13.Cu" "In15.Cu")
		(hatch none 0.5)
		(connect_pads
			(clearance 0)
		)
		(min_thickness 0.25)
		(keepout
			(tracks not_allowed)
			(vias allowed)
			(pads allowed)
			(copperpour not_allowed)
			(footprints allowed)
		)
		(placement
			(enabled no)
			(sheetname "")
		)
		(fill yes
			(thermal_gap 0.5)
			(thermal_bridge_width 0.5)
			(island_removal_mode 0)
		)
		(polygon
			(pts
				(arc
					(start 68.920868 -410.030168)
					(mid 68.217288 -410.030168)
					(end 68.920868 -410.030168)
				)
			)
		)
	)
	(zone
		(layers "B.Cu" "In11.Cu" "In13.Cu" "In15.Cu")
		(hatch none 0.5)
		(connect_pads
			(clearance 0)
		)
		(min_thickness 0.25)
		(keepout
			(tracks not_allowed)
			(vias allowed)
			(pads allowed)
			(copperpour not_allowed)
			(footprints allowed)
		)
		(placement
			(enabled no)
			(sheetname "")
		)
		(fill yes
			(thermal_gap 0.5)
			(thermal_bridge_width 0.5)
			(island_removal_mode 0)
		)
		(polygon
			(pts
				(arc
					(start 375.053606 -263.686544)
					(mid 374.400826 -263.686544)
					(end 375.053606 -263.686544)
				)
			)
		)
	)
	(zone
		(layers "B.Cu" "In11.Cu" "In13.Cu" "In15.Cu")
		(hatch none 0.5)
		(connect_pads
			(clearance 0)
		)
		(min_thickness 0.25)
		(keepout
			(tracks not_allowed)
			(vias allowed)
			(pads allowed)
			(copperpour not_allowed)
			(footprints allowed)
		)
		(placement
			(enabled no)
			(sheetname "")
		)
		(fill yes
			(thermal_gap 0.5)
			(thermal_bridge_width 0.5)
			(island_removal_mode 0)
		)
		(polygon
			(pts
				(arc
					(start 346.054934 -427.089824)
					(mid 345.245182 -427.089824)
					(end 346.054934 -427.089824)
				)
			)
		)
	)
	(zone
		(layers "B.Cu" "In11.Cu" "In13.Cu" "In15.Cu")
		(hatch none 0.5)
		(connect_pads
			(clearance 0)
		)
		(min_thickness 0.25)
		(keepout
			(tracks not_allowed)
			(vias allowed)
			(pads allowed)
			(copperpour not_allowed)
			(footprints allowed)
		)
		(placement
			(enabled no)
			(sheetname "")
		)
		(fill yes
			(thermal_gap 0.5)
			(thermal_bridge_width 0.5)
			(island_removal_mode 0)
		)
		(polygon
			(pts
				(arc
					(start 354.267516 -214.622634)
					(mid 353.614736 -214.622634)
					(end 354.267516 -214.622634)
				)
			)
		)
	)
	(zone
		(layers "B.Cu" "In11.Cu" "In13.Cu" "In15.Cu")
		(hatch none 0.5)
		(connect_pads
			(clearance 0)
		)
		(min_thickness 0.25)
		(keepout
			(tracks not_allowed)
			(vias allowed)
			(pads allowed)
			(copperpour not_allowed)
			(footprints allowed)
		)
		(placement
			(enabled no)
			(sheetname "")
		)
		(fill yes
			(thermal_gap 0.5)
			(thermal_bridge_width 0.5)
			(island_removal_mode 0)
		)
		(polygon
			(pts
				(arc
					(start 127.003556 -229.272846)
					(mid 126.350776 -229.272846)
					(end 127.003556 -229.272846)
				)
			)
		)
	)
	(zone
		(layers "B.Cu" "In11.Cu" "In13.Cu" "In15.Cu")
		(hatch none 0.5)
		(connect_pads
			(clearance 0)
		)
		(min_thickness 0.25)
		(keepout
			(tracks not_allowed)
			(vias allowed)
			(pads allowed)
			(copperpour not_allowed)
			(footprints allowed)
		)
		(placement
			(enabled no)
			(sheetname "")
		)
		(fill yes
			(thermal_gap 0.5)
			(thermal_bridge_width 0.5)
			(island_removal_mode 0)
		)
		(polygon
			(pts
				(arc
					(start 436.150004 -284.866588)
					(mid 435.497224 -284.866588)
					(end 436.150004 -284.866588)
				)
			)
		)
	)
	(zone
		(layers "B.Cu" "In11.Cu" "In13.Cu" "In15.Cu")
		(hatch none 0.5)
		(connect_pads
			(clearance 0)
		)
		(min_thickness 0.25)
		(keepout
			(tracks not_allowed)
			(vias allowed)
			(pads allowed)
			(copperpour not_allowed)
			(footprints allowed)
		)
		(placement
			(enabled no)
			(sheetname "")
		)
		(fill yes
			(thermal_gap 0.5)
			(thermal_bridge_width 0.5)
			(island_removal_mode 0)
		)
		(polygon
			(pts
				(arc
					(start 78.054962 -427.089824)
					(mid 77.24521 -427.089824)
					(end 78.054962 -427.089824)
				)
			)
		)
	)
	(zone
		(layers "B.Cu" "In11.Cu" "In13.Cu" "In15.Cu")
		(hatch none 0.5)
		(connect_pads
			(clearance 0)
		)
		(min_thickness 0.25)
		(keepout
			(tracks not_allowed)
			(vias allowed)
			(pads allowed)
			(copperpour not_allowed)
			(footprints allowed)
		)
		(placement
			(enabled no)
			(sheetname "")
		)
		(fill yes
			(thermal_gap 0.5)
			(thermal_bridge_width 0.5)
			(island_removal_mode 0)
		)
		(polygon
			(pts
				(arc
					(start 416.86988 -410.030168)
					(mid 416.1663 -410.030168)
					(end 416.86988 -410.030168)
				)
			)
		)
	)
	(zone
		(layers "B.Cu" "In11.Cu" "In13.Cu" "In15.Cu")
		(hatch none 0.5)
		(connect_pads
			(clearance 0)
		)
		(min_thickness 0.25)
		(keepout
			(tracks not_allowed)
			(vias allowed)
			(pads allowed)
			(copperpour not_allowed)
			(footprints allowed)
		)
		(placement
			(enabled no)
			(sheetname "")
		)
		(fill yes
			(thermal_gap 0.5)
			(thermal_bridge_width 0.5)
			(island_removal_mode 0)
		)
		(polygon
			(pts
				(arc
					(start 136.154922 -430.689766)
					(mid 135.34517 -430.689766)
					(end 136.154922 -430.689766)
				)
			)
		)
	)
	(zone
		(layers "B.Cu" "In11.Cu" "In13.Cu" "In15.Cu")
		(hatch none 0.5)
		(connect_pads
			(clearance 0)
		)
		(min_thickness 0.25)
		(keepout
			(tracks not_allowed)
			(vias allowed)
			(pads allowed)
			(copperpour not_allowed)
			(footprints allowed)
		)
		(placement
			(enabled no)
			(sheetname "")
		)
		(fill yes
			(thermal_gap 0.5)
			(thermal_bridge_width 0.5)
			(island_removal_mode 0)
		)
		(polygon
			(pts
				(arc
					(start 345.449652 -274.266914)
					(mid 344.796872 -274.266914)
					(end 345.449652 -274.266914)
				)
			)
		)
	)
	(zone
		(layers "B.Cu" "In11.Cu" "In13.Cu" "In15.Cu")
		(hatch none 0.5)
		(connect_pads
			(clearance 0)
		)
		(min_thickness 0.25)
		(keepout
			(tracks not_allowed)
			(vias allowed)
			(pads allowed)
			(copperpour not_allowed)
			(footprints allowed)
		)
		(placement
			(enabled no)
			(sheetname "")
		)
		(fill yes
			(thermal_gap 0.5)
			(thermal_bridge_width 0.5)
			(island_removal_mode 0)
		)
		(polygon
			(pts
				(arc
					(start 134.154926 -438.089802)
					(mid 133.345174 -438.089802)
					(end 134.154926 -438.089802)
				)
			)
		)
	)
	(zone
		(layers "B.Cu" "In11.Cu" "In13.Cu" "In15.Cu")
		(hatch none 0.5)
		(connect_pads
			(clearance 0)
		)
		(min_thickness 0.25)
		(keepout
			(tracks not_allowed)
			(vias allowed)
			(pads allowed)
			(copperpour not_allowed)
			(footprints allowed)
		)
		(placement
			(enabled no)
			(sheetname "")
		)
		(fill yes
			(thermal_gap 0.5)
			(thermal_bridge_width 0.5)
			(island_removal_mode 0)
		)
		(polygon
			(pts
				(arc
					(start 127.583184 -266.128246)
					(mid 126.930404 -266.128246)
					(end 127.583184 -266.128246)
				)
			)
		)
	)
	(zone
		(layers "B.Cu" "In11.Cu" "In13.Cu" "In15.Cu")
		(hatch none 0.5)
		(connect_pads
			(clearance 0)
		)
		(min_thickness 0.25)
		(keepout
			(tracks not_allowed)
			(vias allowed)
			(pads allowed)
			(copperpour not_allowed)
			(footprints allowed)
		)
		(placement
			(enabled no)
			(sheetname "")
		)
		(fill yes
			(thermal_gap 0.5)
			(thermal_bridge_width 0.5)
			(island_removal_mode 0)
		)
		(polygon
			(pts
				(arc
					(start 78.110588 -410.030168)
					(mid 77.407008 -410.030168)
					(end 78.110588 -410.030168)
				)
			)
		)
	)
	(zone
		(layers "B.Cu" "In11.Cu" "In13.Cu" "In15.Cu")
		(hatch none 0.5)
		(connect_pads
			(clearance 0)
		)
		(min_thickness 0.25)
		(keepout
			(tracks not_allowed)
			(vias allowed)
			(pads allowed)
			(copperpour not_allowed)
			(footprints allowed)
		)
		(placement
			(enabled no)
			(sheetname "")
		)
		(fill yes
			(thermal_gap 0.5)
			(thermal_bridge_width 0.5)
			(island_removal_mode 0)
		)
		(polygon
			(pts
				(arc
					(start 284.243272 -276.366732)
					(mid 283.590492 -276.366732)
					(end 284.243272 -276.366732)
				)
			)
		)
	)
	(zone
		(layers "B.Cu" "In11.Cu" "In13.Cu" "In15.Cu")
		(hatch none 0.5)
		(connect_pads
			(clearance 0)
		)
		(min_thickness 0.25)
		(keepout
			(tracks not_allowed)
			(vias allowed)
			(pads allowed)
			(copperpour not_allowed)
			(footprints allowed)
		)
		(placement
			(enabled no)
			(sheetname "")
		)
		(fill yes
			(thermal_gap 0.5)
			(thermal_bridge_width 0.5)
			(island_removal_mode 0)
		)
		(polygon
			(pts
				(arc
					(start 316.584838 -403.883876)
					(mid 315.881258 -403.883876)
					(end 316.584838 -403.883876)
				)
			)
		)
	)
	(zone
		(layers "B.Cu" "In11.Cu" "In13.Cu" "In15.Cu")
		(hatch none 0.5)
		(connect_pads
			(clearance 0)
		)
		(min_thickness 0.25)
		(keepout
			(tracks not_allowed)
			(vias allowed)
			(pads allowed)
			(copperpour not_allowed)
			(footprints allowed)
		)
		(placement
			(enabled no)
			(sheetname "")
		)
		(fill yes
			(thermal_gap 0.5)
			(thermal_bridge_width 0.5)
			(island_removal_mode 0)
		)
		(polygon
			(pts
				(arc
					(start 207.397604 -307.816758)
					(mid 206.744824 -307.816758)
					(end 207.397604 -307.816758)
				)
			)
		)
	)
	(zone
		(layers "B.Cu" "In11.Cu" "In13.Cu" "In15.Cu")
		(hatch none 0.5)
		(connect_pads
			(clearance 0)
		)
		(min_thickness 0.25)
		(keepout
			(tracks not_allowed)
			(vias allowed)
			(pads allowed)
			(copperpour not_allowed)
			(footprints allowed)
		)
		(placement
			(enabled no)
			(sheetname "")
		)
		(fill yes
			(thermal_gap 0.5)
			(thermal_bridge_width 0.5)
			(island_removal_mode 0)
		)
		(polygon
			(pts
				(arc
					(start 126.154942 -436.889906)
					(mid 125.34519 -436.889906)
					(end 126.154942 -436.889906)
				)
			)
		)
	)
	(zone
		(layers "B.Cu" "In11.Cu" "In13.Cu" "In15.Cu")
		(hatch none 0.5)
		(connect_pads
			(clearance 0)
		)
		(min_thickness 0.25)
		(keepout
			(tracks not_allowed)
			(vias allowed)
			(pads allowed)
			(copperpour not_allowed)
			(footprints allowed)
		)
		(placement
			(enabled no)
			(sheetname "")
		)
		(fill yes
			(thermal_gap 0.5)
			(thermal_bridge_width 0.5)
			(island_removal_mode 0)
		)
		(polygon
			(pts
				(arc
					(start 74.183748 -410.030168)
					(mid 73.480168 -410.030168)
					(end 74.183748 -410.030168)
				)
			)
		)
	)
	(zone
		(layers "B.Cu" "In11.Cu" "In13.Cu" "In15.Cu")
		(hatch none 0.5)
		(connect_pads
			(clearance 0)
		)
		(min_thickness 0.25)
		(keepout
			(tracks not_allowed)
			(vias allowed)
			(pads allowed)
			(copperpour not_allowed)
			(footprints allowed)
		)
		(placement
			(enabled no)
			(sheetname "")
		)
		(fill yes
			(thermal_gap 0.5)
			(thermal_bridge_width 0.5)
			(island_removal_mode 0)
		)
		(polygon
			(pts
				(arc
					(start 88.111584 -282.405836)
					(mid 87.458804 -282.405836)
					(end 88.111584 -282.405836)
				)
			)
		)
	)
	(zone
		(layers "B.Cu" "In11.Cu" "In13.Cu" "In15.Cu")
		(hatch none 0.5)
		(connect_pads
			(clearance 0)
		)
		(min_thickness 0.25)
		(keepout
			(tracks not_allowed)
			(vias allowed)
			(pads allowed)
			(copperpour not_allowed)
			(footprints allowed)
		)
		(placement
			(enabled no)
			(sheetname "")
		)
		(fill yes
			(thermal_gap 0.5)
			(thermal_bridge_width 0.5)
			(island_removal_mode 0)
		)
		(polygon
			(pts
				(arc
					(start 180.640736 -243.216684)
					(mid 179.987956 -243.216684)
					(end 180.640736 -243.216684)
				)
			)
		)
	)
	(zone
		(layers "B.Cu" "In11.Cu" "In13.Cu" "In15.Cu")
		(hatch none 0.5)
		(connect_pads
			(clearance 0)
		)
		(min_thickness 0.25)
		(keepout
			(tracks not_allowed)
			(vias allowed)
			(pads allowed)
			(copperpour not_allowed)
			(footprints allowed)
		)
		(placement
			(enabled no)
			(sheetname "")
		)
		(fill yes
			(thermal_gap 0.5)
			(thermal_bridge_width 0.5)
			(island_removal_mode 0)
		)
		(polygon
			(pts
				(arc
					(start 338.891118 -403.883876)
					(mid 338.187538 -403.883876)
					(end 338.891118 -403.883876)
				)
			)
		)
	)
	(zone
		(layers "B.Cu" "In11.Cu" "In13.Cu" "In15.Cu")
		(hatch none 0.5)
		(connect_pads
			(clearance 0)
		)
		(min_thickness 0.25)
		(keepout
			(tracks not_allowed)
			(vias allowed)
			(pads allowed)
			(copperpour not_allowed)
			(footprints allowed)
		)
		(placement
			(enabled no)
			(sheetname "")
		)
		(fill yes
			(thermal_gap 0.5)
			(thermal_bridge_width 0.5)
			(island_removal_mode 0)
		)
		(polygon
			(pts
				(arc
					(start 90.461084 -279.964134)
					(mid 89.808304 -279.964134)
					(end 90.461084 -279.964134)
				)
			)
		)
	)
	(zone
		(layers "B.Cu" "In11.Cu" "In13.Cu" "In15.Cu")
		(hatch none 0.5)
		(connect_pads
			(clearance 0)
		)
		(min_thickness 0.25)
		(keepout
			(tracks not_allowed)
			(vias allowed)
			(pads allowed)
			(copperpour not_allowed)
			(footprints allowed)
		)
		(placement
			(enabled no)
			(sheetname "")
		)
		(fill yes
			(thermal_gap 0.5)
			(thermal_bridge_width 0.5)
			(island_removal_mode 0)
		)
		(polygon
			(pts
				(arc
					(start 127.473202 -241.481102)
					(mid 126.820422 -241.481102)
					(end 127.473202 -241.481102)
				)
			)
		)
	)
	(zone
		(layers "B.Cu" "In11.Cu" "In13.Cu" "In15.Cu")
		(hatch none 0.5)
		(connect_pads
			(clearance 0)
		)
		(min_thickness 0.25)
		(keepout
			(tracks not_allowed)
			(vias allowed)
			(pads allowed)
			(copperpour not_allowed)
			(footprints allowed)
		)
		(placement
			(enabled no)
			(sheetname "")
		)
		(fill yes
			(thermal_gap 0.5)
			(thermal_bridge_width 0.5)
			(island_removal_mode 0)
		)
		(polygon
			(pts
				(arc
					(start 356.147116 -214.622634)
					(mid 355.494336 -214.622634)
					(end 356.147116 -214.622634)
				)
			)
		)
	)
	(zone
		(layers "B.Cu" "In11.Cu" "In13.Cu" "In15.Cu")
		(hatch none 0.5)
		(connect_pads
			(clearance 0)
		)
		(min_thickness 0.25)
		(keepout
			(tracks not_allowed)
			(vias allowed)
			(pads allowed)
			(copperpour not_allowed)
			(footprints allowed)
		)
		(placement
			(enabled no)
			(sheetname "")
		)
		(fill yes
			(thermal_gap 0.5)
			(thermal_bridge_width 0.5)
			(island_removal_mode 0)
		)
		(polygon
			(pts
				(arc
					(start 352.968052 -280.778204)
					(mid 352.315272 -280.778204)
					(end 352.968052 -280.778204)
				)
			)
		)
	)
	(zone
		(layers "B.Cu" "In11.Cu" "In13.Cu" "In15.Cu")
		(hatch none 0.5)
		(connect_pads
			(clearance 0)
		)
		(min_thickness 0.25)
		(keepout
			(tracks not_allowed)
			(vias allowed)
			(pads allowed)
			(copperpour not_allowed)
			(footprints allowed)
		)
		(placement
			(enabled no)
			(sheetname "")
		)
		(fill yes
			(thermal_gap 0.5)
			(thermal_bridge_width 0.5)
			(island_removal_mode 0)
		)
		(polygon
			(pts
				(arc
					(start 114.316002 -215.436704)
					(mid 113.663222 -215.436704)
					(end 114.316002 -215.436704)
				)
			)
		)
	)
	(zone
		(layers "B.Cu" "In11.Cu" "In13.Cu" "In15.Cu")
		(hatch none 0.5)
		(connect_pads
			(clearance 0)
		)
		(min_thickness 0.25)
		(keepout
			(tracks not_allowed)
			(vias allowed)
			(pads allowed)
			(copperpour not_allowed)
			(footprints allowed)
		)
		(placement
			(enabled no)
			(sheetname "")
		)
		(fill yes
			(thermal_gap 0.5)
			(thermal_bridge_width 0.5)
			(island_removal_mode 0)
		)
		(polygon
			(pts
				(arc
					(start 55.804308 -410.030168)
					(mid 55.100728 -410.030168)
					(end 55.804308 -410.030168)
				)
			)
		)
	)
	(zone
		(layers "B.Cu" "In11.Cu" "In13.Cu" "In15.Cu")
		(hatch none 0.5)
		(connect_pads
			(clearance 0)
		)
		(min_thickness 0.25)
		(keepout
			(tracks not_allowed)
			(vias allowed)
			(pads allowed)
			(copperpour not_allowed)
			(footprints allowed)
		)
		(placement
			(enabled no)
			(sheetname "")
		)
		(fill yes
			(thermal_gap 0.5)
			(thermal_bridge_width 0.5)
			(island_removal_mode 0)
		)
		(polygon
			(pts
				(arc
					(start 188.209936 -272.966688)
					(mid 187.557156 -272.966688)
					(end 188.209936 -272.966688)
				)
			)
		)
	)
	(zone
		(layers "B.Cu" "In11.Cu" "In13.Cu" "In15.Cu")
		(hatch none 0.5)
		(connect_pads
			(clearance 0)
		)
		(min_thickness 0.25)
		(keepout
			(tracks not_allowed)
			(vias allowed)
			(pads allowed)
			(copperpour not_allowed)
			(footprints allowed)
		)
		(placement
			(enabled no)
			(sheetname "")
		)
		(fill yes
			(thermal_gap 0.5)
			(thermal_bridge_width 0.5)
			(island_removal_mode 0)
		)
		(polygon
			(pts
				(arc
					(start 440.250072 -216.016586)
					(mid 439.597292 -216.016586)
					(end 440.250072 -216.016586)
				)
			)
		)
	)
	(zone
		(layers "B.Cu" "In11.Cu" "In13.Cu" "In15.Cu")
		(hatch none 0.5)
		(connect_pads
			(clearance 0)
		)
		(min_thickness 0.25)
		(keepout
			(tracks not_allowed)
			(vias allowed)
			(pads allowed)
			(copperpour not_allowed)
			(footprints allowed)
		)
		(placement
			(enabled no)
			(sheetname "")
		)
		(fill yes
			(thermal_gap 0.5)
			(thermal_bridge_width 0.5)
			(island_removal_mode 0)
		)
		(polygon
			(pts
				(arc
					(start 128.413002 -228.45903)
					(mid 127.760222 -228.45903)
					(end 128.413002 -228.45903)
				)
			)
		)
	)
	(zone
		(layers "B.Cu" "In11.Cu" "In13.Cu" "In15.Cu")
		(hatch none 0.5)
		(connect_pads
			(clearance 0)
		)
		(min_thickness 0.25)
		(keepout
			(tracks not_allowed)
			(vias allowed)
			(pads allowed)
			(copperpour not_allowed)
			(footprints allowed)
		)
		(placement
			(enabled no)
			(sheetname "")
		)
		(fill yes
			(thermal_gap 0.5)
			(thermal_bridge_width 0.5)
			(island_removal_mode 0)
		)
		(polygon
			(pts
				(arc
					(start 230.84917 -53.84292)
					(mid 230.14559 -53.84292)
					(end 230.84917 -53.84292)
				)
			)
		)
	)
	(zone
		(layers "B.Cu" "In11.Cu" "In13.Cu" "In15.Cu")
		(hatch none 0.5)
		(connect_pads
			(clearance 0)
		)
		(min_thickness 0.25)
		(keepout
			(tracks not_allowed)
			(vias allowed)
			(pads allowed)
			(copperpour not_allowed)
			(footprints allowed)
		)
		(placement
			(enabled no)
			(sheetname "")
		)
		(fill yes
			(thermal_gap 0.5)
			(thermal_bridge_width 0.5)
			(island_removal_mode 0)
		)
		(polygon
			(pts
				(arc
					(start 21.215604 -311.216802)
					(mid 20.562824 -311.216802)
					(end 21.215604 -311.216802)
				)
			)
		)
	)
	(zone
		(layers "B.Cu" "In11.Cu" "In13.Cu" "In15.Cu")
		(hatch none 0.5)
		(connect_pads
			(clearance 0)
		)
		(min_thickness 0.25)
		(keepout
			(tracks not_allowed)
			(vias allowed)
			(pads allowed)
			(copperpour not_allowed)
			(footprints allowed)
		)
		(placement
			(enabled no)
			(sheetname "")
		)
		(fill yes
			(thermal_gap 0.5)
			(thermal_bridge_width 0.5)
			(island_removal_mode 0)
		)
		(polygon
			(pts
				(arc
					(start 344.870024 -245.55069)
					(mid 344.217244 -245.55069)
					(end 344.870024 -245.55069)
				)
			)
		)
	)
	(zone
		(layers "B.Cu" "In11.Cu" "In13.Cu" "In15.Cu")
		(hatch none 0.5)
		(connect_pads
			(clearance 0)
		)
		(min_thickness 0.25)
		(keepout
			(tracks not_allowed)
			(vias allowed)
			(pads allowed)
			(copperpour not_allowed)
			(footprints allowed)
		)
		(placement
			(enabled no)
			(sheetname "")
		)
		(fill yes
			(thermal_gap 0.5)
			(thermal_bridge_width 0.5)
			(island_removal_mode 0)
		)
		(polygon
			(pts
				(arc
					(start 391.50036 -410.030168)
					(mid 390.79678 -410.030168)
					(end 391.50036 -410.030168)
				)
			)
		)
	)
	(zone
		(layers "B.Cu" "In11.Cu" "In13.Cu" "In15.Cu")
		(hatch none 0.5)
		(connect_pads
			(clearance 0)
		)
		(min_thickness 0.25)
		(keepout
			(tracks not_allowed)
			(vias allowed)
			(pads allowed)
			(copperpour not_allowed)
			(footprints allowed)
		)
		(placement
			(enabled no)
			(sheetname "")
		)
		(fill yes
			(thermal_gap 0.5)
			(thermal_bridge_width 0.5)
			(island_removal_mode 0)
		)
		(polygon
			(pts
				(arc
					(start 97.399602 -231.714548)
					(mid 96.746822 -231.714548)
					(end 97.399602 -231.714548)
				)
			)
		)
	)
	(zone
		(layers "B.Cu" "In11.Cu" "In13.Cu" "In15.Cu")
		(hatch none 0.5)
		(connect_pads
			(clearance 0)
		)
		(min_thickness 0.25)
		(keepout
			(tracks not_allowed)
			(vias allowed)
			(pads allowed)
			(copperpour not_allowed)
			(footprints allowed)
		)
		(placement
			(enabled no)
			(sheetname "")
		)
		(fill yes
			(thermal_gap 0.5)
			(thermal_bridge_width 0.5)
			(island_removal_mode 0)
		)
		(polygon
			(pts
				(arc
					(start 141.095984 -410.030168)
					(mid 140.392404 -410.030168)
					(end 141.095984 -410.030168)
				)
			)
		)
	)
	(zone
		(layers "B.Cu" "In11.Cu" "In13.Cu" "In15.Cu")
		(hatch none 0.5)
		(connect_pads
			(clearance 0)
		)
		(min_thickness 0.25)
		(keepout
			(tracks not_allowed)
			(vias allowed)
			(pads allowed)
			(copperpour not_allowed)
			(footprints allowed)
		)
		(placement
			(enabled no)
			(sheetname "")
		)
		(fill yes
			(thermal_gap 0.5)
			(thermal_bridge_width 0.5)
			(island_removal_mode 0)
		)
		(polygon
			(pts
				(arc
					(start 345.449652 -266.128246)
					(mid 344.796872 -266.128246)
					(end 345.449652 -266.128246)
				)
			)
		)
	)
	(zone
		(layers "B.Cu" "In11.Cu" "In13.Cu" "In15.Cu")
		(hatch none 0.5)
		(connect_pads
			(clearance 0)
		)
		(min_thickness 0.25)
		(keepout
			(tracks not_allowed)
			(vias allowed)
			(pads allowed)
			(copperpour not_allowed)
			(footprints allowed)
		)
		(placement
			(enabled no)
			(sheetname "")
		)
		(fill yes
			(thermal_gap 0.5)
			(thermal_bridge_width 0.5)
			(island_removal_mode 0)
		)
		(polygon
			(pts
				(arc
					(start 392.154918 -431.889916)
					(mid 391.345166 -431.889916)
					(end 392.154918 -431.889916)
				)
			)
		)
	)
	(zone
		(layers "B.Cu" "In11.Cu" "In13.Cu" "In15.Cu")
		(hatch none 0.5)
		(connect_pads
			(clearance 0)
		)
		(min_thickness 0.25)
		(keepout
			(tracks not_allowed)
			(vias allowed)
			(pads allowed)
			(copperpour not_allowed)
			(footprints allowed)
		)
		(placement
			(enabled no)
			(sheetname "")
		)
		(fill yes
			(thermal_gap 0.5)
			(thermal_bridge_width 0.5)
			(island_removal_mode 0)
		)
		(polygon
			(pts
				(arc
					(start 153.154888 -439.0898)
					(mid 152.345136 -439.0898)
					(end 153.154888 -439.0898)
				)
			)
		)
	)
	(zone
		(layers "B.Cu" "In11.Cu" "In13.Cu" "In15.Cu")
		(hatch none 0.5)
		(connect_pads
			(clearance 0)
		)
		(min_thickness 0.25)
		(keepout
			(tracks not_allowed)
			(vias allowed)
			(pads allowed)
			(copperpour not_allowed)
			(footprints allowed)
		)
		(placement
			(enabled no)
			(sheetname "")
		)
		(fill yes
			(thermal_gap 0.5)
			(thermal_bridge_width 0.5)
			(island_removal_mode 0)
		)
		(polygon
			(pts
				(arc
					(start 100.219256 -213.732618)
					(mid 99.566476 -213.732618)
					(end 100.219256 -213.732618)
				)
			)
		)
	)
	(zone
		(layers "B.Cu" "In11.Cu" "In13.Cu" "In15.Cu")
		(hatch none 0.5)
		(connect_pads
			(clearance 0)
		)
		(min_thickness 0.25)
		(keepout
			(tracks not_allowed)
			(vias allowed)
			(pads allowed)
			(copperpour not_allowed)
			(footprints allowed)
		)
		(placement
			(enabled no)
			(sheetname "")
		)
		(fill yes
			(thermal_gap 0.5)
			(thermal_bridge_width 0.5)
			(island_removal_mode 0)
		)
		(polygon
			(pts
				(arc
					(start 440.250072 -273.816572)
					(mid 439.597292 -273.816572)
					(end 440.250072 -273.816572)
				)
			)
		)
	)
	(zone
		(layers "B.Cu" "In11.Cu" "In13.Cu" "In15.Cu")
		(hatch none 0.5)
		(connect_pads
			(clearance 0)
		)
		(min_thickness 0.25)
		(keepout
			(tracks not_allowed)
			(vias allowed)
			(pads allowed)
			(copperpour not_allowed)
			(footprints allowed)
		)
		(placement
			(enabled no)
			(sheetname "")
		)
		(fill yes
			(thermal_gap 0.5)
			(thermal_bridge_width 0.5)
			(island_removal_mode 0)
		)
		(polygon
			(pts
				(arc
					(start 436.150004 -278.916638)
					(mid 435.497224 -278.916638)
					(end 436.150004 -278.916638)
				)
			)
		)
	)
	(zone
		(layers "B.Cu" "In11.Cu" "In13.Cu" "In15.Cu")
		(hatch none 0.5)
		(connect_pads
			(clearance 0)
		)
		(min_thickness 0.25)
		(keepout
			(tracks not_allowed)
			(vias allowed)
			(pads allowed)
			(copperpour not_allowed)
			(footprints allowed)
		)
		(placement
			(enabled no)
			(sheetname "")
		)
		(fill yes
			(thermal_gap 0.5)
			(thermal_bridge_width 0.5)
			(island_removal_mode 0)
		)
		(polygon
			(pts
				(arc
					(start 90.350848 -214.622634)
					(mid 89.698068 -214.622634)
					(end 90.350848 -214.622634)
				)
			)
		)
	)
	(zone
		(layers "B.Cu" "In11.Cu" "In13.Cu" "In15.Cu")
		(hatch none 0.5)
		(connect_pads
			(clearance 0)
		)
		(min_thickness 0.25)
		(keepout
			(tracks not_allowed)
			(vias allowed)
			(pads allowed)
			(copperpour not_allowed)
			(footprints allowed)
		)
		(placement
			(enabled no)
			(sheetname "")
		)
		(fill yes
			(thermal_gap 0.5)
			(thermal_bridge_width 0.5)
			(island_removal_mode 0)
		)
		(polygon
			(pts
				(arc
					(start 269.155672 -244.916706)
					(mid 268.502892 -244.916706)
					(end 269.155672 -244.916706)
				)
			)
		)
	)
	(zone
		(layers "B.Cu" "In11.Cu" "In13.Cu" "In15.Cu")
		(hatch none 0.5)
		(connect_pads
			(clearance 0)
		)
		(min_thickness 0.25)
		(keepout
			(tracks not_allowed)
			(vias allowed)
			(pads allowed)
			(copperpour not_allowed)
			(footprints allowed)
		)
		(placement
			(enabled no)
			(sheetname "")
		)
		(fill yes
			(thermal_gap 0.5)
			(thermal_bridge_width 0.5)
			(island_removal_mode 0)
		)
		(polygon
			(pts
				(arc
					(start 21.215604 -244.916706)
					(mid 20.562824 -244.916706)
					(end 21.215604 -244.916706)
				)
			)
		)
	)
	(zone
		(layers "B.Cu" "In11.Cu" "In13.Cu" "In15.Cu")
		(hatch none 0.5)
		(connect_pads
			(clearance 0)
		)
		(min_thickness 0.25)
		(keepout
			(tracks not_allowed)
			(vias allowed)
			(pads allowed)
			(copperpour not_allowed)
			(footprints allowed)
		)
		(placement
			(enabled no)
			(sheetname "")
		)
		(fill yes
			(thermal_gap 0.5)
			(thermal_bridge_width 0.5)
			(island_removal_mode 0)
		)
		(polygon
			(pts
				(arc
					(start 230.84917 -57.443116)
					(mid 230.14559 -57.443116)
					(end 230.84917 -57.443116)
				)
			)
		)
	)
	(zone
		(layers "B.Cu" "In11.Cu" "In13.Cu" "In15.Cu")
		(hatch none 0.5)
		(connect_pads
			(clearance 0)
		)
		(min_thickness 0.25)
		(keepout
			(tracks not_allowed)
			(vias allowed)
			(pads allowed)
			(copperpour not_allowed)
			(footprints allowed)
		)
		(placement
			(enabled no)
			(sheetname "")
		)
		(fill yes
			(thermal_gap 0.5)
			(thermal_bridge_width 0.5)
			(island_removal_mode 0)
		)
		(polygon
			(pts
				(arc
					(start 127.003556 -243.922804)
					(mid 126.350776 -243.922804)
					(end 127.003556 -243.922804)
				)
			)
		)
	)
	(zone
		(layers "B.Cu" "In11.Cu" "In13.Cu" "In15.Cu")
		(hatch none 0.5)
		(connect_pads
			(clearance 0)
		)
		(min_thickness 0.25)
		(keepout
			(tracks not_allowed)
			(vias allowed)
			(pads allowed)
			(copperpour not_allowed)
			(footprints allowed)
		)
		(placement
			(enabled no)
			(sheetname "")
		)
		(fill yes
			(thermal_gap 0.5)
			(thermal_bridge_width 0.5)
			(island_removal_mode 0)
		)
		(polygon
			(pts
				(arc
					(start 213.712044 -4.2672)
					(mid 213.008464 -4.2672)
					(end 213.712044 -4.2672)
				)
			)
		)
	)
	(zone
		(layers "B.Cu" "In11.Cu" "In13.Cu" "In15.Cu")
		(hatch none 0.5)
		(connect_pads
			(clearance 0)
		)
		(min_thickness 0.25)
		(keepout
			(tracks not_allowed)
			(vias allowed)
			(pads allowed)
			(copperpour not_allowed)
			(footprints allowed)
		)
		(placement
			(enabled no)
			(sheetname "")
		)
		(fill yes
			(thermal_gap 0.5)
			(thermal_bridge_width 0.5)
			(island_removal_mode 0)
		)
		(polygon
			(pts
				(arc
					(start 80.054958 -433.289964)
					(mid 79.245206 -433.289964)
					(end 80.054958 -433.289964)
				)
			)
		)
	)
	(zone
		(layers "B.Cu" "In11.Cu" "In13.Cu" "In15.Cu")
		(hatch none 0.5)
		(connect_pads
			(clearance 0)
		)
		(min_thickness 0.25)
		(keepout
			(tracks not_allowed)
			(vias allowed)
			(pads allowed)
			(copperpour not_allowed)
			(footprints allowed)
		)
		(placement
			(enabled no)
			(sheetname "")
		)
		(fill yes
			(thermal_gap 0.5)
			(thermal_bridge_width 0.5)
			(island_removal_mode 0)
		)
		(polygon
			(pts
				(arc
					(start 436.150004 -215.166702)
					(mid 435.497224 -215.166702)
					(end 436.150004 -215.166702)
				)
			)
		)
	)
	(zone
		(layers "B.Cu" "In11.Cu" "In13.Cu" "In15.Cu")
		(hatch none 0.5)
		(connect_pads
			(clearance 0)
		)
		(min_thickness 0.25)
		(keepout
			(tracks not_allowed)
			(vias allowed)
			(pads allowed)
			(copperpour not_allowed)
			(footprints allowed)
		)
		(placement
			(enabled no)
			(sheetname "")
		)
		(fill yes
			(thermal_gap 0.5)
			(thermal_bridge_width 0.5)
			(island_removal_mode 0)
		)
		(polygon
			(pts
				(arc
					(start 352.968052 -282.405836)
					(mid 352.315272 -282.405836)
					(end 352.968052 -282.405836)
				)
			)
		)
	)
	(zone
		(layers "B.Cu" "In11.Cu" "In13.Cu" "In15.Cu")
		(hatch none 0.5)
		(connect_pads
			(clearance 0)
		)
		(min_thickness 0.25)
		(keepout
			(tracks not_allowed)
			(vias allowed)
			(pads allowed)
			(copperpour not_allowed)
			(footprints allowed)
		)
		(placement
			(enabled no)
			(sheetname "")
		)
		(fill yes
			(thermal_gap 0.5)
			(thermal_bridge_width 0.5)
			(island_removal_mode 0)
		)
		(polygon
			(pts
				(arc
					(start 345.449652 -271.011396)
					(mid 344.796872 -271.011396)
					(end 345.449652 -271.011396)
				)
			)
		)
	)
	(zone
		(layers "B.Cu" "In11.Cu" "In13.Cu" "In15.Cu")
		(hatch none 0.5)
		(connect_pads
			(clearance 0)
		)
		(min_thickness 0.25)
		(keepout
			(tracks not_allowed)
			(vias allowed)
			(pads allowed)
			(copperpour not_allowed)
			(footprints allowed)
		)
		(placement
			(enabled no)
			(sheetname "")
		)
		(fill yes
			(thermal_gap 0.5)
			(thermal_bridge_width 0.5)
			(island_removal_mode 0)
		)
		(polygon
			(pts
				(arc
					(start 265.055604 -243.216684)
					(mid 264.402824 -243.216684)
					(end 265.055604 -243.216684)
				)
			)
		)
	)
	(zone
		(layers "B.Cu" "In11.Cu" "In13.Cu" "In15.Cu")
		(hatch none 0.5)
		(connect_pads
			(clearance 0)
		)
		(min_thickness 0.25)
		(keepout
			(tracks not_allowed)
			(vias allowed)
			(pads allowed)
			(copperpour not_allowed)
			(footprints allowed)
		)
		(placement
			(enabled no)
			(sheetname "")
		)
		(fill yes
			(thermal_gap 0.5)
			(thermal_bridge_width 0.5)
			(island_removal_mode 0)
		)
		(polygon
			(pts
				(arc
					(start 97.509584 -271.011396)
					(mid 96.856804 -271.011396)
					(end 97.509584 -271.011396)
				)
			)
		)
	)
	(zone
		(layers "B.Cu" "In11.Cu" "In13.Cu" "In15.Cu")
		(hatch none 0.5)
		(connect_pads
			(clearance 0)
		)
		(min_thickness 0.25)
		(keepout
			(tracks not_allowed)
			(vias allowed)
			(pads allowed)
			(copperpour not_allowed)
			(footprints allowed)
		)
		(placement
			(enabled no)
			(sheetname "")
		)
		(fill yes
			(thermal_gap 0.5)
			(thermal_bridge_width 0.5)
			(island_removal_mode 0)
		)
		(polygon
			(pts
				(arc
					(start 127.003556 -234.15625)
					(mid 126.350776 -234.15625)
					(end 127.003556 -234.15625)
				)
			)
		)
	)
	(zone
		(layers "B.Cu" "In11.Cu" "In13.Cu" "In15.Cu")
		(hatch none 0.5)
		(connect_pads
			(clearance 0)
		)
		(min_thickness 0.25)
		(keepout
			(tracks not_allowed)
			(vias allowed)
			(pads allowed)
			(copperpour not_allowed)
			(footprints allowed)
		)
		(placement
			(enabled no)
			(sheetname "")
		)
		(fill yes
			(thermal_gap 0.5)
			(thermal_bridge_width 0.5)
			(island_removal_mode 0)
		)
		(polygon
			(pts
				(arc
					(start 188.209936 -227.91674)
					(mid 187.557156 -227.91674)
					(end 188.209936 -227.91674)
				)
			)
		)
	)
	(zone
		(layers "B.Cu" "In11.Cu" "In13.Cu" "In15.Cu")
		(hatch none 0.5)
		(connect_pads
			(clearance 0)
		)
		(min_thickness 0.25)
		(keepout
			(tracks not_allowed)
			(vias allowed)
			(pads allowed)
			(copperpour not_allowed)
			(footprints allowed)
		)
		(placement
			(enabled no)
			(sheetname "")
		)
		(fill yes
			(thermal_gap 0.5)
			(thermal_bridge_width 0.5)
			(island_removal_mode 0)
		)
		(polygon
			(pts
				(arc
					(start 96.929448 -214.622634)
					(mid 96.276668 -214.622634)
					(end 96.929448 -214.622634)
				)
			)
		)
	)
	(zone
		(layers "B.Cu" "In11.Cu" "In13.Cu" "In15.Cu")
		(hatch none 0.5)
		(connect_pads
			(clearance 0)
		)
		(min_thickness 0.25)
		(keepout
			(tracks not_allowed)
			(vias allowed)
			(pads allowed)
			(copperpour not_allowed)
			(footprints allowed)
		)
		(placement
			(enabled no)
			(sheetname "")
		)
		(fill yes
			(thermal_gap 0.5)
			(thermal_bridge_width 0.5)
			(island_removal_mode 0)
		)
		(polygon
			(pts
				(arc
					(start 69.05498 -435.489858)
					(mid 68.245228 -435.489858)
					(end 69.05498 -435.489858)
				)
			)
		)
	)
	(zone
		(layers "B.Cu" "In11.Cu" "In13.Cu" "In15.Cu")
		(hatch none 0.5)
		(connect_pads
			(clearance 0)
		)
		(min_thickness 0.25)
		(keepout
			(tracks not_allowed)
			(vias allowed)
			(pads allowed)
			(copperpour not_allowed)
			(footprints allowed)
		)
		(placement
			(enabled no)
			(sheetname "")
		)
		(fill yes
			(thermal_gap 0.5)
			(thermal_bridge_width 0.5)
			(island_removal_mode 0)
		)
		(polygon
			(pts
				(arc
					(start 96.570038 -280.778204)
					(mid 95.917258 -280.778204)
					(end 96.570038 -280.778204)
				)
			)
		)
	)
	(zone
		(layers "B.Cu" "In11.Cu" "In13.Cu" "In15.Cu")
		(hatch none 0.5)
		(connect_pads
			(clearance 0)
		)
		(min_thickness 0.25)
		(keepout
			(tracks not_allowed)
			(vias allowed)
			(pads allowed)
			(copperpour not_allowed)
			(footprints allowed)
		)
		(placement
			(enabled no)
			(sheetname "")
		)
		(fill yes
			(thermal_gap 0.5)
			(thermal_bridge_width 0.5)
			(island_removal_mode 0)
		)
		(polygon
			(pts
				(arc
					(start 96.100138 -270.19758)
					(mid 95.447358 -270.19758)
					(end 96.100138 -270.19758)
				)
			)
		)
	)
	(zone
		(layers "B.Cu" "In11.Cu" "In13.Cu" "In15.Cu")
		(hatch none 0.5)
		(connect_pads
			(clearance 0)
		)
		(min_thickness 0.25)
		(keepout
			(tracks not_allowed)
			(vias allowed)
			(pads allowed)
			(copperpour not_allowed)
			(footprints allowed)
		)
		(placement
			(enabled no)
			(sheetname "")
		)
		(fill yes
			(thermal_gap 0.5)
			(thermal_bridge_width 0.5)
			(island_removal_mode 0)
		)
		(polygon
			(pts
				(arc
					(start 96.100138 -260.430772)
					(mid 95.447358 -260.430772)
					(end 96.100138 -260.430772)
				)
			)
		)
	)
	(zone
		(layers "B.Cu" "In11.Cu" "In13.Cu" "In15.Cu")
		(hatch none 0.5)
		(connect_pads
			(clearance 0)
		)
		(min_thickness 0.25)
		(keepout
			(tracks not_allowed)
			(vias allowed)
			(pads allowed)
			(copperpour not_allowed)
			(footprints allowed)
		)
		(placement
			(enabled no)
			(sheetname "")
		)
		(fill yes
			(thermal_gap 0.5)
			(thermal_bridge_width 0.5)
			(island_removal_mode 0)
		)
		(polygon
			(pts
				(arc
					(start 343.100406 -265.314176)
					(mid 342.447626 -265.314176)
					(end 343.100406 -265.314176)
				)
			)
		)
	)
	(zone
		(layers "B.Cu" "In11.Cu" "In13.Cu" "In15.Cu")
		(hatch none 0.5)
		(connect_pads
			(clearance 0)
		)
		(min_thickness 0.25)
		(keepout
			(tracks not_allowed)
			(vias allowed)
			(pads allowed)
			(copperpour not_allowed)
			(footprints allowed)
		)
		(placement
			(enabled no)
			(sheetname "")
		)
		(fill yes
			(thermal_gap 0.5)
			(thermal_bridge_width 0.5)
			(island_removal_mode 0)
		)
		(polygon
			(pts
				(arc
					(start 375.41327 -233.34218)
					(mid 374.76049 -233.34218)
					(end 375.41327 -233.34218)
				)
			)
		)
	)
	(zone
		(layers "B.Cu" "In11.Cu" "In13.Cu" "In15.Cu")
		(hatch none 0.5)
		(connect_pads
			(clearance 0)
		)
		(min_thickness 0.25)
		(keepout
			(tracks not_allowed)
			(vias allowed)
			(pads allowed)
			(copperpour not_allowed)
			(footprints allowed)
		)
		(placement
			(enabled no)
			(sheetname "")
		)
		(fill yes
			(thermal_gap 0.5)
			(thermal_bridge_width 0.5)
			(island_removal_mode 0)
		)
		(polygon
			(pts
				(arc
					(start 413.154876 -437.889904)
					(mid 412.345124 -437.889904)
					(end 413.154876 -437.889904)
				)
			)
		)
	)
	(zone
		(layers "B.Cu" "In11.Cu" "In13.Cu" "In15.Cu")
		(hatch none 0.5)
		(connect_pads
			(clearance 0)
		)
		(min_thickness 0.25)
		(keepout
			(tracks not_allowed)
			(vias allowed)
			(pads allowed)
			(copperpour not_allowed)
			(footprints allowed)
		)
		(placement
			(enabled no)
			(sheetname "")
		)
		(fill yes
			(thermal_gap 0.5)
			(thermal_bridge_width 0.5)
			(island_removal_mode 0)
		)
		(polygon
			(pts
				(arc
					(start 440.250072 -221.96679)
					(mid 439.597292 -221.96679)
					(end 440.250072 -221.96679)
				)
			)
		)
	)
	(zone
		(layers "B.Cu" "In11.Cu" "In13.Cu" "In15.Cu")
		(hatch none 0.5)
		(connect_pads
			(clearance 0)
		)
		(min_thickness 0.25)
		(keepout
			(tracks not_allowed)
			(vias allowed)
			(pads allowed)
			(copperpour not_allowed)
			(footprints allowed)
		)
		(placement
			(enabled no)
			(sheetname "")
		)
		(fill yes
			(thermal_gap 0.5)
			(thermal_bridge_width 0.5)
			(island_removal_mode 0)
		)
		(polygon
			(pts
				(arc
					(start 157.15488 -439.0898)
					(mid 156.345128 -439.0898)
					(end 157.15488 -439.0898)
				)
			)
		)
	)
	(zone
		(layers "B.Cu" "In11.Cu" "In13.Cu" "In15.Cu")
		(hatch none 0.5)
		(connect_pads
			(clearance 0)
		)
		(min_thickness 0.25)
		(keepout
			(tracks not_allowed)
			(vias allowed)
			(pads allowed)
			(copperpour not_allowed)
			(footprints allowed)
		)
		(placement
			(enabled no)
			(sheetname "")
		)
		(fill yes
			(thermal_gap 0.5)
			(thermal_bridge_width 0.5)
			(island_removal_mode 0)
		)
		(polygon
			(pts
				(arc
					(start 89.881202 -215.436704)
					(mid 89.228422 -215.436704)
					(end 89.881202 -215.436704)
				)
			)
		)
	)
	(zone
		(layers "B.Cu" "In11.Cu" "In13.Cu" "In15.Cu")
		(hatch none 0.5)
		(connect_pads
			(clearance 0)
		)
		(min_thickness 0.25)
		(keepout
			(tracks not_allowed)
			(vias allowed)
			(pads allowed)
			(copperpour not_allowed)
			(footprints allowed)
		)
		(placement
			(enabled no)
			(sheetname "")
		)
		(fill yes
			(thermal_gap 0.5)
			(thermal_bridge_width 0.5)
			(island_removal_mode 0)
		)
		(polygon
			(pts
				(arc
					(start 36.303204 -272.116804)
					(mid 35.650424 -272.116804)
					(end 36.303204 -272.116804)
				)
			)
		)
	)
	(zone
		(layers "B.Cu" "In11.Cu" "In13.Cu" "In15.Cu")
		(hatch none 0.5)
		(connect_pads
			(clearance 0)
		)
		(min_thickness 0.25)
		(keepout
			(tracks not_allowed)
			(vias allowed)
			(pads allowed)
			(copperpour not_allowed)
			(footprints allowed)
		)
		(placement
			(enabled no)
			(sheetname "")
		)
		(fill yes
			(thermal_gap 0.5)
			(thermal_bridge_width 0.5)
			(island_removal_mode 0)
		)
		(polygon
			(pts
				(arc
					(start 319.054988 -434.48986)
					(mid 318.245236 -434.48986)
					(end 319.054988 -434.48986)
				)
			)
		)
	)
	(zone
		(layers "B.Cu" "In11.Cu" "In13.Cu" "In15.Cu")
		(hatch none 0.5)
		(connect_pads
			(clearance 0)
		)
		(min_thickness 0.25)
		(keepout
			(tracks not_allowed)
			(vias allowed)
			(pads allowed)
			(copperpour not_allowed)
			(footprints allowed)
		)
		(placement
			(enabled no)
			(sheetname "")
		)
		(fill yes
			(thermal_gap 0.5)
			(thermal_bridge_width 0.5)
			(island_removal_mode 0)
		)
		(polygon
			(pts
				(arc
					(start 352.85807 -228.45903)
					(mid 352.20529 -228.45903)
					(end 352.85807 -228.45903)
				)
			)
		)
	)
	(zone
		(layers "B.Cu" "In11.Cu" "In13.Cu" "In15.Cu")
		(hatch none 0.5)
		(connect_pads
			(clearance 0)
		)
		(min_thickness 0.25)
		(keepout
			(tracks not_allowed)
			(vias allowed)
			(pads allowed)
			(copperpour not_allowed)
			(footprints allowed)
		)
		(placement
			(enabled no)
			(sheetname "")
		)
		(fill yes
			(thermal_gap 0.5)
			(thermal_bridge_width 0.5)
			(island_removal_mode 0)
		)
		(polygon
			(pts
				(arc
					(start 36.303204 -306.116736)
					(mid 35.650424 -306.116736)
					(end 36.303204 -306.116736)
				)
			)
		)
	)
	(zone
		(layers "B.Cu" "In11.Cu" "In13.Cu" "In15.Cu")
		(hatch none 0.5)
		(connect_pads
			(clearance 0)
		)
		(min_thickness 0.25)
		(keepout
			(tracks not_allowed)
			(vias allowed)
			(pads allowed)
			(copperpour not_allowed)
			(footprints allowed)
		)
		(placement
			(enabled no)
			(sheetname "")
		)
		(fill yes
			(thermal_gap 0.5)
			(thermal_bridge_width 0.5)
			(island_removal_mode 0)
		)
		(polygon
			(pts
				(arc
					(start 21.215604 -307.816758)
					(mid 20.562824 -307.816758)
					(end 21.215604 -307.816758)
				)
			)
		)
	)
	(zone
		(layers "B.Cu" "In11.Cu" "In13.Cu" "In15.Cu")
		(hatch none 0.5)
		(connect_pads
			(clearance 0)
		)
		(min_thickness 0.25)
		(keepout
			(tracks not_allowed)
			(vias allowed)
			(pads allowed)
			(copperpour not_allowed)
			(footprints allowed)
		)
		(placement
			(enabled no)
			(sheetname "")
		)
		(fill yes
			(thermal_gap 0.5)
			(thermal_bridge_width 0.5)
			(island_removal_mode 0)
		)
		(polygon
			(pts
				(arc
					(start 36.303204 -301.866808)
					(mid 35.650424 -301.866808)
					(end 36.303204 -301.866808)
				)
			)
		)
	)
	(zone
		(layers "B.Cu" "In11.Cu" "In13.Cu" "In15.Cu")
		(hatch none 0.5)
		(connect_pads
			(clearance 0)
		)
		(min_thickness 0.25)
		(keepout
			(tracks not_allowed)
			(vias allowed)
			(pads allowed)
			(copperpour not_allowed)
			(footprints allowed)
		)
		(placement
			(enabled no)
			(sheetname "")
		)
		(fill yes
			(thermal_gap 0.5)
			(thermal_bridge_width 0.5)
			(island_removal_mode 0)
		)
		(polygon
			(pts
				(arc
					(start 188.209936 -306.96662)
					(mid 187.557156 -306.96662)
					(end 188.209936 -306.96662)
				)
			)
		)
	)
	(zone
		(layers "B.Cu" "In11.Cu" "In13.Cu" "In15.Cu")
		(hatch none 0.5)
		(connect_pads
			(clearance 0)
		)
		(min_thickness 0.25)
		(keepout
			(tracks not_allowed)
			(vias allowed)
			(pads allowed)
			(copperpour not_allowed)
			(footprints allowed)
		)
		(placement
			(enabled no)
			(sheetname "")
		)
		(fill yes
			(thermal_gap 0.5)
			(thermal_bridge_width 0.5)
			(island_removal_mode 0)
		)
		(polygon
			(pts
				(arc
					(start 376.463052 -277.522432)
					(mid 375.810272 -277.522432)
					(end 376.463052 -277.522432)
				)
			)
		)
	)
	(zone
		(layers "B.Cu" "In11.Cu" "In13.Cu" "In15.Cu")
		(hatch none 0.5)
		(connect_pads
			(clearance 0)
		)
		(min_thickness 0.25)
		(keepout
			(tracks not_allowed)
			(vias allowed)
			(pads allowed)
			(copperpour not_allowed)
			(footprints allowed)
		)
		(placement
			(enabled no)
			(sheetname "")
		)
		(fill yes
			(thermal_gap 0.5)
			(thermal_bridge_width 0.5)
			(island_removal_mode 0)
		)
		(polygon
			(pts
				(arc
					(start 344.980006 -273.453098)
					(mid 344.327226 -273.453098)
					(end 344.980006 -273.453098)
				)
			)
		)
	)
	(zone
		(layers "B.Cu" "In11.Cu" "In13.Cu" "In15.Cu")
		(hatch none 0.5)
		(connect_pads
			(clearance 0)
		)
		(min_thickness 0.25)
		(keepout
			(tracks not_allowed)
			(vias allowed)
			(pads allowed)
			(copperpour not_allowed)
			(footprints allowed)
		)
		(placement
			(enabled no)
			(sheetname "")
		)
		(fill yes
			(thermal_gap 0.5)
			(thermal_bridge_width 0.5)
			(island_removal_mode 0)
		)
		(polygon
			(pts
				(arc
					(start 411.15488 -438.089802)
					(mid 410.345128 -438.089802)
					(end 411.15488 -438.089802)
				)
			)
		)
	)
	(zone
		(layers "B.Cu" "In11.Cu" "In13.Cu" "In15.Cu")
		(hatch none 0.5)
		(connect_pads
			(clearance 0)
		)
		(min_thickness 0.25)
		(keepout
			(tracks not_allowed)
			(vias allowed)
			(pads allowed)
			(copperpour not_allowed)
			(footprints allowed)
		)
		(placement
			(enabled no)
			(sheetname "")
		)
		(fill yes
			(thermal_gap 0.5)
			(thermal_bridge_width 0.5)
			(island_removal_mode 0)
		)
		(polygon
			(pts
				(arc
					(start 133.692138 -253.919736)
					(mid 133.039358 -253.919736)
					(end 133.692138 -253.919736)
				)
			)
		)
	)
	(zone
		(layers "B.Cu" "In11.Cu" "In13.Cu" "In15.Cu")
		(hatch none 0.5)
		(connect_pads
			(clearance 0)
		)
		(min_thickness 0.25)
		(keepout
			(tracks not_allowed)
			(vias allowed)
			(pads allowed)
			(copperpour not_allowed)
			(footprints allowed)
		)
		(placement
			(enabled no)
			(sheetname "")
		)
		(fill yes
			(thermal_gap 0.5)
			(thermal_bridge_width 0.5)
			(island_removal_mode 0)
		)
		(polygon
			(pts
				(arc
					(start 96.100138 -268.569694)
					(mid 95.447358 -268.569694)
					(end 96.100138 -268.569694)
				)
			)
		)
	)
	(zone
		(layers "B.Cu" "In11.Cu" "In13.Cu" "In15.Cu")
		(hatch none 0.5)
		(connect_pads
			(clearance 0)
		)
		(min_thickness 0.25)
		(keepout
			(tracks not_allowed)
			(vias allowed)
			(pads allowed)
			(copperpour not_allowed)
			(footprints allowed)
		)
		(placement
			(enabled no)
			(sheetname "")
		)
		(fill yes
			(thermal_gap 0.5)
			(thermal_bridge_width 0.5)
			(island_removal_mode 0)
		)
		(polygon
			(pts
				(arc
					(start 96.100138 -253.919736)
					(mid 95.447358 -253.919736)
					(end 96.100138 -253.919736)
				)
			)
		)
	)
	(zone
		(layers "B.Cu" "In11.Cu" "In13.Cu" "In15.Cu")
		(hatch none 0.5)
		(connect_pads
			(clearance 0)
		)
		(min_thickness 0.25)
		(keepout
			(tracks not_allowed)
			(vias allowed)
			(pads allowed)
			(copperpour not_allowed)
			(footprints allowed)
		)
		(placement
			(enabled no)
			(sheetname "")
		)
		(fill yes
			(thermal_gap 0.5)
			(thermal_bridge_width 0.5)
			(island_removal_mode 0)
		)
		(polygon
			(pts
				(arc
					(start 32.203136 -216.866724)
					(mid 31.550356 -216.866724)
					(end 32.203136 -216.866724)
				)
			)
		)
	)
	(zone
		(layers "B.Cu" "In11.Cu" "In13.Cu" "In15.Cu")
		(hatch none 0.5)
		(connect_pads
			(clearance 0)
		)
		(min_thickness 0.25)
		(keepout
			(tracks not_allowed)
			(vias allowed)
			(pads allowed)
			(copperpour not_allowed)
			(footprints allowed)
		)
		(placement
			(enabled no)
			(sheetname "")
		)
		(fill yes
			(thermal_gap 0.5)
			(thermal_bridge_width 0.5)
			(island_removal_mode 0)
		)
		(polygon
			(pts
				(arc
					(start 319.648078 -403.883876)
					(mid 318.944498 -403.883876)
					(end 319.648078 -403.883876)
				)
			)
		)
	)
	(zone
		(layers "B.Cu" "In11.Cu" "In13.Cu" "In15.Cu")
		(hatch none 0.5)
		(connect_pads
			(clearance 0)
		)
		(min_thickness 0.25)
		(keepout
			(tracks not_allowed)
			(vias allowed)
			(pads allowed)
			(copperpour not_allowed)
			(footprints allowed)
		)
		(placement
			(enabled no)
			(sheetname "")
		)
		(fill yes
			(thermal_gap 0.5)
			(thermal_bridge_width 0.5)
			(island_removal_mode 0)
		)
		(polygon
			(pts
				(arc
					(start 75.047348 -410.030168)
					(mid 74.343768 -410.030168)
					(end 75.047348 -410.030168)
				)
			)
		)
	)
	(zone
		(layers "B.Cu" "In11.Cu" "In13.Cu" "In15.Cu")
		(hatch none 0.5)
		(connect_pads
			(clearance 0)
		)
		(min_thickness 0.25)
		(keepout
			(tracks not_allowed)
			(vias allowed)
			(pads allowed)
			(copperpour not_allowed)
			(footprints allowed)
		)
		(placement
			(enabled no)
			(sheetname "")
		)
		(fill yes
			(thermal_gap 0.5)
			(thermal_bridge_width 0.5)
			(island_removal_mode 0)
		)
		(polygon
			(pts
				(arc
					(start 126.533402 -213.732618)
					(mid 125.880622 -213.732618)
					(end 126.533402 -213.732618)
				)
			)
		)
	)
	(zone
		(layers "B.Cu" "In11.Cu" "In13.Cu" "In15.Cu")
		(hatch none 0.5)
		(connect_pads
			(clearance 0)
		)
		(min_thickness 0.25)
		(keepout
			(tracks not_allowed)
			(vias allowed)
			(pads allowed)
			(copperpour not_allowed)
			(footprints allowed)
		)
		(placement
			(enabled no)
			(sheetname "")
		)
		(fill yes
			(thermal_gap 0.5)
			(thermal_bridge_width 0.5)
			(island_removal_mode 0)
		)
		(polygon
			(pts
				(arc
					(start 32.203136 -284.866588)
					(mid 31.550356 -284.866588)
					(end 32.203136 -284.866588)
				)
			)
		)
	)
	(zone
		(layers "B.Cu" "In11.Cu" "In13.Cu" "In15.Cu")
		(hatch none 0.5)
		(connect_pads
			(clearance 0)
		)
		(min_thickness 0.25)
		(keepout
			(tracks not_allowed)
			(vias allowed)
			(pads allowed)
			(copperpour not_allowed)
			(footprints allowed)
		)
		(placement
			(enabled no)
			(sheetname "")
		)
		(fill yes
			(thermal_gap 0.5)
			(thermal_bridge_width 0.5)
			(island_removal_mode 0)
		)
		(polygon
			(pts
				(arc
					(start 62.794388 -410.030168)
					(mid 62.090808 -410.030168)
					(end 62.794388 -410.030168)
				)
			)
		)
	)
	(zone
		(layers "B.Cu" "In11.Cu" "In13.Cu" "In15.Cu")
		(hatch none 0.5)
		(connect_pads
			(clearance 0)
		)
		(min_thickness 0.25)
		(keepout
			(tracks not_allowed)
			(vias allowed)
			(pads allowed)
			(copperpour not_allowed)
			(footprints allowed)
		)
		(placement
			(enabled no)
			(sheetname "")
		)
		(fill yes
			(thermal_gap 0.5)
			(thermal_bridge_width 0.5)
			(island_removal_mode 0)
		)
		(polygon
			(pts
				(arc
					(start 329.054968 -435.489858)
					(mid 328.245216 -435.489858)
					(end 329.054968 -435.489858)
				)
			)
		)
	)
	(zone
		(layers "B.Cu" "In11.Cu" "In13.Cu" "In15.Cu")
		(hatch none 0.5)
		(connect_pads
			(clearance 0)
		)
		(min_thickness 0.25)
		(keepout
			(tracks not_allowed)
			(vias allowed)
			(pads allowed)
			(copperpour not_allowed)
			(footprints allowed)
		)
		(placement
			(enabled no)
			(sheetname "")
		)
		(fill yes
			(thermal_gap 0.5)
			(thermal_bridge_width 0.5)
			(island_removal_mode 0)
		)
		(polygon
			(pts
				(arc
					(start 400.69008 -410.030168)
					(mid 399.9865 -410.030168)
					(end 400.69008 -410.030168)
				)
			)
		)
	)
	(zone
		(layers "B.Cu" "In11.Cu" "In13.Cu" "In15.Cu")
		(hatch none 0.5)
		(connect_pads
			(clearance 0)
		)
		(min_thickness 0.25)
		(keepout
			(tracks not_allowed)
			(vias allowed)
			(pads allowed)
			(copperpour not_allowed)
			(footprints allowed)
		)
		(placement
			(enabled no)
			(sheetname "")
		)
		(fill yes
			(thermal_gap 0.5)
			(thermal_bridge_width 0.5)
			(island_removal_mode 0)
		)
		(polygon
			(pts
				(arc
					(start 344.153998 -403.883876)
					(mid 343.450418 -403.883876)
					(end 344.153998 -403.883876)
				)
			)
		)
	)
	(zone
		(layers "B.Cu" "In11.Cu" "In13.Cu" "In15.Cu")
		(hatch none 0.5)
		(connect_pads
			(clearance 0)
		)
		(min_thickness 0.25)
		(keepout
			(tracks not_allowed)
			(vias allowed)
			(pads allowed)
			(copperpour not_allowed)
			(footprints allowed)
		)
		(placement
			(enabled no)
			(sheetname "")
		)
		(fill yes
			(thermal_gap 0.5)
			(thermal_bridge_width 0.5)
			(island_removal_mode 0)
		)
		(polygon
			(pts
				(arc
					(start 167.950896 -12.005056)
					(mid 167.247316 -12.005056)
					(end 167.950896 -12.005056)
				)
			)
		)
	)
	(zone
		(layers "B.Cu" "In11.Cu" "In13.Cu" "In15.Cu")
		(hatch none 0.5)
		(connect_pads
			(clearance 0)
		)
		(min_thickness 0.25)
		(keepout
			(tracks not_allowed)
			(vias allowed)
			(pads allowed)
			(copperpour not_allowed)
			(footprints allowed)
		)
		(placement
			(enabled no)
			(sheetname "")
		)
		(fill yes
			(thermal_gap 0.5)
			(thermal_bridge_width 0.5)
			(island_removal_mode 0)
		)
		(polygon
			(pts
				(arc
					(start 102.568756 -247.178322)
					(mid 101.915976 -247.178322)
					(end 102.568756 -247.178322)
				)
			)
		)
	)
	(zone
		(layers "B.Cu" "In11.Cu" "In13.Cu" "In15.Cu")
		(hatch none 0.5)
		(connect_pads
			(clearance 0)
		)
		(min_thickness 0.25)
		(keepout
			(tracks not_allowed)
			(vias allowed)
			(pads allowed)
			(copperpour not_allowed)
			(footprints allowed)
		)
		(placement
			(enabled no)
			(sheetname "")
		)
		(fill yes
			(thermal_gap 0.5)
			(thermal_bridge_width 0.5)
			(island_removal_mode 0)
		)
		(polygon
			(pts
				(arc
					(start 436.150004 -284.016704)
					(mid 435.497224 -284.016704)
					(end 436.150004 -284.016704)
				)
			)
		)
	)
	(zone
		(layers "B.Cu" "In11.Cu" "In13.Cu" "In15.Cu")
		(hatch none 0.5)
		(connect_pads
			(clearance 0)
		)
		(min_thickness 0.25)
		(keepout
			(tracks not_allowed)
			(vias allowed)
			(pads allowed)
			(copperpour not_allowed)
			(footprints allowed)
		)
		(placement
			(enabled no)
			(sheetname "")
		)
		(fill yes
			(thermal_gap 0.5)
			(thermal_bridge_width 0.5)
			(island_removal_mode 0)
		)
		(polygon
			(pts
				(arc
					(start 134.154926 -429.689768)
					(mid 133.345174 -429.689768)
					(end 134.154926 -429.689768)
				)
			)
		)
	)
	(zone
		(layers "B.Cu" "In11.Cu" "In13.Cu" "In15.Cu")
		(hatch none 0.5)
		(connect_pads
			(clearance 0)
		)
		(min_thickness 0.25)
		(keepout
			(tracks not_allowed)
			(vias allowed)
			(pads allowed)
			(copperpour not_allowed)
			(footprints allowed)
		)
		(placement
			(enabled no)
			(sheetname "")
		)
		(fill yes
			(thermal_gap 0.5)
			(thermal_bridge_width 0.5)
			(island_removal_mode 0)
		)
		(polygon
			(pts
				(arc
					(start 280.143204 -284.016704)
					(mid 279.490424 -284.016704)
					(end 280.143204 -284.016704)
				)
			)
		)
	)
	(zone
		(layers "B.Cu" "In11.Cu" "In13.Cu" "In15.Cu")
		(hatch none 0.5)
		(connect_pads
			(clearance 0)
		)
		(min_thickness 0.25)
		(keepout
			(tracks not_allowed)
			(vias allowed)
			(pads allowed)
			(copperpour not_allowed)
			(footprints allowed)
		)
		(placement
			(enabled no)
			(sheetname "")
		)
		(fill yes
			(thermal_gap 0.5)
			(thermal_bridge_width 0.5)
			(island_removal_mode 0)
		)
		(polygon
			(pts
				(arc
					(start 343.46007 -246.364506)
					(mid 342.80729 -246.364506)
					(end 343.46007 -246.364506)
				)
			)
		)
	)
	(zone
		(layers "B.Cu" "In11.Cu" "In13.Cu" "In15.Cu")
		(hatch none 0.5)
		(connect_pads
			(clearance 0)
		)
		(min_thickness 0.25)
		(keepout
			(tracks not_allowed)
			(vias allowed)
			(pads allowed)
			(copperpour not_allowed)
			(footprints allowed)
		)
		(placement
			(enabled no)
			(sheetname "")
		)
		(fill yes
			(thermal_gap 0.5)
			(thermal_bridge_width 0.5)
			(island_removal_mode 0)
		)
		(polygon
			(pts
				(arc
					(start 334.964278 -403.883876)
					(mid 334.260698 -403.883876)
					(end 334.964278 -403.883876)
				)
			)
		)
	)
	(zone
		(layers "B.Cu" "In11.Cu" "In13.Cu" "In15.Cu")
		(hatch none 0.5)
		(connect_pads
			(clearance 0)
		)
		(min_thickness 0.25)
		(keepout
			(tracks not_allowed)
			(vias allowed)
			(pads allowed)
			(copperpour not_allowed)
			(footprints allowed)
		)
		(placement
			(enabled no)
			(sheetname "")
		)
		(fill yes
			(thermal_gap 0.5)
			(thermal_bridge_width 0.5)
			(island_removal_mode 0)
		)
		(polygon
			(pts
				(arc
					(start 280.143204 -219.41663)
					(mid 279.490424 -219.41663)
					(end 280.143204 -219.41663)
				)
			)
		)
	)
	(zone
		(layers "B.Cu" "In11.Cu" "In13.Cu" "In15.Cu")
		(hatch none 0.5)
		(connect_pads
			(clearance 0)
		)
		(min_thickness 0.25)
		(keepout
			(tracks not_allowed)
			(vias allowed)
			(pads allowed)
			(copperpour not_allowed)
			(footprints allowed)
		)
		(placement
			(enabled no)
			(sheetname "")
		)
		(fill yes
			(thermal_gap 0.5)
			(thermal_bridge_width 0.5)
			(island_removal_mode 0)
		)
		(polygon
			(pts
				(arc
					(start 269.155672 -204.96657)
					(mid 268.502892 -204.96657)
					(end 269.155672 -204.96657)
				)
			)
		)
	)
	(zone
		(layers "B.Cu" "In11.Cu" "In13.Cu" "In15.Cu")
		(hatch none 0.5)
		(connect_pads
			(clearance 0)
		)
		(min_thickness 0.25)
		(keepout
			(tracks not_allowed)
			(vias allowed)
			(pads allowed)
			(copperpour not_allowed)
			(footprints allowed)
		)
		(placement
			(enabled no)
			(sheetname "")
		)
		(fill yes
			(thermal_gap 0.5)
			(thermal_bridge_width 0.5)
			(island_removal_mode 0)
		)
		(polygon
			(pts
				(arc
					(start 345.919806 -275.08073)
					(mid 345.267026 -275.08073)
					(end 345.919806 -275.08073)
				)
			)
		)
	)
	(zone
		(layers "B.Cu" "In11.Cu" "In13.Cu" "In15.Cu")
		(hatch none 0.5)
		(connect_pads
			(clearance 0)
		)
		(min_thickness 0.25)
		(keepout
			(tracks not_allowed)
			(vias allowed)
			(pads allowed)
			(copperpour not_allowed)
			(footprints allowed)
		)
		(placement
			(enabled no)
			(sheetname "")
		)
		(fill yes
			(thermal_gap 0.5)
			(thermal_bridge_width 0.5)
			(island_removal_mode 0)
		)
		(polygon
			(pts
				(arc
					(start 68.057268 -410.030168)
					(mid 67.353688 -410.030168)
					(end 68.057268 -410.030168)
				)
			)
		)
	)
	(zone
		(layers "B.Cu" "In11.Cu" "In13.Cu" "In15.Cu")
		(hatch none 0.5)
		(connect_pads
			(clearance 0)
		)
		(min_thickness 0.25)
		(keepout
			(tracks not_allowed)
			(vias allowed)
			(pads allowed)
			(copperpour not_allowed)
			(footprints allowed)
		)
		(placement
			(enabled no)
			(sheetname "")
		)
		(fill yes
			(thermal_gap 0.5)
			(thermal_bridge_width 0.5)
			(island_removal_mode 0)
		)
		(polygon
			(pts
				(arc
					(start 436.150004 -275.516594)
					(mid 435.497224 -275.516594)
					(end 436.150004 -275.516594)
				)
			)
		)
	)
	(zone
		(layers "B.Cu" "In11.Cu" "In13.Cu" "In15.Cu")
		(hatch none 0.5)
		(connect_pads
			(clearance 0)
		)
		(min_thickness 0.25)
		(keepout
			(tracks not_allowed)
			(vias allowed)
			(pads allowed)
			(copperpour not_allowed)
			(footprints allowed)
		)
		(placement
			(enabled no)
			(sheetname "")
		)
		(fill yes
			(thermal_gap 0.5)
			(thermal_bridge_width 0.5)
			(island_removal_mode 0)
		)
		(polygon
			(pts
				(arc
					(start 350.97847 -215.436704)
					(mid 350.32569 -215.436704)
					(end 350.97847 -215.436704)
				)
			)
		)
	)
	(zone
		(layers "B.Cu" "In11.Cu" "In13.Cu" "In15.Cu")
		(hatch none 0.5)
		(connect_pads
			(clearance 0)
		)
		(min_thickness 0.25)
		(keepout
			(tracks not_allowed)
			(vias allowed)
			(pads allowed)
			(copperpour not_allowed)
			(footprints allowed)
		)
		(placement
			(enabled no)
			(sheetname "")
		)
		(fill yes
			(thermal_gap 0.5)
			(thermal_bridge_width 0.5)
			(island_removal_mode 0)
		)
		(polygon
			(pts
				(arc
					(start 90.054938 -435.489858)
					(mid 89.245186 -435.489858)
					(end 90.054938 -435.489858)
				)
			)
		)
	)
	(zone
		(layers "B.Cu" "In11.Cu" "In13.Cu" "In15.Cu")
		(hatch none 0.5)
		(connect_pads
			(clearance 0)
		)
		(min_thickness 0.25)
		(keepout
			(tracks not_allowed)
			(vias allowed)
			(pads allowed)
			(copperpour not_allowed)
			(footprints allowed)
		)
		(placement
			(enabled no)
			(sheetname "")
		)
		(fill yes
			(thermal_gap 0.5)
			(thermal_bridge_width 0.5)
			(island_removal_mode 0)
		)
		(polygon
			(pts
				(arc
					(start 347.093286 -71.816976)
					(mid 346.389706 -71.816976)
					(end 347.093286 -71.816976)
				)
			)
		)
	)
	(zone
		(layers "B.Cu" "In11.Cu" "In13.Cu" "In15.Cu")
		(hatch none 0.5)
		(connect_pads
			(clearance 0)
		)
		(min_thickness 0.25)
		(keepout
			(tracks not_allowed)
			(vias allowed)
			(pads allowed)
			(copperpour not_allowed)
			(footprints allowed)
		)
		(placement
			(enabled no)
			(sheetname "")
		)
		(fill yes
			(thermal_gap 0.5)
			(thermal_bridge_width 0.5)
			(island_removal_mode 0)
		)
		(polygon
			(pts
				(arc
					(start 436.150004 -202.416664)
					(mid 435.497224 -202.416664)
					(end 436.150004 -202.416664)
				)
			)
		)
	)
	(zone
		(layers "B.Cu" "In11.Cu" "In13.Cu" "In15.Cu")
		(hatch none 0.5)
		(connect_pads
			(clearance 0)
		)
		(min_thickness 0.25)
		(keepout
			(tracks not_allowed)
			(vias allowed)
			(pads allowed)
			(copperpour not_allowed)
			(footprints allowed)
		)
		(placement
			(enabled no)
			(sheetname "")
		)
		(fill yes
			(thermal_gap 0.5)
			(thermal_bridge_width 0.5)
			(island_removal_mode 0)
		)
		(polygon
			(pts
				(arc
					(start 167.087296 -12.005056)
					(mid 166.383716 -12.005056)
					(end 167.087296 -12.005056)
				)
			)
		)
	)
	(zone
		(layers "B.Cu" "In11.Cu" "In13.Cu" "In15.Cu")
		(hatch none 0.5)
		(connect_pads
			(clearance 0)
		)
		(min_thickness 0.25)
		(keepout
			(tracks not_allowed)
			(vias allowed)
			(pads allowed)
			(copperpour not_allowed)
			(footprints allowed)
		)
		(placement
			(enabled no)
			(sheetname "")
		)
		(fill yes
			(thermal_gap 0.5)
			(thermal_bridge_width 0.5)
			(island_removal_mode 0)
		)
		(polygon
			(pts
				(arc
					(start 188.209936 -243.216684)
					(mid 187.557156 -243.216684)
					(end 188.209936 -243.216684)
				)
			)
		)
	)
	(zone
		(layers "B.Cu" "In11.Cu" "In13.Cu" "In15.Cu")
		(hatch none 0.5)
		(connect_pads
			(clearance 0)
		)
		(min_thickness 0.25)
		(keepout
			(tracks not_allowed)
			(vias allowed)
			(pads allowed)
			(copperpour not_allowed)
			(footprints allowed)
		)
		(placement
			(enabled no)
			(sheetname "")
		)
		(fill yes
			(thermal_gap 0.5)
			(thermal_bridge_width 0.5)
			(island_removal_mode 0)
		)
		(polygon
			(pts
				(arc
					(start 307.395118 -403.883876)
					(mid 306.691538 -403.883876)
					(end 307.395118 -403.883876)
				)
			)
		)
	)
	(zone
		(layers "B.Cu" "In11.Cu" "In13.Cu" "In15.Cu")
		(hatch none 0.5)
		(connect_pads
			(clearance 0)
		)
		(min_thickness 0.25)
		(keepout
			(tracks not_allowed)
			(vias allowed)
			(pads allowed)
			(copperpour not_allowed)
			(footprints allowed)
		)
		(placement
			(enabled no)
			(sheetname "")
		)
		(fill yes
			(thermal_gap 0.5)
			(thermal_bridge_width 0.5)
			(island_removal_mode 0)
		)
		(polygon
			(pts
				(arc
					(start 88.054942 -426.089826)
					(mid 87.24519 -426.089826)
					(end 88.054942 -426.089826)
				)
			)
		)
	)
	(zone
		(layers "B.Cu" "In11.Cu" "In13.Cu" "In15.Cu")
		(hatch none 0.5)
		(connect_pads
			(clearance 0)
		)
		(min_thickness 0.25)
		(keepout
			(tracks not_allowed)
			(vias allowed)
			(pads allowed)
			(copperpour not_allowed)
			(footprints allowed)
		)
		(placement
			(enabled no)
			(sheetname "")
		)
		(fill yes
			(thermal_gap 0.5)
			(thermal_bridge_width 0.5)
			(island_removal_mode 0)
		)
		(polygon
			(pts
				(arc
					(start 32.203136 -278.916638)
					(mid 31.550356 -278.916638)
					(end 32.203136 -278.916638)
				)
			)
		)
	)
	(zone
		(layers "B.Cu" "In11.Cu" "In13.Cu" "In15.Cu")
		(hatch none 0.5)
		(connect_pads
			(clearance 0)
		)
		(min_thickness 0.25)
		(keepout
			(tracks not_allowed)
			(vias allowed)
			(pads allowed)
			(copperpour not_allowed)
			(footprints allowed)
		)
		(placement
			(enabled no)
			(sheetname "")
		)
		(fill yes
			(thermal_gap 0.5)
			(thermal_bridge_width 0.5)
			(island_removal_mode 0)
		)
		(polygon
			(pts
				(arc
					(start 152.485344 -410.030168)
					(mid 151.781764 -410.030168)
					(end 152.485344 -410.030168)
				)
			)
		)
	)
	(zone
		(layers "B.Cu" "In11.Cu" "In13.Cu" "In15.Cu")
		(hatch none 0.5)
		(connect_pads
			(clearance 0)
		)
		(min_thickness 0.25)
		(keepout
			(tracks not_allowed)
			(vias allowed)
			(pads allowed)
			(copperpour not_allowed)
			(footprints allowed)
		)
		(placement
			(enabled no)
			(sheetname "")
		)
		(fill yes
			(thermal_gap 0.5)
			(thermal_bridge_width 0.5)
			(island_removal_mode 0)
		)
		(polygon
			(pts
				(arc
					(start 265.055604 -245.76659)
					(mid 264.402824 -245.76659)
					(end 265.055604 -245.76659)
				)
			)
		)
	)
	(zone
		(layers "B.Cu" "In11.Cu" "In13.Cu" "In15.Cu")
		(hatch none 0.5)
		(connect_pads
			(clearance 0)
		)
		(min_thickness 0.25)
		(keepout
			(tracks not_allowed)
			(vias allowed)
			(pads allowed)
			(copperpour not_allowed)
			(footprints allowed)
		)
		(placement
			(enabled no)
			(sheetname "")
		)
		(fill yes
			(thermal_gap 0.5)
			(thermal_bridge_width 0.5)
			(island_removal_mode 0)
		)
		(polygon
			(pts
				(arc
					(start 210.841336 -245.76659)
					(mid 210.188556 -245.76659)
					(end 210.841336 -245.76659)
				)
			)
		)
	)
	(zone
		(layers "B.Cu" "In11.Cu" "In13.Cu" "In15.Cu")
		(hatch none 0.5)
		(connect_pads
			(clearance 0)
		)
		(min_thickness 0.25)
		(keepout
			(tracks not_allowed)
			(vias allowed)
			(pads allowed)
			(copperpour not_allowed)
			(footprints allowed)
		)
		(placement
			(enabled no)
			(sheetname "")
		)
		(fill yes
			(thermal_gap 0.5)
			(thermal_bridge_width 0.5)
			(island_removal_mode 0)
		)
		(polygon
			(pts
				(arc
					(start 32.203136 -232.166668)
					(mid 31.550356 -232.166668)
					(end 32.203136 -232.166668)
				)
			)
		)
	)
	(zone
		(layers "B.Cu" "In11.Cu" "In13.Cu" "In15.Cu")
		(hatch none 0.5)
		(connect_pads
			(clearance 0)
		)
		(min_thickness 0.25)
		(keepout
			(tracks not_allowed)
			(vias allowed)
			(pads allowed)
			(copperpour not_allowed)
			(footprints allowed)
		)
		(placement
			(enabled no)
			(sheetname "")
		)
		(fill yes
			(thermal_gap 0.5)
			(thermal_bridge_width 0.5)
			(island_removal_mode 0)
		)
		(polygon
			(pts
				(arc
					(start 69.05498 -427.089824)
					(mid 68.245228 -427.089824)
					(end 69.05498 -427.089824)
				)
			)
		)
	)
	(zone
		(layers "B.Cu" "In11.Cu" "In13.Cu" "In15.Cu")
		(hatch none 0.5)
		(connect_pads
			(clearance 0)
		)
		(min_thickness 0.25)
		(keepout
			(tracks not_allowed)
			(vias allowed)
			(pads allowed)
			(copperpour not_allowed)
			(footprints allowed)
		)
		(placement
			(enabled no)
			(sheetname "")
		)
		(fill yes
			(thermal_gap 0.5)
			(thermal_bridge_width 0.5)
			(island_removal_mode 0)
		)
		(polygon
			(pts
				(arc
					(start 188.209936 -222.816674)
					(mid 187.557156 -222.816674)
					(end 188.209936 -222.816674)
				)
			)
		)
	)
	(zone
		(layers "B.Cu" "In11.Cu" "In13.Cu" "In15.Cu")
		(hatch none 0.5)
		(connect_pads
			(clearance 0)
		)
		(min_thickness 0.25)
		(keepout
			(tracks not_allowed)
			(vias allowed)
			(pads allowed)
			(copperpour not_allowed)
			(footprints allowed)
		)
		(placement
			(enabled no)
			(sheetname "")
		)
		(fill yes
			(thermal_gap 0.5)
			(thermal_bridge_width 0.5)
			(island_removal_mode 0)
		)
		(polygon
			(pts
				(arc
					(start 135.931402 -215.436704)
					(mid 135.278622 -215.436704)
					(end 135.931402 -215.436704)
				)
			)
		)
	)
	(zone
		(layers "B.Cu" "In11.Cu" "In13.Cu" "In15.Cu")
		(hatch none 0.5)
		(connect_pads
			(clearance 0)
		)
		(min_thickness 0.25)
		(keepout
			(tracks not_allowed)
			(vias allowed)
			(pads allowed)
			(copperpour not_allowed)
			(footprints allowed)
		)
		(placement
			(enabled no)
			(sheetname "")
		)
		(fill yes
			(thermal_gap 0.5)
			(thermal_bridge_width 0.5)
			(island_removal_mode 0)
		)
		(polygon
			(pts
				(arc
					(start 333.702152 -284.847538)
					(mid 333.049372 -284.847538)
					(end 333.702152 -284.847538)
				)
			)
		)
	)
	(zone
		(layers "B.Cu" "In11.Cu" "In13.Cu" "In15.Cu")
		(hatch none 0.5)
		(connect_pads
			(clearance 0)
		)
		(min_thickness 0.25)
		(keepout
			(tracks not_allowed)
			(vias allowed)
			(pads allowed)
			(copperpour not_allowed)
			(footprints allowed)
		)
		(placement
			(enabled no)
			(sheetname "")
		)
		(fill yes
			(thermal_gap 0.5)
			(thermal_bridge_width 0.5)
			(island_removal_mode 0)
		)
		(polygon
			(pts
				(arc
					(start 65.054988 -434.289962)
					(mid 64.245236 -434.289962)
					(end 65.054988 -434.289962)
				)
			)
		)
	)
	(zone
		(layers "B.Cu" "In11.Cu" "In13.Cu" "In15.Cu")
		(hatch none 0.5)
		(connect_pads
			(clearance 0)
		)
		(min_thickness 0.25)
		(keepout
			(tracks not_allowed)
			(vias allowed)
			(pads allowed)
			(copperpour not_allowed)
			(footprints allowed)
		)
		(placement
			(enabled no)
			(sheetname "")
		)
		(fill yes
			(thermal_gap 0.5)
			(thermal_bridge_width 0.5)
			(island_removal_mode 0)
		)
		(polygon
			(pts
				(arc
					(start 195.753736 -244.066568)
					(mid 195.100956 -244.066568)
					(end 195.753736 -244.066568)
				)
			)
		)
	)
	(zone
		(layers "B.Cu" "In11.Cu" "In13.Cu" "In15.Cu")
		(hatch none 0.5)
		(connect_pads
			(clearance 0)
		)
		(min_thickness 0.25)
		(keepout
			(tracks not_allowed)
			(vias allowed)
			(pads allowed)
			(copperpour not_allowed)
			(footprints allowed)
		)
		(placement
			(enabled no)
			(sheetname "")
		)
		(fill yes
			(thermal_gap 0.5)
			(thermal_bridge_width 0.5)
			(island_removal_mode 0)
		)
		(polygon
			(pts
				(arc
					(start 95.050356 -227.64496)
					(mid 94.397576 -227.64496)
					(end 95.050356 -227.64496)
				)
			)
		)
	)
	(zone
		(layers "B.Cu" "In11.Cu" "In13.Cu" "In15.Cu")
		(hatch none 0.5)
		(connect_pads
			(clearance 0)
		)
		(min_thickness 0.25)
		(keepout
			(tracks not_allowed)
			(vias allowed)
			(pads allowed)
			(copperpour not_allowed)
			(footprints allowed)
		)
		(placement
			(enabled no)
			(sheetname "")
		)
		(fill yes
			(thermal_gap 0.5)
			(thermal_bridge_width 0.5)
			(island_removal_mode 0)
		)
		(polygon
			(pts
				(arc
					(start 93.640402 -215.436704)
					(mid 92.987622 -215.436704)
					(end 93.640402 -215.436704)
				)
			)
		)
	)
	(zone
		(layers "B.Cu" "In11.Cu" "In13.Cu" "In15.Cu")
		(hatch none 0.5)
		(connect_pads
			(clearance 0)
		)
		(min_thickness 0.25)
		(keepout
			(tracks not_allowed)
			(vias allowed)
			(pads allowed)
			(copperpour not_allowed)
			(footprints allowed)
		)
		(placement
			(enabled no)
			(sheetname "")
		)
		(fill yes
			(thermal_gap 0.5)
			(thermal_bridge_width 0.5)
			(island_removal_mode 0)
		)
		(polygon
			(pts
				(arc
					(start 36.303204 -221.96679)
					(mid 35.650424 -221.96679)
					(end 36.303204 -221.96679)
				)
			)
		)
	)
	(zone
		(layers "B.Cu" "In11.Cu" "In13.Cu" "In15.Cu")
		(hatch none 0.5)
		(connect_pads
			(clearance 0)
		)
		(min_thickness 0.25)
		(keepout
			(tracks not_allowed)
			(vias allowed)
			(pads allowed)
			(copperpour not_allowed)
			(footprints allowed)
		)
		(placement
			(enabled no)
			(sheetname "")
		)
		(fill yes
			(thermal_gap 0.5)
			(thermal_bridge_width 0.5)
			(island_removal_mode 0)
		)
		(polygon
			(pts
				(arc
					(start 188.209936 -202.416664)
					(mid 187.557156 -202.416664)
					(end 188.209936 -202.416664)
				)
			)
		)
	)
	(zone
		(layers "B.Cu" "In11.Cu" "In13.Cu" "In15.Cu")
		(hatch none 0.5)
		(connect_pads
			(clearance 0)
		)
		(min_thickness 0.25)
		(keepout
			(tracks not_allowed)
			(vias allowed)
			(pads allowed)
			(copperpour not_allowed)
			(footprints allowed)
		)
		(placement
			(enabled no)
			(sheetname "")
		)
		(fill yes
			(thermal_gap 0.5)
			(thermal_bridge_width 0.5)
			(island_removal_mode 0)
		)
		(polygon
			(pts
				(arc
					(start 89.051638 -282.405836)
					(mid 88.398858 -282.405836)
					(end 89.051638 -282.405836)
				)
			)
		)
	)
	(zone
		(layers "B.Cu" "In11.Cu" "In13.Cu" "In15.Cu")
		(hatch none 0.5)
		(connect_pads
			(clearance 0)
		)
		(min_thickness 0.25)
		(keepout
			(tracks not_allowed)
			(vias allowed)
			(pads allowed)
			(copperpour not_allowed)
			(footprints allowed)
		)
		(placement
			(enabled no)
			(sheetname "")
		)
		(fill yes
			(thermal_gap 0.5)
			(thermal_bridge_width 0.5)
			(island_removal_mode 0)
		)
		(polygon
			(pts
				(arc
					(start 356.308914 -50.207672)
					(mid 355.605334 -50.207672)
					(end 356.308914 -50.207672)
				)
			)
		)
	)
	(zone
		(layers "B.Cu" "In11.Cu" "In13.Cu" "In15.Cu")
		(hatch none 0.5)
		(connect_pads
			(clearance 0)
		)
		(min_thickness 0.25)
		(keepout
			(tracks not_allowed)
			(vias allowed)
			(pads allowed)
			(copperpour not_allowed)
			(footprints allowed)
		)
		(placement
			(enabled no)
			(sheetname "")
		)
		(fill yes
			(thermal_gap 0.5)
			(thermal_bridge_width 0.5)
			(island_removal_mode 0)
		)
		(polygon
			(pts
				(arc
					(start 192.310004 -278.066754)
					(mid 191.657224 -278.066754)
					(end 192.310004 -278.066754)
				)
			)
		)
	)
	(zone
		(layers "B.Cu" "In11.Cu" "In13.Cu" "In15.Cu")
		(hatch none 0.5)
		(connect_pads
			(clearance 0)
		)
		(min_thickness 0.25)
		(keepout
			(tracks not_allowed)
			(vias allowed)
			(pads allowed)
			(copperpour not_allowed)
			(footprints allowed)
		)
		(placement
			(enabled no)
			(sheetname "")
		)
		(fill yes
			(thermal_gap 0.5)
			(thermal_bridge_width 0.5)
			(island_removal_mode 0)
		)
		(polygon
			(pts
				(arc
					(start 382.154938 -430.889918)
					(mid 381.345186 -430.889918)
					(end 382.154938 -430.889918)
				)
			)
		)
	)
	(zone
		(layers "B.Cu" "In11.Cu" "In13.Cu" "In15.Cu")
		(hatch none 0.5)
		(connect_pads
			(clearance 0)
		)
		(min_thickness 0.25)
		(keepout
			(tracks not_allowed)
			(vias allowed)
			(pads allowed)
			(copperpour not_allowed)
			(footprints allowed)
		)
		(placement
			(enabled no)
			(sheetname "")
		)
		(fill yes
			(thermal_gap 0.5)
			(thermal_bridge_width 0.5)
			(island_removal_mode 0)
		)
		(polygon
			(pts
				(arc
					(start 377.402852 -277.522432)
					(mid 376.750072 -277.522432)
					(end 377.402852 -277.522432)
				)
			)
		)
	)
	(zone
		(layers "B.Cu" "In11.Cu" "In13.Cu" "In15.Cu")
		(hatch none 0.5)
		(connect_pads
			(clearance 0)
		)
		(min_thickness 0.25)
		(keepout
			(tracks not_allowed)
			(vias allowed)
			(pads allowed)
			(copperpour not_allowed)
			(footprints allowed)
		)
		(placement
			(enabled no)
			(sheetname "")
		)
		(fill yes
			(thermal_gap 0.5)
			(thermal_bridge_width 0.5)
			(island_removal_mode 0)
		)
		(polygon
			(pts
				(arc
					(start 97.399602 -228.45903)
					(mid 96.746822 -228.45903)
					(end 97.399602 -228.45903)
				)
			)
		)
	)
	(zone
		(layers "B.Cu" "In11.Cu" "In13.Cu" "In15.Cu")
		(hatch none 0.5)
		(connect_pads
			(clearance 0)
		)
		(min_thickness 0.25)
		(keepout
			(tracks not_allowed)
			(vias allowed)
			(pads allowed)
			(copperpour not_allowed)
			(footprints allowed)
		)
		(placement
			(enabled no)
			(sheetname "")
		)
		(fill yes
			(thermal_gap 0.5)
			(thermal_bridge_width 0.5)
			(island_removal_mode 0)
		)
		(polygon
			(pts
				(arc
					(start 192.310004 -223.666558)
					(mid 191.657224 -223.666558)
					(end 192.310004 -223.666558)
				)
			)
		)
	)
	(zone
		(layers "B.Cu" "In11.Cu" "In13.Cu" "In15.Cu")
		(hatch none 0.5)
		(connect_pads
			(clearance 0)
		)
		(min_thickness 0.25)
		(keepout
			(tracks not_allowed)
			(vias allowed)
			(pads allowed)
			(copperpour not_allowed)
			(footprints allowed)
		)
		(placement
			(enabled no)
			(sheetname "")
		)
		(fill yes
			(thermal_gap 0.5)
			(thermal_bridge_width 0.5)
			(island_removal_mode 0)
		)
		(polygon
			(pts
				(arc
					(start 359.43667 -215.436704)
					(mid 358.78389 -215.436704)
					(end 359.43667 -215.436704)
				)
			)
		)
	)
	(zone
		(layers "B.Cu" "In11.Cu" "In13.Cu" "In15.Cu")
		(hatch none 0.5)
		(connect_pads
			(clearance 0)
		)
		(min_thickness 0.25)
		(keepout
			(tracks not_allowed)
			(vias allowed)
			(pads allowed)
			(copperpour not_allowed)
			(footprints allowed)
		)
		(placement
			(enabled no)
			(sheetname "")
		)
		(fill yes
			(thermal_gap 0.5)
			(thermal_bridge_width 0.5)
			(island_removal_mode 0)
		)
		(polygon
			(pts
				(arc
					(start 92.700856 -213.732618)
					(mid 92.048076 -213.732618)
					(end 92.700856 -213.732618)
				)
			)
		)
	)
	(zone
		(layers "B.Cu" "In11.Cu" "In13.Cu" "In15.Cu")
		(hatch none 0.5)
		(connect_pads
			(clearance 0)
		)
		(min_thickness 0.25)
		(keepout
			(tracks not_allowed)
			(vias allowed)
			(pads allowed)
			(copperpour not_allowed)
			(footprints allowed)
		)
		(placement
			(enabled no)
			(sheetname "")
		)
		(fill yes
			(thermal_gap 0.5)
			(thermal_bridge_width 0.5)
			(island_removal_mode 0)
		)
		(polygon
			(pts
				(arc
					(start 207.397604 -208.366614)
					(mid 206.744824 -208.366614)
					(end 207.397604 -208.366614)
				)
			)
		)
	)
	(zone
		(layers "B.Cu" "In11.Cu" "In13.Cu" "In15.Cu")
		(hatch none 0.5)
		(connect_pads
			(clearance 0)
		)
		(min_thickness 0.25)
		(keepout
			(tracks not_allowed)
			(vias allowed)
			(pads allowed)
			(copperpour not_allowed)
			(footprints allowed)
		)
		(placement
			(enabled no)
			(sheetname "")
		)
		(fill yes
			(thermal_gap 0.5)
			(thermal_bridge_width 0.5)
			(island_removal_mode 0)
		)
		(polygon
			(pts
				(arc
					(start 32.203136 -284.016704)
					(mid 31.550356 -284.016704)
					(end 32.203136 -284.016704)
				)
			)
		)
	)
	(zone
		(layers "B.Cu" "In11.Cu" "In13.Cu" "In15.Cu")
		(hatch none 0.5)
		(connect_pads
			(clearance 0)
		)
		(min_thickness 0.25)
		(keepout
			(tracks not_allowed)
			(vias allowed)
			(pads allowed)
			(copperpour not_allowed)
			(footprints allowed)
		)
		(placement
			(enabled no)
			(sheetname "")
		)
		(fill yes
			(thermal_gap 0.5)
			(thermal_bridge_width 0.5)
			(island_removal_mode 0)
		)
		(polygon
			(pts
				(arc
					(start 342.990424 -237.411514)
					(mid 342.337644 -237.411514)
					(end 342.990424 -237.411514)
				)
			)
		)
	)
	(zone
		(layers "B.Cu" "In11.Cu" "In13.Cu" "In15.Cu")
		(hatch none 0.5)
		(connect_pads
			(clearance 0)
		)
		(min_thickness 0.25)
		(keepout
			(tracks not_allowed)
			(vias allowed)
			(pads allowed)
			(copperpour not_allowed)
			(footprints allowed)
		)
		(placement
			(enabled no)
			(sheetname "")
		)
		(fill yes
			(thermal_gap 0.5)
			(thermal_bridge_width 0.5)
			(island_removal_mode 0)
		)
		(polygon
			(pts
				(arc
					(start 382.154938 -438.089802)
					(mid 381.345186 -438.089802)
					(end 382.154938 -438.089802)
				)
			)
		)
	)
	(zone
		(layers "B.Cu" "In11.Cu" "In13.Cu" "In15.Cu")
		(hatch none 0.5)
		(connect_pads
			(clearance 0)
		)
		(min_thickness 0.25)
		(keepout
			(tracks not_allowed)
			(vias allowed)
			(pads allowed)
			(copperpour not_allowed)
			(footprints allowed)
		)
		(placement
			(enabled no)
			(sheetname "")
		)
		(fill yes
			(thermal_gap 0.5)
			(thermal_bridge_width 0.5)
			(island_removal_mode 0)
		)
		(polygon
			(pts
				(arc
					(start 155.154884 -438.089802)
					(mid 154.345132 -438.089802)
					(end 155.154884 -438.089802)
				)
			)
		)
	)
	(zone
		(layers "B.Cu" "In11.Cu" "In13.Cu" "In15.Cu")
		(hatch none 0.5)
		(connect_pads
			(clearance 0)
		)
		(min_thickness 0.25)
		(keepout
			(tracks not_allowed)
			(vias allowed)
			(pads allowed)
			(copperpour not_allowed)
			(footprints allowed)
		)
		(placement
			(enabled no)
			(sheetname "")
		)
		(fill yes
			(thermal_gap 0.5)
			(thermal_bridge_width 0.5)
			(island_removal_mode 0)
		)
		(polygon
			(pts
				(arc
					(start 350.618806 -279.964134)
					(mid 349.966026 -279.964134)
					(end 350.618806 -279.964134)
				)
			)
		)
	)
	(zone
		(layers "B.Cu" "In11.Cu" "In13.Cu" "In15.Cu")
		(hatch none 0.5)
		(connect_pads
			(clearance 0)
		)
		(min_thickness 0.25)
		(keepout
			(tracks not_allowed)
			(vias allowed)
			(pads allowed)
			(copperpour not_allowed)
			(footprints allowed)
		)
		(placement
			(enabled no)
			(sheetname "")
		)
		(fill yes
			(thermal_gap 0.5)
			(thermal_bridge_width 0.5)
			(island_removal_mode 0)
		)
		(polygon
			(pts
				(arc
					(start 284.243272 -281.466798)
					(mid 283.590492 -281.466798)
					(end 284.243272 -281.466798)
				)
			)
		)
	)
	(zone
		(layers "B.Cu" "In11.Cu" "In13.Cu" "In15.Cu")
		(hatch none 0.5)
		(connect_pads
			(clearance 0)
		)
		(min_thickness 0.25)
		(keepout
			(tracks not_allowed)
			(vias allowed)
			(pads allowed)
			(copperpour not_allowed)
			(footprints allowed)
		)
		(placement
			(enabled no)
			(sheetname "")
		)
		(fill yes
			(thermal_gap 0.5)
			(thermal_bridge_width 0.5)
			(island_removal_mode 0)
		)
		(polygon
			(pts
				(arc
					(start 407.154888 -436.889906)
					(mid 406.345136 -436.889906)
					(end 407.154888 -436.889906)
				)
			)
		)
	)
	(zone
		(layers "B.Cu" "In11.Cu" "In13.Cu" "In15.Cu")
		(hatch none 0.5)
		(connect_pads
			(clearance 0)
		)
		(min_thickness 0.25)
		(keepout
			(tracks not_allowed)
			(vias allowed)
			(pads allowed)
			(copperpour not_allowed)
			(footprints allowed)
		)
		(placement
			(enabled no)
			(sheetname "")
		)
		(fill yes
			(thermal_gap 0.5)
			(thermal_bridge_width 0.5)
			(island_removal_mode 0)
		)
		(polygon
			(pts
				(arc
					(start 207.397604 -313.766708)
					(mid 206.744824 -313.766708)
					(end 207.397604 -313.766708)
				)
			)
		)
	)
	(zone
		(layers "B.Cu" "In11.Cu" "In13.Cu" "In15.Cu")
		(hatch none 0.5)
		(connect_pads
			(clearance 0)
		)
		(min_thickness 0.25)
		(keepout
			(tracks not_allowed)
			(vias allowed)
			(pads allowed)
			(copperpour not_allowed)
			(footprints allowed)
		)
		(placement
			(enabled no)
			(sheetname "")
		)
		(fill yes
			(thermal_gap 0.5)
			(thermal_bridge_width 0.5)
			(island_removal_mode 0)
		)
		(polygon
			(pts
				(arc
					(start 383.17424 -410.030168)
					(mid 382.47066 -410.030168)
					(end 383.17424 -410.030168)
				)
			)
		)
	)
	(zone
		(layers "B.Cu" "In11.Cu" "In13.Cu" "In15.Cu")
		(hatch none 0.5)
		(connect_pads
			(clearance 0)
		)
		(min_thickness 0.25)
		(keepout
			(tracks not_allowed)
			(vias allowed)
			(pads allowed)
			(copperpour not_allowed)
			(footprints allowed)
		)
		(placement
			(enabled no)
			(sheetname "")
		)
		(fill yes
			(thermal_gap 0.5)
			(thermal_bridge_width 0.5)
			(island_removal_mode 0)
		)
		(polygon
			(pts
				(arc
					(start 455.337672 -208.366614)
					(mid 454.684892 -208.366614)
					(end 455.337672 -208.366614)
				)
			)
		)
	)
	(zone
		(layers "B.Cu" "In11.Cu" "In13.Cu" "In15.Cu")
		(hatch none 0.5)
		(connect_pads
			(clearance 0)
		)
		(min_thickness 0.25)
		(keepout
			(tracks not_allowed)
			(vias allowed)
			(pads allowed)
			(copperpour not_allowed)
			(footprints allowed)
		)
		(placement
			(enabled no)
			(sheetname "")
		)
		(fill yes
			(thermal_gap 0.5)
			(thermal_bridge_width 0.5)
			(island_removal_mode 0)
		)
		(polygon
			(pts
				(arc
					(start 128.413002 -236.597952)
					(mid 127.760222 -236.597952)
					(end 128.413002 -236.597952)
				)
			)
		)
	)
	(zone
		(layers "B.Cu" "In11.Cu" "In13.Cu" "In15.Cu")
		(hatch none 0.5)
		(connect_pads
			(clearance 0)
		)
		(min_thickness 0.25)
		(keepout
			(tracks not_allowed)
			(vias allowed)
			(pads allowed)
			(copperpour not_allowed)
			(footprints allowed)
		)
		(placement
			(enabled no)
			(sheetname "")
		)
		(fill yes
			(thermal_gap 0.5)
			(thermal_bridge_width 0.5)
			(island_removal_mode 0)
		)
		(polygon
			(pts
				(arc
					(start 95.629984 -261.244842)
					(mid 94.977204 -261.244842)
					(end 95.629984 -261.244842)
				)
			)
		)
	)
	(zone
		(layers "B.Cu" "In11.Cu" "In13.Cu" "In15.Cu")
		(hatch none 0.5)
		(connect_pads
			(clearance 0)
		)
		(min_thickness 0.25)
		(keepout
			(tracks not_allowed)
			(vias allowed)
			(pads allowed)
			(copperpour not_allowed)
			(footprints allowed)
		)
		(placement
			(enabled no)
			(sheetname "")
		)
		(fill yes
			(thermal_gap 0.5)
			(thermal_bridge_width 0.5)
			(island_removal_mode 0)
		)
		(polygon
			(pts
				(arc
					(start 128.413002 -239.853216)
					(mid 127.760222 -239.853216)
					(end 128.413002 -239.853216)
				)
			)
		)
	)
	(zone
		(layers "B.Cu" "In11.Cu" "In13.Cu" "In15.Cu")
		(hatch none 0.5)
		(connect_pads
			(clearance 0)
		)
		(min_thickness 0.25)
		(keepout
			(tracks not_allowed)
			(vias allowed)
			(pads allowed)
			(copperpour not_allowed)
			(footprints allowed)
		)
		(placement
			(enabled no)
			(sheetname "")
		)
		(fill yes
			(thermal_gap 0.5)
			(thermal_bridge_width 0.5)
			(island_removal_mode 0)
		)
		(polygon
			(pts
				(arc
					(start 132.15493 -439.0898)
					(mid 131.345178 -439.0898)
					(end 132.15493 -439.0898)
				)
			)
		)
	)
	(zone
		(layers "B.Cu" "In11.Cu" "In13.Cu" "In15.Cu")
		(hatch none 0.5)
		(connect_pads
			(clearance 0)
		)
		(min_thickness 0.25)
		(keepout
			(tracks not_allowed)
			(vias allowed)
			(pads allowed)
			(copperpour not_allowed)
			(footprints allowed)
		)
		(placement
			(enabled no)
			(sheetname "")
		)
		(fill yes
			(thermal_gap 0.5)
			(thermal_bridge_width 0.5)
			(island_removal_mode 0)
		)
		(polygon
			(pts
				(arc
					(start 229.54869 -52.906676)
					(mid 228.84511 -52.906676)
					(end 229.54869 -52.906676)
				)
			)
		)
	)
	(zone
		(layers "B.Cu" "In11.Cu" "In13.Cu" "In15.Cu")
		(hatch none 0.5)
		(connect_pads
			(clearance 0)
		)
		(min_thickness 0.25)
		(keepout
			(tracks not_allowed)
			(vias allowed)
			(pads allowed)
			(copperpour not_allowed)
			(footprints allowed)
		)
		(placement
			(enabled no)
			(sheetname "")
		)
		(fill yes
			(thermal_gap 0.5)
			(thermal_bridge_width 0.5)
			(island_removal_mode 0)
		)
		(polygon
			(pts
				(arc
					(start 321.054984 -435.489858)
					(mid 320.245232 -435.489858)
					(end 321.054984 -435.489858)
				)
			)
		)
	)
	(zone
		(layers "B.Cu" "In11.Cu" "In13.Cu" "In15.Cu")
		(hatch none 0.5)
		(connect_pads
			(clearance 0)
		)
		(min_thickness 0.25)
		(keepout
			(tracks not_allowed)
			(vias allowed)
			(pads allowed)
			(copperpour not_allowed)
			(footprints allowed)
		)
		(placement
			(enabled no)
			(sheetname "")
		)
		(fill yes
			(thermal_gap 0.5)
			(thermal_bridge_width 0.5)
			(island_removal_mode 0)
		)
		(polygon
			(pts
				(arc
					(start 352.028252 -280.778204)
					(mid 351.375472 -280.778204)
					(end 352.028252 -280.778204)
				)
			)
		)
	)
	(zone
		(layers "B.Cu" "In11.Cu" "In13.Cu" "In15.Cu")
		(hatch none 0.5)
		(connect_pads
			(clearance 0)
		)
		(min_thickness 0.25)
		(keepout
			(tracks not_allowed)
			(vias allowed)
			(pads allowed)
			(copperpour not_allowed)
			(footprints allowed)
		)
		(placement
			(enabled no)
			(sheetname "")
		)
		(fill yes
			(thermal_gap 0.5)
			(thermal_bridge_width 0.5)
			(island_removal_mode 0)
		)
		(polygon
			(pts
				(arc
					(start 321.054984 -427.089824)
					(mid 320.245232 -427.089824)
					(end 321.054984 -427.089824)
				)
			)
		)
	)
	(zone
		(layers "B.Cu" "In11.Cu" "In13.Cu" "In15.Cu")
		(hatch none 0.5)
		(connect_pads
			(clearance 0)
		)
		(min_thickness 0.25)
		(keepout
			(tracks not_allowed)
			(vias allowed)
			(pads allowed)
			(copperpour not_allowed)
			(footprints allowed)
		)
		(placement
			(enabled no)
			(sheetname "")
		)
		(fill yes
			(thermal_gap 0.5)
			(thermal_bridge_width 0.5)
			(island_removal_mode 0)
		)
		(polygon
			(pts
				(arc
					(start 396.15491 -437.889904)
					(mid 395.345158 -437.889904)
					(end 396.15491 -437.889904)
				)
			)
		)
	)
	(zone
		(layers "B.Cu" "In11.Cu" "In13.Cu" "In15.Cu")
		(hatch none 0.5)
		(connect_pads
			(clearance 0)
		)
		(min_thickness 0.25)
		(keepout
			(tracks not_allowed)
			(vias allowed)
			(pads allowed)
			(copperpour not_allowed)
			(footprints allowed)
		)
		(placement
			(enabled no)
			(sheetname "")
		)
		(fill yes
			(thermal_gap 0.5)
			(thermal_bridge_width 0.5)
			(island_removal_mode 0)
		)
		(polygon
			(pts
				(arc
					(start 343.930224 -230.900478)
					(mid 343.277444 -230.900478)
					(end 343.930224 -230.900478)
				)
			)
		)
	)
	(zone
		(layers "B.Cu" "In11.Cu" "In13.Cu" "In15.Cu")
		(hatch none 0.5)
		(connect_pads
			(clearance 0)
		)
		(min_thickness 0.25)
		(keepout
			(tracks not_allowed)
			(vias allowed)
			(pads allowed)
			(copperpour not_allowed)
			(footprints allowed)
		)
		(placement
			(enabled no)
			(sheetname "")
		)
		(fill yes
			(thermal_gap 0.5)
			(thermal_bridge_width 0.5)
			(island_removal_mode 0)
		)
		(polygon
			(pts
				(arc
					(start 280.143204 -228.766624)
					(mid 279.490424 -228.766624)
					(end 280.143204 -228.766624)
				)
			)
		)
	)
	(zone
		(layers "B.Cu" "In11.Cu" "In13.Cu" "In15.Cu")
		(hatch none 0.5)
		(connect_pads
			(clearance 0)
		)
		(min_thickness 0.25)
		(keepout
			(tracks not_allowed)
			(vias allowed)
			(pads allowed)
			(copperpour not_allowed)
			(footprints allowed)
		)
		(placement
			(enabled no)
			(sheetname "")
		)
		(fill yes
			(thermal_gap 0.5)
			(thermal_bridge_width 0.5)
			(island_removal_mode 0)
		)
		(polygon
			(pts
				(arc
					(start 377.402852 -267.755878)
					(mid 376.750072 -267.755878)
					(end 377.402852 -267.755878)
				)
			)
		)
	)
	(zone
		(layers "B.Cu" "In11.Cu" "In13.Cu" "In15.Cu")
		(hatch none 0.5)
		(connect_pads
			(clearance 0)
		)
		(min_thickness 0.25)
		(keepout
			(tracks not_allowed)
			(vias allowed)
			(pads allowed)
			(copperpour not_allowed)
			(footprints allowed)
		)
		(placement
			(enabled no)
			(sheetname "")
		)
		(fill yes
			(thermal_gap 0.5)
			(thermal_bridge_width 0.5)
			(island_removal_mode 0)
		)
		(polygon
			(pts
				(arc
					(start 62.378336 -244.066568)
					(mid 61.725556 -244.066568)
					(end 62.378336 -244.066568)
				)
			)
		)
	)
	(zone
		(layers "B.Cu" "In11.Cu" "In13.Cu" "In15.Cu")
		(hatch none 0.5)
		(connect_pads
			(clearance 0)
		)
		(min_thickness 0.25)
		(keepout
			(tracks not_allowed)
			(vias allowed)
			(pads allowed)
			(copperpour not_allowed)
			(footprints allowed)
		)
		(placement
			(enabled no)
			(sheetname "")
		)
		(fill yes
			(thermal_gap 0.5)
			(thermal_bridge_width 0.5)
			(island_removal_mode 0)
		)
		(polygon
			(pts
				(arc
					(start 96.569784 -282.405836)
					(mid 95.917004 -282.405836)
					(end 96.569784 -282.405836)
				)
			)
		)
	)
	(zone
		(layers "B.Cu" "In11.Cu" "In13.Cu" "In15.Cu")
		(hatch none 0.5)
		(connect_pads
			(clearance 0)
		)
		(min_thickness 0.25)
		(keepout
			(tracks not_allowed)
			(vias allowed)
			(pads allowed)
			(copperpour not_allowed)
			(footprints allowed)
		)
		(placement
			(enabled no)
			(sheetname "")
		)
		(fill yes
			(thermal_gap 0.5)
			(thermal_bridge_width 0.5)
			(island_removal_mode 0)
		)
		(polygon
			(pts
				(arc
					(start 61.054996 -434.289962)
					(mid 60.245244 -434.289962)
					(end 61.054996 -434.289962)
				)
			)
		)
	)
	(zone
		(layers "B.Cu" "In11.Cu" "In13.Cu" "In15.Cu")
		(hatch none 0.5)
		(connect_pads
			(clearance 0)
		)
		(min_thickness 0.25)
		(keepout
			(tracks not_allowed)
			(vias allowed)
			(pads allowed)
			(copperpour not_allowed)
			(footprints allowed)
		)
		(placement
			(enabled no)
			(sheetname "")
		)
		(fill yes
			(thermal_gap 0.5)
			(thermal_bridge_width 0.5)
			(island_removal_mode 0)
		)
		(polygon
			(pts
				(arc
					(start 436.150004 -200.716642)
					(mid 435.497224 -200.716642)
					(end 436.150004 -200.716642)
				)
			)
		)
	)
	(zone
		(layers "B.Cu" "In11.Cu" "In13.Cu" "In15.Cu")
		(hatch none 0.5)
		(connect_pads
			(clearance 0)
		)
		(min_thickness 0.25)
		(keepout
			(tracks not_allowed)
			(vias allowed)
			(pads allowed)
			(copperpour not_allowed)
			(footprints allowed)
		)
		(placement
			(enabled no)
			(sheetname "")
		)
		(fill yes
			(thermal_gap 0.5)
			(thermal_bridge_width 0.5)
			(island_removal_mode 0)
		)
		(polygon
			(pts
				(arc
					(start 344.400124 -213.732618)
					(mid 343.747344 -213.732618)
					(end 344.400124 -213.732618)
				)
			)
		)
	)
	(zone
		(layers "B.Cu" "In11.Cu" "In13.Cu" "In15.Cu")
		(hatch none 0.5)
		(connect_pads
			(clearance 0)
		)
		(min_thickness 0.25)
		(keepout
			(tracks not_allowed)
			(vias allowed)
			(pads allowed)
			(copperpour not_allowed)
			(footprints allowed)
		)
		(placement
			(enabled no)
			(sheetname "")
		)
		(fill yes
			(thermal_gap 0.5)
			(thermal_bridge_width 0.5)
			(island_removal_mode 0)
		)
		(polygon
			(pts
				(arc
					(start 131.042664 -410.030168)
					(mid 130.339084 -410.030168)
					(end 131.042664 -410.030168)
				)
			)
		)
	)
	(zone
		(layers "B.Cu" "In11.Cu" "In13.Cu" "In15.Cu")
		(hatch none 0.5)
		(connect_pads
			(clearance 0)
		)
		(min_thickness 0.25)
		(keepout
			(tracks not_allowed)
			(vias allowed)
			(pads allowed)
			(copperpour not_allowed)
			(footprints allowed)
		)
		(placement
			(enabled no)
			(sheetname "")
		)
		(fill yes
			(thermal_gap 0.5)
			(thermal_bridge_width 0.5)
			(island_removal_mode 0)
		)
		(polygon
			(pts
				(arc
					(start 436.150004 -305.266598)
					(mid 435.497224 -305.266598)
					(end 436.150004 -305.266598)
				)
			)
		)
	)
	(zone
		(layers "B.Cu" "In11.Cu" "In13.Cu" "In15.Cu")
		(hatch none 0.5)
		(connect_pads
			(clearance 0)
		)
		(min_thickness 0.25)
		(keepout
			(tracks not_allowed)
			(vias allowed)
			(pads allowed)
			(copperpour not_allowed)
			(footprints allowed)
		)
		(placement
			(enabled no)
			(sheetname "")
		)
		(fill yes
			(thermal_gap 0.5)
			(thermal_bridge_width 0.5)
			(island_removal_mode 0)
		)
		(polygon
			(pts
				(arc
					(start 96.929956 -245.55069)
					(mid 96.277176 -245.55069)
					(end 96.929956 -245.55069)
				)
			)
		)
	)
	(zone
		(layers "B.Cu" "In11.Cu" "In13.Cu" "In15.Cu")
		(hatch none 0.5)
		(connect_pads
			(clearance 0)
		)
		(min_thickness 0.25)
		(keepout
			(tracks not_allowed)
			(vias allowed)
			(pads allowed)
			(copperpour not_allowed)
			(footprints allowed)
		)
		(placement
			(enabled no)
			(sheetname "")
		)
		(fill yes
			(thermal_gap 0.5)
			(thermal_bridge_width 0.5)
			(island_removal_mode 0)
		)
		(polygon
			(pts
				(arc
					(start 125.123956 -248.806208)
					(mid 124.471176 -248.806208)
					(end 125.123956 -248.806208)
				)
			)
		)
	)
	(zone
		(layers "B.Cu" "In11.Cu" "In13.Cu" "In15.Cu")
		(hatch none 0.5)
		(connect_pads
			(clearance 0)
		)
		(min_thickness 0.25)
		(keepout
			(tracks not_allowed)
			(vias allowed)
			(pads allowed)
			(copperpour not_allowed)
			(footprints allowed)
		)
		(placement
			(enabled no)
			(sheetname "")
		)
		(fill yes
			(thermal_gap 0.5)
			(thermal_bridge_width 0.5)
			(island_removal_mode 0)
		)
		(polygon
			(pts
				(arc
					(start 440.250072 -223.666558)
					(mid 439.597292 -223.666558)
					(end 440.250072 -223.666558)
				)
			)
		)
	)
	(zone
		(layers "B.Cu" "In11.Cu" "In13.Cu" "In15.Cu")
		(hatch none 0.5)
		(connect_pads
			(clearance 0)
		)
		(min_thickness 0.25)
		(keepout
			(tracks not_allowed)
			(vias allowed)
			(pads allowed)
			(copperpour not_allowed)
			(footprints allowed)
		)
		(placement
			(enabled no)
			(sheetname "")
		)
		(fill yes
			(thermal_gap 0.5)
			(thermal_bridge_width 0.5)
			(island_removal_mode 0)
		)
		(polygon
			(pts
				(arc
					(start 440.208162 -301.866808)
					(mid 439.555382 -301.866808)
					(end 440.208162 -301.866808)
				)
			)
		)
	)
	(zone
		(layers "B.Cu" "In11.Cu" "In13.Cu" "In15.Cu")
		(hatch none 0.5)
		(connect_pads
			(clearance 0)
		)
		(min_thickness 0.25)
		(keepout
			(tracks not_allowed)
			(vias allowed)
			(pads allowed)
			(copperpour not_allowed)
			(footprints allowed)
		)
		(placement
			(enabled no)
			(sheetname "")
		)
		(fill yes
			(thermal_gap 0.5)
			(thermal_bridge_width 0.5)
			(island_removal_mode 0)
		)
		(polygon
			(pts
				(arc
					(start 280.143204 -232.166668)
					(mid 279.490424 -232.166668)
					(end 280.143204 -232.166668)
				)
			)
		)
	)
	(zone
		(layers "B.Cu" "In11.Cu" "In13.Cu" "In15.Cu")
		(hatch none 0.5)
		(connect_pads
			(clearance 0)
		)
		(min_thickness 0.25)
		(keepout
			(tracks not_allowed)
			(vias allowed)
			(pads allowed)
			(copperpour not_allowed)
			(footprints allowed)
		)
		(placement
			(enabled no)
			(sheetname "")
		)
		(fill yes
			(thermal_gap 0.5)
			(thermal_bridge_width 0.5)
			(island_removal_mode 0)
		)
		(polygon
			(pts
				(arc
					(start 280.143204 -275.516594)
					(mid 279.490424 -275.516594)
					(end 280.143204 -275.516594)
				)
			)
		)
	)
	(zone
		(layers "B.Cu" "In11.Cu" "In13.Cu" "In15.Cu")
		(hatch none 0.5)
		(connect_pads
			(clearance 0)
		)
		(min_thickness 0.25)
		(keepout
			(tracks not_allowed)
			(vias allowed)
			(pads allowed)
			(copperpour not_allowed)
			(footprints allowed)
		)
		(placement
			(enabled no)
			(sheetname "")
		)
		(fill yes
			(thermal_gap 0.5)
			(thermal_bridge_width 0.5)
			(island_removal_mode 0)
		)
		(polygon
			(pts
				(arc
					(start 325.054976 -428.28972)
					(mid 324.245224 -428.28972)
					(end 325.054976 -428.28972)
				)
			)
		)
	)
	(zone
		(layers "B.Cu" "In11.Cu" "In13.Cu" "In15.Cu")
		(hatch none 0.5)
		(connect_pads
			(clearance 0)
		)
		(min_thickness 0.25)
		(keepout
			(tracks not_allowed)
			(vias allowed)
			(pads allowed)
			(copperpour not_allowed)
			(footprints allowed)
		)
		(placement
			(enabled no)
			(sheetname "")
		)
		(fill yes
			(thermal_gap 0.5)
			(thermal_bridge_width 0.5)
			(island_removal_mode 0)
		)
		(polygon
			(pts
				(arc
					(start 97.509584 -261.244842)
					(mid 96.856804 -261.244842)
					(end 97.509584 -261.244842)
				)
			)
		)
	)
	(zone
		(layers "B.Cu" "In11.Cu" "In13.Cu" "In15.Cu")
		(hatch none 0.5)
		(connect_pads
			(clearance 0)
		)
		(min_thickness 0.25)
		(keepout
			(tracks not_allowed)
			(vias allowed)
			(pads allowed)
			(copperpour not_allowed)
			(footprints allowed)
		)
		(placement
			(enabled no)
			(sheetname "")
		)
		(fill yes
			(thermal_gap 0.5)
			(thermal_bridge_width 0.5)
			(island_removal_mode 0)
		)
		(polygon
			(pts
				(arc
					(start 345.809824 -237.411514)
					(mid 345.157044 -237.411514)
					(end 345.809824 -237.411514)
				)
			)
		)
	)
	(zone
		(layers "B.Cu" "In11.Cu" "In13.Cu" "In15.Cu")
		(hatch none 0.5)
		(connect_pads
			(clearance 0)
		)
		(min_thickness 0.25)
		(keepout
			(tracks not_allowed)
			(vias allowed)
			(pads allowed)
			(copperpour not_allowed)
			(footprints allowed)
		)
		(placement
			(enabled no)
			(sheetname "")
		)
		(fill yes
			(thermal_gap 0.5)
			(thermal_bridge_width 0.5)
			(island_removal_mode 0)
		)
		(polygon
			(pts
				(arc
					(start 355.445314 -50.207672)
					(mid 354.741734 -50.207672)
					(end 355.445314 -50.207672)
				)
			)
		)
	)
	(zone
		(layers "B.Cu" "In11.Cu" "In13.Cu" "In15.Cu")
		(hatch none 0.5)
		(connect_pads
			(clearance 0)
		)
		(min_thickness 0.25)
		(keepout
			(tracks not_allowed)
			(vias allowed)
			(pads allowed)
			(copperpour not_allowed)
			(footprints allowed)
		)
		(placement
			(enabled no)
			(sheetname "")
		)
		(fill yes
			(thermal_gap 0.5)
			(thermal_bridge_width 0.5)
			(island_removal_mode 0)
		)
		(polygon
			(pts
				(arc
					(start 396.15491 -431.889916)
					(mid 395.345158 -431.889916)
					(end 396.15491 -431.889916)
				)
			)
		)
	)
	(zone
		(layers "B.Cu" "In11.Cu" "In13.Cu" "In15.Cu")
		(hatch none 0.5)
		(connect_pads
			(clearance 0)
		)
		(min_thickness 0.25)
		(keepout
			(tracks not_allowed)
			(vias allowed)
			(pads allowed)
			(copperpour not_allowed)
			(footprints allowed)
		)
		(placement
			(enabled no)
			(sheetname "")
		)
		(fill yes
			(thermal_gap 0.5)
			(thermal_bridge_width 0.5)
			(island_removal_mode 0)
		)
		(polygon
			(pts
				(arc
					(start 95.629984 -266.128246)
					(mid 94.977204 -266.128246)
					(end 95.629984 -266.128246)
				)
			)
		)
	)
	(zone
		(layers "B.Cu" "In11.Cu" "In13.Cu" "In15.Cu")
		(hatch none 0.5)
		(connect_pads
			(clearance 0)
		)
		(min_thickness 0.25)
		(keepout
			(tracks not_allowed)
			(vias allowed)
			(pads allowed)
			(copperpour not_allowed)
			(footprints allowed)
		)
		(placement
			(enabled no)
			(sheetname "")
		)
		(fill yes
			(thermal_gap 0.5)
			(thermal_bridge_width 0.5)
			(island_removal_mode 0)
		)
		(polygon
			(pts
				(arc
					(start 376.35307 -243.108988)
					(mid 375.70029 -243.108988)
					(end 376.35307 -243.108988)
				)
			)
		)
	)
	(zone
		(layers "B.Cu" "In11.Cu" "In13.Cu" "In15.Cu")
		(hatch none 0.5)
		(connect_pads
			(clearance 0)
		)
		(min_thickness 0.25)
		(keepout
			(tracks not_allowed)
			(vias allowed)
			(pads allowed)
			(copperpour not_allowed)
			(footprints allowed)
		)
		(placement
			(enabled no)
			(sheetname "")
		)
		(fill yes
			(thermal_gap 0.5)
			(thermal_bridge_width 0.5)
			(island_removal_mode 0)
		)
		(polygon
			(pts
				(arc
					(start 127.583184 -277.522432)
					(mid 126.930404 -277.522432)
					(end 127.583184 -277.522432)
				)
			)
		)
	)
	(zone
		(layers "B.Cu" "In11.Cu" "In13.Cu" "In15.Cu")
		(hatch none 0.5)
		(connect_pads
			(clearance 0)
		)
		(min_thickness 0.25)
		(keepout
			(tracks not_allowed)
			(vias allowed)
			(pads allowed)
			(copperpour not_allowed)
			(footprints allowed)
		)
		(placement
			(enabled no)
			(sheetname "")
		)
		(fill yes
			(thermal_gap 0.5)
			(thermal_bridge_width 0.5)
			(island_removal_mode 0)
		)
		(polygon
			(pts
				(arc
					(start 138.280902 -219.506038)
					(mid 137.628122 -219.506038)
					(end 138.280902 -219.506038)
				)
			)
		)
	)
	(zone
		(layers "B.Cu" "In11.Cu" "In13.Cu" "In15.Cu")
		(hatch none 0.5)
		(connect_pads
			(clearance 0)
		)
		(min_thickness 0.25)
		(keepout
			(tracks not_allowed)
			(vias allowed)
			(pads allowed)
			(copperpour not_allowed)
			(footprints allowed)
		)
		(placement
			(enabled no)
			(sheetname "")
		)
		(fill yes
			(thermal_gap 0.5)
			(thermal_bridge_width 0.5)
			(island_removal_mode 0)
		)
		(polygon
			(pts
				(arc
					(start 379.2474 -410.030168)
					(mid 378.54382 -410.030168)
					(end 379.2474 -410.030168)
				)
			)
		)
	)
	(zone
		(layers "B.Cu" "In11.Cu" "In13.Cu" "In15.Cu")
		(hatch none 0.5)
		(connect_pads
			(clearance 0)
		)
		(min_thickness 0.25)
		(keepout
			(tracks not_allowed)
			(vias allowed)
			(pads allowed)
			(copperpour not_allowed)
			(footprints allowed)
		)
		(placement
			(enabled no)
			(sheetname "")
		)
		(fill yes
			(thermal_gap 0.5)
			(thermal_bridge_width 0.5)
			(island_removal_mode 0)
		)
		(polygon
			(pts
				(arc
					(start 344.054938 -427.289976)
					(mid 343.245186 -427.289976)
					(end 344.054938 -427.289976)
				)
			)
		)
	)
	(zone
		(layers "B.Cu" "In11.Cu" "In13.Cu" "In15.Cu")
		(hatch none 0.5)
		(connect_pads
			(clearance 0)
		)
		(min_thickness 0.25)
		(keepout
			(tracks not_allowed)
			(vias allowed)
			(pads allowed)
			(copperpour not_allowed)
			(footprints allowed)
		)
		(placement
			(enabled no)
			(sheetname "")
		)
		(fill yes
			(thermal_gap 0.5)
			(thermal_bridge_width 0.5)
			(island_removal_mode 0)
		)
		(polygon
			(pts
				(arc
					(start 17.115536 -210.066636)
					(mid 16.462756 -210.066636)
					(end 17.115536 -210.066636)
				)
			)
		)
	)
	(zone
		(layers "B.Cu" "In11.Cu" "In13.Cu" "In15.Cu")
		(hatch none 0.5)
		(connect_pads
			(clearance 0)
		)
		(min_thickness 0.25)
		(keepout
			(tracks not_allowed)
			(vias allowed)
			(pads allowed)
			(copperpour not_allowed)
			(footprints allowed)
		)
		(placement
			(enabled no)
			(sheetname "")
		)
		(fill yes
			(thermal_gap 0.5)
			(thermal_bridge_width 0.5)
			(island_removal_mode 0)
		)
		(polygon
			(pts
				(arc
					(start 192.310004 -276.366732)
					(mid 191.657224 -276.366732)
					(end 192.310004 -276.366732)
				)
			)
		)
	)
	(zone
		(layers "B.Cu" "In11.Cu" "In13.Cu" "In15.Cu")
		(hatch none 0.5)
		(connect_pads
			(clearance 0)
		)
		(min_thickness 0.25)
		(keepout
			(tracks not_allowed)
			(vias allowed)
			(pads allowed)
			(copperpour not_allowed)
			(footprints allowed)
		)
		(placement
			(enabled no)
			(sheetname "")
		)
		(fill yes
			(thermal_gap 0.5)
			(thermal_bridge_width 0.5)
			(island_removal_mode 0)
		)
		(polygon
			(pts
				(arc
					(start 99.389184 -254.733552)
					(mid 98.736404 -254.733552)
					(end 99.389184 -254.733552)
				)
			)
		)
	)
	(zone
		(layers "B.Cu" "In11.Cu" "In13.Cu" "In15.Cu")
		(hatch none 0.5)
		(connect_pads
			(clearance 0)
		)
		(min_thickness 0.25)
		(keepout
			(tracks not_allowed)
			(vias allowed)
			(pads allowed)
			(copperpour not_allowed)
			(footprints allowed)
		)
		(placement
			(enabled no)
			(sheetname "")
		)
		(fill yes
			(thermal_gap 0.5)
			(thermal_bridge_width 0.5)
			(island_removal_mode 0)
		)
		(polygon
			(pts
				(arc
					(start 207.397604 -209.216752)
					(mid 206.744824 -209.216752)
					(end 207.397604 -209.216752)
				)
			)
		)
	)
	(zone
		(layers "B.Cu" "In11.Cu" "In13.Cu" "In15.Cu")
		(hatch none 0.5)
		(connect_pads
			(clearance 0)
		)
		(min_thickness 0.25)
		(keepout
			(tracks not_allowed)
			(vias allowed)
			(pads allowed)
			(copperpour not_allowed)
			(footprints allowed)
		)
		(placement
			(enabled no)
			(sheetname "")
		)
		(fill yes
			(thermal_gap 0.5)
			(thermal_bridge_width 0.5)
			(island_removal_mode 0)
		)
		(polygon
			(pts
				(arc
					(start 265.055604 -312.91657)
					(mid 264.402824 -312.91657)
					(end 265.055604 -312.91657)
				)
			)
		)
	)
	(zone
		(layers "B.Cu" "In11.Cu" "In13.Cu" "In15.Cu")
		(hatch none 0.5)
		(connect_pads
			(clearance 0)
		)
		(min_thickness 0.25)
		(keepout
			(tracks not_allowed)
			(vias allowed)
			(pads allowed)
			(copperpour not_allowed)
			(footprints allowed)
		)
		(placement
			(enabled no)
			(sheetname "")
		)
		(fill yes
			(thermal_gap 0.5)
			(thermal_bridge_width 0.5)
			(island_removal_mode 0)
		)
		(polygon
			(pts
				(arc
					(start 337.82127 -215.436704)
					(mid 337.16849 -215.436704)
					(end 337.82127 -215.436704)
				)
			)
		)
	)
	(zone
		(layers "B.Cu" "In11.Cu" "In13.Cu" "In15.Cu")
		(hatch none 0.5)
		(connect_pads
			(clearance 0)
		)
		(min_thickness 0.25)
		(keepout
			(tracks not_allowed)
			(vias allowed)
			(pads allowed)
			(copperpour not_allowed)
			(footprints allowed)
		)
		(placement
			(enabled no)
			(sheetname "")
		)
		(fill yes
			(thermal_gap 0.5)
			(thermal_bridge_width 0.5)
			(island_removal_mode 0)
		)
		(polygon
			(pts
				(arc
					(start 134.161784 -254.733552)
					(mid 133.509004 -254.733552)
					(end 134.161784 -254.733552)
				)
			)
		)
	)
	(zone
		(layers "B.Cu" "In11.Cu" "In13.Cu" "In15.Cu")
		(hatch none 0.5)
		(connect_pads
			(clearance 0)
		)
		(min_thickness 0.25)
		(keepout
			(tracks not_allowed)
			(vias allowed)
			(pads allowed)
			(copperpour not_allowed)
			(footprints allowed)
		)
		(placement
			(enabled no)
			(sheetname "")
		)
		(fill yes
			(thermal_gap 0.5)
			(thermal_bridge_width 0.5)
			(island_removal_mode 0)
		)
		(polygon
			(pts
				(arc
					(start 157.15488 -431.889916)
					(mid 156.345128 -431.889916)
					(end 157.15488 -431.889916)
				)
			)
		)
	)
	(zone
		(layers "B.Cu" "In11.Cu" "In13.Cu" "In15.Cu")
		(hatch none 0.5)
		(connect_pads
			(clearance 0)
		)
		(min_thickness 0.25)
		(keepout
			(tracks not_allowed)
			(vias allowed)
			(pads allowed)
			(copperpour not_allowed)
			(footprints allowed)
		)
		(placement
			(enabled no)
			(sheetname "")
		)
		(fill yes
			(thermal_gap 0.5)
			(thermal_bridge_width 0.5)
			(island_removal_mode 0)
		)
		(polygon
			(pts
				(arc
					(start 403.154896 -429.689768)
					(mid 402.345144 -429.689768)
					(end 403.154896 -429.689768)
				)
			)
		)
	)
	(zone
		(layers "B.Cu" "In11.Cu" "In13.Cu" "In15.Cu")
		(hatch none 0.5)
		(connect_pads
			(clearance 0)
		)
		(min_thickness 0.25)
		(keepout
			(tracks not_allowed)
			(vias allowed)
			(pads allowed)
			(copperpour not_allowed)
			(footprints allowed)
		)
		(placement
			(enabled no)
			(sheetname "")
		)
		(fill yes
			(thermal_gap 0.5)
			(thermal_bridge_width 0.5)
			(island_removal_mode 0)
		)
		(polygon
			(pts
				(arc
					(start 384.341624 -217.878406)
					(mid 383.688844 -217.878406)
					(end 384.341624 -217.878406)
				)
			)
		)
	)
	(zone
		(layers "B.Cu" "In11.Cu" "In13.Cu" "In15.Cu")
		(hatch none 0.5)
		(connect_pads
			(clearance 0)
		)
		(min_thickness 0.25)
		(keepout
			(tracks not_allowed)
			(vias allowed)
			(pads allowed)
			(copperpour not_allowed)
			(footprints allowed)
		)
		(placement
			(enabled no)
			(sheetname "")
		)
		(fill yes
			(thermal_gap 0.5)
			(thermal_bridge_width 0.5)
			(island_removal_mode 0)
		)
		(polygon
			(pts
				(arc
					(start 375.523252 -254.733552)
					(mid 374.870472 -254.733552)
					(end 375.523252 -254.733552)
				)
			)
		)
	)
	(zone
		(layers "B.Cu" "In11.Cu" "In13.Cu" "In15.Cu")
		(hatch none 0.5)
		(connect_pads
			(clearance 0)
		)
		(min_thickness 0.25)
		(keepout
			(tracks not_allowed)
			(vias allowed)
			(pads allowed)
			(copperpour not_allowed)
			(footprints allowed)
		)
		(placement
			(enabled no)
			(sheetname "")
		)
		(fill yes
			(thermal_gap 0.5)
			(thermal_bridge_width 0.5)
			(island_removal_mode 0)
		)
		(polygon
			(pts
				(arc
					(start 128.993138 -263.686544)
					(mid 128.340358 -263.686544)
					(end 128.993138 -263.686544)
				)
			)
		)
	)
	(zone
		(layers "B.Cu" "In11.Cu" "In13.Cu" "In15.Cu")
		(hatch none 0.5)
		(connect_pads
			(clearance 0)
		)
		(min_thickness 0.25)
		(keepout
			(tracks not_allowed)
			(vias allowed)
			(pads allowed)
			(copperpour not_allowed)
			(footprints allowed)
		)
		(placement
			(enabled no)
			(sheetname "")
		)
		(fill yes
			(thermal_gap 0.5)
			(thermal_bridge_width 0.5)
			(island_removal_mode 0)
		)
		(polygon
			(pts
				(arc
					(start 127.003556 -235.783882)
					(mid 126.350776 -235.783882)
					(end 127.003556 -235.783882)
				)
			)
		)
	)
	(zone
		(layers "B.Cu" "In11.Cu" "In13.Cu" "In15.Cu")
		(hatch none 0.5)
		(connect_pads
			(clearance 0)
		)
		(min_thickness 0.25)
		(keepout
			(tracks not_allowed)
			(vias allowed)
			(pads allowed)
			(copperpour not_allowed)
			(footprints allowed)
		)
		(placement
			(enabled no)
			(sheetname "")
		)
		(fill yes
			(thermal_gap 0.5)
			(thermal_bridge_width 0.5)
			(island_removal_mode 0)
		)
		(polygon
			(pts
				(arc
					(start 94.580202 -226.831144)
					(mid 93.927422 -226.831144)
					(end 94.580202 -226.831144)
				)
			)
		)
	)
	(zone
		(layers "B.Cu" "In11.Cu" "In13.Cu" "In15.Cu")
		(hatch none 0.5)
		(connect_pads
			(clearance 0)
		)
		(min_thickness 0.25)
		(keepout
			(tracks not_allowed)
			(vias allowed)
			(pads allowed)
			(copperpour not_allowed)
			(footprints allowed)
		)
		(placement
			(enabled no)
			(sheetname "")
		)
		(fill yes
			(thermal_gap 0.5)
			(thermal_bridge_width 0.5)
			(island_removal_mode 0)
		)
		(polygon
			(pts
				(arc
					(start 137.341356 -217.878406)
					(mid 136.688576 -217.878406)
					(end 137.341356 -217.878406)
				)
			)
		)
	)
	(zone
		(layers "B.Cu" "In11.Cu" "In13.Cu" "In15.Cu")
		(hatch none 0.5)
		(connect_pads
			(clearance 0)
		)
		(min_thickness 0.25)
		(keepout
			(tracks not_allowed)
			(vias allowed)
			(pads allowed)
			(copperpour not_allowed)
			(footprints allowed)
		)
		(placement
			(enabled no)
			(sheetname "")
		)
		(fill yes
			(thermal_gap 0.5)
			(thermal_bridge_width 0.5)
			(island_removal_mode 0)
		)
		(polygon
			(pts
				(arc
					(start 136.401556 -219.506038)
					(mid 135.748776 -219.506038)
					(end 136.401556 -219.506038)
				)
			)
		)
	)
	(zone
		(layers "B.Cu" "In11.Cu" "In13.Cu" "In15.Cu")
		(hatch none 0.5)
		(connect_pads
			(clearance 0)
		)
		(min_thickness 0.25)
		(keepout
			(tracks not_allowed)
			(vias allowed)
			(pads allowed)
			(copperpour not_allowed)
			(footprints allowed)
		)
		(placement
			(enabled no)
			(sheetname "")
		)
		(fill yes
			(thermal_gap 0.5)
			(thermal_bridge_width 0.5)
			(island_removal_mode 0)
		)
		(polygon
			(pts
				(arc
					(start 436.150004 -218.566746)
					(mid 435.497224 -218.566746)
					(end 436.150004 -218.566746)
				)
			)
		)
	)
	(zone
		(layers "B.Cu" "In11.Cu" "In13.Cu" "In15.Cu")
		(hatch none 0.5)
		(connect_pads
			(clearance 0)
		)
		(min_thickness 0.25)
		(keepout
			(tracks not_allowed)
			(vias allowed)
			(pads allowed)
			(copperpour not_allowed)
			(footprints allowed)
		)
		(placement
			(enabled no)
			(sheetname "")
		)
		(fill yes
			(thermal_gap 0.5)
			(thermal_bridge_width 0.5)
			(island_removal_mode 0)
		)
		(polygon
			(pts
				(arc
					(start 440.250072 -279.766776)
					(mid 439.597292 -279.766776)
					(end 440.250072 -279.766776)
				)
			)
		)
	)
	(zone
		(layers "B.Cu" "In11.Cu" "In13.Cu" "In15.Cu")
		(hatch none 0.5)
		(connect_pads
			(clearance 0)
		)
		(min_thickness 0.25)
		(keepout
			(tracks not_allowed)
			(vias allowed)
			(pads allowed)
			(copperpour not_allowed)
			(footprints allowed)
		)
		(placement
			(enabled no)
			(sheetname "")
		)
		(fill yes
			(thermal_gap 0.5)
			(thermal_bridge_width 0.5)
			(island_removal_mode 0)
		)
		(polygon
			(pts
				(arc
					(start 269.155672 -309.51678)
					(mid 268.502892 -309.51678)
					(end 269.155672 -309.51678)
				)
			)
		)
	)
	(zone
		(layers "B.Cu" "In11.Cu" "In13.Cu" "In15.Cu")
		(hatch none 0.5)
		(connect_pads
			(clearance 0)
		)
		(min_thickness 0.25)
		(keepout
			(tracks not_allowed)
			(vias allowed)
			(pads allowed)
			(copperpour not_allowed)
			(footprints allowed)
		)
		(placement
			(enabled no)
			(sheetname "")
		)
		(fill yes
			(thermal_gap 0.5)
			(thermal_bridge_width 0.5)
			(island_removal_mode 0)
		)
		(polygon
			(pts
				(arc
					(start 140.154914 -439.0898)
					(mid 139.345162 -439.0898)
					(end 140.154914 -439.0898)
				)
			)
		)
	)
	(zone
		(layers "B.Cu" "In11.Cu" "In13.Cu" "In15.Cu")
		(hatch none 0.5)
		(connect_pads
			(clearance 0)
		)
		(min_thickness 0.25)
		(keepout
			(tracks not_allowed)
			(vias allowed)
			(pads allowed)
			(copperpour not_allowed)
			(footprints allowed)
		)
		(placement
			(enabled no)
			(sheetname "")
		)
		(fill yes
			(thermal_gap 0.5)
			(thermal_bridge_width 0.5)
			(island_removal_mode 0)
		)
		(polygon
			(pts
				(arc
					(start 126.533402 -230.086662)
					(mid 125.880622 -230.086662)
					(end 126.533402 -230.086662)
				)
			)
		)
	)
	(zone
		(layers "B.Cu" "In11.Cu" "In13.Cu" "In15.Cu")
		(hatch none 0.5)
		(connect_pads
			(clearance 0)
		)
		(min_thickness 0.25)
		(keepout
			(tracks not_allowed)
			(vias allowed)
			(pads allowed)
			(copperpour not_allowed)
			(footprints allowed)
		)
		(placement
			(enabled no)
			(sheetname "")
		)
		(fill yes
			(thermal_gap 0.5)
			(thermal_bridge_width 0.5)
			(island_removal_mode 0)
		)
		(polygon
			(pts
				(arc
					(start 188.209936 -284.866588)
					(mid 187.557156 -284.866588)
					(end 188.209936 -284.866588)
				)
			)
		)
	)
	(zone
		(layers "B.Cu" "In11.Cu" "In13.Cu" "In15.Cu")
		(hatch none 0.5)
		(connect_pads
			(clearance 0)
		)
		(min_thickness 0.25)
		(keepout
			(tracks not_allowed)
			(vias allowed)
			(pads allowed)
			(copperpour not_allowed)
			(footprints allowed)
		)
		(placement
			(enabled no)
			(sheetname "")
		)
		(fill yes
			(thermal_gap 0.5)
			(thermal_bridge_width 0.5)
			(island_removal_mode 0)
		)
		(polygon
			(pts
				(arc
					(start 384.154934 -430.689766)
					(mid 383.345182 -430.689766)
					(end 384.154934 -430.689766)
				)
			)
		)
	)
	(zone
		(layers "B.Cu" "In11.Cu" "In13.Cu" "In15.Cu")
		(hatch none 0.5)
		(connect_pads
			(clearance 0)
		)
		(min_thickness 0.25)
		(keepout
			(tracks not_allowed)
			(vias allowed)
			(pads allowed)
			(copperpour not_allowed)
			(footprints allowed)
		)
		(placement
			(enabled no)
			(sheetname "")
		)
		(fill yes
			(thermal_gap 0.5)
			(thermal_bridge_width 0.5)
			(island_removal_mode 0)
		)
		(polygon
			(pts
				(arc
					(start 374.583452 -272.639282)
					(mid 373.930672 -272.639282)
					(end 374.583452 -272.639282)
				)
			)
		)
	)
	(zone
		(layers "B.Cu" "In11.Cu" "In13.Cu" "In15.Cu")
		(hatch none 0.5)
		(connect_pads
			(clearance 0)
		)
		(min_thickness 0.25)
		(keepout
			(tracks not_allowed)
			(vias allowed)
			(pads allowed)
			(copperpour not_allowed)
			(footprints allowed)
		)
		(placement
			(enabled no)
			(sheetname "")
		)
		(fill yes
			(thermal_gap 0.5)
			(thermal_bridge_width 0.5)
			(island_removal_mode 0)
		)
		(polygon
			(pts
				(arc
					(start 95.990156 -234.15625)
					(mid 95.337376 -234.15625)
					(end 95.990156 -234.15625)
				)
			)
		)
	)
	(zone
		(layers "B.Cu" "In11.Cu" "In13.Cu" "In15.Cu")
		(hatch none 0.5)
		(connect_pads
			(clearance 0)
		)
		(min_thickness 0.25)
		(keepout
			(tracks not_allowed)
			(vias allowed)
			(pads allowed)
			(copperpour not_allowed)
			(footprints allowed)
		)
		(placement
			(enabled no)
			(sheetname "")
		)
		(fill yes
			(thermal_gap 0.5)
			(thermal_bridge_width 0.5)
			(island_removal_mode 0)
		)
		(polygon
			(pts
				(arc
					(start 192.310004 -218.566746)
					(mid 191.657224 -218.566746)
					(end 192.310004 -218.566746)
				)
			)
		)
	)
	(zone
		(layers "B.Cu" "In11.Cu" "In13.Cu" "In15.Cu")
		(hatch none 0.5)
		(connect_pads
			(clearance 0)
		)
		(min_thickness 0.25)
		(keepout
			(tracks not_allowed)
			(vias allowed)
			(pads allowed)
			(copperpour not_allowed)
			(footprints allowed)
		)
		(placement
			(enabled no)
			(sheetname "")
		)
		(fill yes
			(thermal_gap 0.5)
			(thermal_bridge_width 0.5)
			(island_removal_mode 0)
		)
		(polygon
			(pts
				(arc
					(start 145.154904 -430.689766)
					(mid 144.345152 -430.689766)
					(end 145.154904 -430.689766)
				)
			)
		)
	)
	(zone
		(layers "B.Cu" "In11.Cu" "In13.Cu" "In15.Cu")
		(hatch none 0.5)
		(connect_pads
			(clearance 0)
		)
		(min_thickness 0.25)
		(keepout
			(tracks not_allowed)
			(vias allowed)
			(pads allowed)
			(copperpour not_allowed)
			(footprints allowed)
		)
		(placement
			(enabled no)
			(sheetname "")
		)
		(fill yes
			(thermal_gap 0.5)
			(thermal_bridge_width 0.5)
			(island_removal_mode 0)
		)
		(polygon
			(pts
				(arc
					(start 17.115536 -314.616592)
					(mid 16.462756 -314.616592)
					(end 17.115536 -314.616592)
				)
			)
		)
	)
	(zone
		(layers "B.Cu" "In11.Cu" "In13.Cu" "In15.Cu")
		(hatch none 0.5)
		(connect_pads
			(clearance 0)
		)
		(min_thickness 0.25)
		(keepout
			(tracks not_allowed)
			(vias allowed)
			(pads allowed)
			(copperpour not_allowed)
			(footprints allowed)
		)
		(placement
			(enabled no)
			(sheetname "")
		)
		(fill yes
			(thermal_gap 0.5)
			(thermal_bridge_width 0.5)
			(island_removal_mode 0)
		)
		(polygon
			(pts
				(arc
					(start 65.857628 -410.030168)
					(mid 65.154048 -410.030168)
					(end 65.857628 -410.030168)
				)
			)
		)
	)
	(zone
		(layers "B.Cu" "In11.Cu" "In13.Cu" "In15.Cu")
		(hatch none 0.5)
		(connect_pads
			(clearance 0)
		)
		(min_thickness 0.25)
		(keepout
			(tracks not_allowed)
			(vias allowed)
			(pads allowed)
			(copperpour not_allowed)
			(footprints allowed)
		)
		(placement
			(enabled no)
			(sheetname "")
		)
		(fill yes
			(thermal_gap 0.5)
			(thermal_bridge_width 0.5)
			(island_removal_mode 0)
		)
		(polygon
			(pts
				(arc
					(start 353.438206 -283.219906)
					(mid 352.785426 -283.219906)
					(end 353.438206 -283.219906)
				)
			)
		)
	)
	(zone
		(layers "B.Cu" "In11.Cu" "In13.Cu" "In15.Cu")
		(hatch none 0.5)
		(connect_pads
			(clearance 0)
		)
		(min_thickness 0.25)
		(keepout
			(tracks not_allowed)
			(vias allowed)
			(pads allowed)
			(copperpour not_allowed)
			(footprints allowed)
		)
		(placement
			(enabled no)
			(sheetname "")
		)
		(fill yes
			(thermal_gap 0.5)
			(thermal_bridge_width 0.5)
			(island_removal_mode 0)
		)
		(polygon
			(pts
				(arc
					(start 145.154904 -437.889904)
					(mid 144.345152 -437.889904)
					(end 145.154904 -437.889904)
				)
			)
		)
	)
	(zone
		(layers "B.Cu" "In11.Cu" "In13.Cu" "In15.Cu")
		(hatch none 0.5)
		(connect_pads
			(clearance 0)
		)
		(min_thickness 0.25)
		(keepout
			(tracks not_allowed)
			(vias allowed)
			(pads allowed)
			(copperpour not_allowed)
			(footprints allowed)
		)
		(placement
			(enabled no)
			(sheetname "")
		)
		(fill yes
			(thermal_gap 0.5)
			(thermal_bridge_width 0.5)
			(island_removal_mode 0)
		)
		(polygon
			(pts
				(arc
					(start 87.641938 -281.59202)
					(mid 86.989158 -281.59202)
					(end 87.641938 -281.59202)
				)
			)
		)
	)
	(zone
		(layers "B.Cu" "In11.Cu" "In13.Cu" "In15.Cu")
		(hatch none 0.5)
		(connect_pads
			(clearance 0)
		)
		(min_thickness 0.25)
		(keepout
			(tracks not_allowed)
			(vias allowed)
			(pads allowed)
			(copperpour not_allowed)
			(footprints allowed)
		)
		(placement
			(enabled no)
			(sheetname "")
		)
		(fill yes
			(thermal_gap 0.5)
			(thermal_bridge_width 0.5)
			(island_removal_mode 0)
		)
		(polygon
			(pts
				(arc
					(start 284.243272 -285.716726)
					(mid 283.590492 -285.716726)
					(end 284.243272 -285.716726)
				)
			)
		)
	)
	(zone
		(layers "B.Cu" "In11.Cu" "In13.Cu" "In15.Cu")
		(hatch none 0.5)
		(connect_pads
			(clearance 0)
		)
		(min_thickness 0.25)
		(keepout
			(tracks not_allowed)
			(vias allowed)
			(pads allowed)
			(copperpour not_allowed)
			(footprints allowed)
		)
		(placement
			(enabled no)
			(sheetname "")
		)
		(fill yes
			(thermal_gap 0.5)
			(thermal_bridge_width 0.5)
			(island_removal_mode 0)
		)
		(polygon
			(pts
				(arc
					(start 96.100138 -266.941808)
					(mid 95.447358 -266.941808)
					(end 96.100138 -266.941808)
				)
			)
		)
	)
	(zone
		(layers "B.Cu" "In11.Cu" "In13.Cu" "In15.Cu")
		(hatch none 0.5)
		(connect_pads
			(clearance 0)
		)
		(min_thickness 0.25)
		(keepout
			(tracks not_allowed)
			(vias allowed)
			(pads allowed)
			(copperpour not_allowed)
			(footprints allowed)
		)
		(placement
			(enabled no)
			(sheetname "")
		)
		(fill yes
			(thermal_gap 0.5)
			(thermal_bridge_width 0.5)
			(island_removal_mode 0)
		)
		(polygon
			(pts
				(arc
					(start 371.65407 -247.992138)
					(mid 371.00129 -247.992138)
					(end 371.65407 -247.992138)
				)
			)
		)
	)
	(zone
		(layers "B.Cu" "In11.Cu" "In13.Cu" "In15.Cu")
		(hatch none 0.5)
		(connect_pads
			(clearance 0)
		)
		(min_thickness 0.25)
		(keepout
			(tracks not_allowed)
			(vias allowed)
			(pads allowed)
			(copperpour not_allowed)
			(footprints allowed)
		)
		(placement
			(enabled no)
			(sheetname "")
		)
		(fill yes
			(thermal_gap 0.5)
			(thermal_bridge_width 0.5)
			(island_removal_mode 0)
		)
		(polygon
			(pts
				(arc
					(start 126.533402 -239.853216)
					(mid 125.880622 -239.853216)
					(end 126.533402 -239.853216)
				)
			)
		)
	)
	(zone
		(layers "B.Cu" "In11.Cu" "In13.Cu" "In15.Cu")
		(hatch none 0.5)
		(connect_pads
			(clearance 0)
		)
		(min_thickness 0.25)
		(keepout
			(tracks not_allowed)
			(vias allowed)
			(pads allowed)
			(copperpour not_allowed)
			(footprints allowed)
		)
		(placement
			(enabled no)
			(sheetname "")
		)
		(fill yes
			(thermal_gap 0.5)
			(thermal_bridge_width 0.5)
			(island_removal_mode 0)
		)
		(polygon
			(pts
				(arc
					(start 354.268024 -227.64496)
					(mid 353.615244 -227.64496)
					(end 354.268024 -227.64496)
				)
			)
		)
	)
	(zone
		(layers "B.Cu" "In11.Cu" "In13.Cu" "In15.Cu")
		(hatch none 0.5)
		(connect_pads
			(clearance 0)
		)
		(min_thickness 0.25)
		(keepout
			(tracks not_allowed)
			(vias allowed)
			(pads allowed)
			(copperpour not_allowed)
			(footprints allowed)
		)
		(placement
			(enabled no)
			(sheetname "")
		)
		(fill yes
			(thermal_gap 0.5)
			(thermal_bridge_width 0.5)
			(island_removal_mode 0)
		)
		(polygon
			(pts
				(arc
					(start 380.111 -410.030168)
					(mid 379.40742 -410.030168)
					(end 380.111 -410.030168)
				)
			)
		)
	)
	(zone
		(layers "B.Cu" "In11.Cu" "In13.Cu" "In15.Cu")
		(hatch none 0.5)
		(connect_pads
			(clearance 0)
		)
		(min_thickness 0.25)
		(keepout
			(tracks not_allowed)
			(vias allowed)
			(pads allowed)
			(copperpour not_allowed)
			(footprints allowed)
		)
		(placement
			(enabled no)
			(sheetname "")
		)
		(fill yes
			(thermal_gap 0.5)
			(thermal_bridge_width 0.5)
			(island_removal_mode 0)
		)
		(polygon
			(pts
				(arc
					(start 371.398546 -175.486568)
					(mid 370.694966 -175.486568)
					(end 371.398546 -175.486568)
				)
			)
		)
	)
	(zone
		(layers "B.Cu" "In11.Cu" "In13.Cu" "In15.Cu")
		(hatch none 0.5)
		(connect_pads
			(clearance 0)
		)
		(min_thickness 0.25)
		(keepout
			(tracks not_allowed)
			(vias allowed)
			(pads allowed)
			(copperpour not_allowed)
			(footprints allowed)
		)
		(placement
			(enabled no)
			(sheetname "")
		)
		(fill yes
			(thermal_gap 0.5)
			(thermal_bridge_width 0.5)
			(island_removal_mode 0)
		)
		(polygon
			(pts
				(arc
					(start 95.990156 -239.0394)
					(mid 95.337376 -239.0394)
					(end 95.990156 -239.0394)
				)
			)
		)
	)
	(zone
		(layers "B.Cu" "In11.Cu" "In13.Cu" "In15.Cu")
		(hatch none 0.5)
		(connect_pads
			(clearance 0)
		)
		(min_thickness 0.25)
		(keepout
			(tracks not_allowed)
			(vias allowed)
			(pads allowed)
			(copperpour not_allowed)
			(footprints allowed)
		)
		(placement
			(enabled no)
			(sheetname "")
		)
		(fill yes
			(thermal_gap 0.5)
			(thermal_bridge_width 0.5)
			(island_removal_mode 0)
		)
		(polygon
			(pts
				(arc
					(start 323.05498 -434.48986)
					(mid 322.245228 -434.48986)
					(end 323.05498 -434.48986)
				)
			)
		)
	)
	(zone
		(layers "B.Cu" "In11.Cu" "In13.Cu" "In15.Cu")
		(hatch none 0.5)
		(connect_pads
			(clearance 0)
		)
		(min_thickness 0.25)
		(keepout
			(tracks not_allowed)
			(vias allowed)
			(pads allowed)
			(copperpour not_allowed)
			(footprints allowed)
		)
		(placement
			(enabled no)
			(sheetname "")
		)
		(fill yes
			(thermal_gap 0.5)
			(thermal_bridge_width 0.5)
			(island_removal_mode 0)
		)
		(polygon
			(pts
				(arc
					(start 317.054992 -435.489858)
					(mid 316.24524 -435.489858)
					(end 317.054992 -435.489858)
				)
			)
		)
	)
	(zone
		(layers "B.Cu" "In11.Cu" "In13.Cu" "In15.Cu")
		(hatch none 0.5)
		(connect_pads
			(clearance 0)
		)
		(min_thickness 0.25)
		(keepout
			(tracks not_allowed)
			(vias allowed)
			(pads allowed)
			(copperpour not_allowed)
			(footprints allowed)
		)
		(placement
			(enabled no)
			(sheetname "")
		)
		(fill yes
			(thermal_gap 0.5)
			(thermal_bridge_width 0.5)
			(island_removal_mode 0)
		)
		(polygon
			(pts
				(arc
					(start 128.522984 -277.522432)
					(mid 127.870204 -277.522432)
					(end 128.522984 -277.522432)
				)
			)
		)
	)
	(zone
		(layers "B.Cu" "In11.Cu" "In13.Cu" "In15.Cu")
		(hatch none 0.5)
		(connect_pads
			(clearance 0)
		)
		(min_thickness 0.25)
		(keepout
			(tracks not_allowed)
			(vias allowed)
			(pads allowed)
			(copperpour not_allowed)
			(footprints allowed)
		)
		(placement
			(enabled no)
			(sheetname "")
		)
		(fill yes
			(thermal_gap 0.5)
			(thermal_bridge_width 0.5)
			(island_removal_mode 0)
		)
		(polygon
			(pts
				(arc
					(start 284.243272 -302.716692)
					(mid 283.590492 -302.716692)
					(end 284.243272 -302.716692)
				)
			)
		)
	)
	(zone
		(layers "B.Cu" "In11.Cu" "In13.Cu" "In15.Cu")
		(hatch none 0.5)
		(connect_pads
			(clearance 0)
		)
		(min_thickness 0.25)
		(keepout
			(tracks not_allowed)
			(vias allowed)
			(pads allowed)
			(copperpour not_allowed)
			(footprints allowed)
		)
		(placement
			(enabled no)
			(sheetname "")
		)
		(fill yes
			(thermal_gap 0.5)
			(thermal_bridge_width 0.5)
			(island_removal_mode 0)
		)
		(polygon
			(pts
				(arc
					(start 280.143204 -271.266666)
					(mid 279.490424 -271.266666)
					(end 280.143204 -271.266666)
				)
			)
		)
	)
	(zone
		(layers "B.Cu" "In11.Cu" "In13.Cu" "In15.Cu")
		(hatch none 0.5)
		(connect_pads
			(clearance 0)
		)
		(min_thickness 0.25)
		(keepout
			(tracks not_allowed)
			(vias allowed)
			(pads allowed)
			(copperpour not_allowed)
			(footprints allowed)
		)
		(placement
			(enabled no)
			(sheetname "")
		)
		(fill yes
			(thermal_gap 0.5)
			(thermal_bridge_width 0.5)
			(island_removal_mode 0)
		)
		(polygon
			(pts
				(arc
					(start 229.54869 -55.643272)
					(mid 228.84511 -55.643272)
					(end 229.54869 -55.643272)
				)
			)
		)
	)
	(zone
		(layers "B.Cu" "In11.Cu" "In13.Cu" "In15.Cu")
		(hatch none 0.5)
		(connect_pads
			(clearance 0)
		)
		(min_thickness 0.25)
		(keepout
			(tracks not_allowed)
			(vias allowed)
			(pads allowed)
			(copperpour not_allowed)
			(footprints allowed)
		)
		(placement
			(enabled no)
			(sheetname "")
		)
		(fill yes
			(thermal_gap 0.5)
			(thermal_bridge_width 0.5)
			(island_removal_mode 0)
		)
		(polygon
			(pts
				(arc
					(start 32.203136 -277.216616)
					(mid 31.550356 -277.216616)
					(end 32.203136 -277.216616)
				)
			)
		)
	)
	(zone
		(layers "B.Cu" "In11.Cu" "In13.Cu" "In15.Cu")
		(hatch none 0.5)
		(connect_pads
			(clearance 0)
		)
		(min_thickness 0.25)
		(keepout
			(tracks not_allowed)
			(vias allowed)
			(pads allowed)
			(copperpour not_allowed)
			(footprints allowed)
		)
		(placement
			(enabled no)
			(sheetname "")
		)
		(fill yes
			(thermal_gap 0.5)
			(thermal_bridge_width 0.5)
			(island_removal_mode 0)
		)
		(polygon
			(pts
				(arc
					(start 192.310004 -298.466764)
					(mid 191.657224 -298.466764)
					(end 192.310004 -298.466764)
				)
			)
		)
	)
	(zone
		(layers "B.Cu" "In11.Cu" "In13.Cu" "In15.Cu")
		(hatch none 0.5)
		(connect_pads
			(clearance 0)
		)
		(min_thickness 0.25)
		(keepout
			(tracks not_allowed)
			(vias allowed)
			(pads allowed)
			(copperpour not_allowed)
			(footprints allowed)
		)
		(placement
			(enabled no)
			(sheetname "")
		)
		(fill yes
			(thermal_gap 0.5)
			(thermal_bridge_width 0.5)
			(island_removal_mode 0)
		)
		(polygon
			(pts
				(arc
					(start 338.027518 -403.883876)
					(mid 337.323938 -403.883876)
					(end 338.027518 -403.883876)
				)
			)
		)
	)
	(zone
		(layers "B.Cu" "In11.Cu" "In13.Cu" "In15.Cu")
		(hatch none 0.5)
		(connect_pads
			(clearance 0)
		)
		(min_thickness 0.25)
		(keepout
			(tracks not_allowed)
			(vias allowed)
			(pads allowed)
			(copperpour not_allowed)
			(footprints allowed)
		)
		(placement
			(enabled no)
			(sheetname "")
		)
		(fill yes
			(thermal_gap 0.5)
			(thermal_bridge_width 0.5)
			(island_removal_mode 0)
		)
		(polygon
			(pts
				(arc
					(start 349.517462 -173.661832)
					(mid 348.813882 -173.661832)
					(end 349.517462 -173.661832)
				)
			)
		)
	)
	(zone
		(layers "B.Cu" "In11.Cu" "In13.Cu" "In15.Cu")
		(hatch none 0.5)
		(connect_pads
			(clearance 0)
		)
		(min_thickness 0.25)
		(keepout
			(tracks not_allowed)
			(vias allowed)
			(pads allowed)
			(copperpour not_allowed)
			(footprints allowed)
		)
		(placement
			(enabled no)
			(sheetname "")
		)
		(fill yes
			(thermal_gap 0.5)
			(thermal_bridge_width 0.5)
			(island_removal_mode 0)
		)
		(polygon
			(pts
				(arc
					(start 344.980006 -253.919736)
					(mid 344.327226 -253.919736)
					(end 344.980006 -253.919736)
				)
			)
		)
	)
	(zone
		(layers "B.Cu" "In11.Cu" "In13.Cu" "In15.Cu")
		(hatch none 0.5)
		(connect_pads
			(clearance 0)
		)
		(min_thickness 0.25)
		(keepout
			(tracks not_allowed)
			(vias allowed)
			(pads allowed)
			(copperpour not_allowed)
			(footprints allowed)
		)
		(placement
			(enabled no)
			(sheetname "")
		)
		(fill yes
			(thermal_gap 0.5)
			(thermal_bridge_width 0.5)
			(island_removal_mode 0)
		)
		(polygon
			(pts
				(arc
					(start 375.41327 -228.45903)
					(mid 374.76049 -228.45903)
					(end 375.41327 -228.45903)
				)
			)
		)
	)
	(zone
		(layers "B.Cu" "In11.Cu" "In13.Cu" "In15.Cu")
		(hatch none 0.5)
		(connect_pads
			(clearance 0)
		)
		(min_thickness 0.25)
		(keepout
			(tracks not_allowed)
			(vias allowed)
			(pads allowed)
			(copperpour not_allowed)
			(footprints allowed)
		)
		(placement
			(enabled no)
			(sheetname "")
		)
		(fill yes
			(thermal_gap 0.5)
			(thermal_bridge_width 0.5)
			(island_removal_mode 0)
		)
		(polygon
			(pts
				(arc
					(start 375.523252 -267.755878)
					(mid 374.870472 -267.755878)
					(end 375.523252 -267.755878)
				)
			)
		)
	)
	(zone
		(layers "B.Cu" "In11.Cu" "In13.Cu" "In15.Cu")
		(hatch none 0.5)
		(connect_pads
			(clearance 0)
		)
		(min_thickness 0.25)
		(keepout
			(tracks not_allowed)
			(vias allowed)
			(pads allowed)
			(copperpour not_allowed)
			(footprints allowed)
		)
		(placement
			(enabled no)
			(sheetname "")
		)
		(fill yes
			(thermal_gap 0.5)
			(thermal_bridge_width 0.5)
			(island_removal_mode 0)
		)
		(polygon
			(pts
				(arc
					(start 344.980006 -276.708616)
					(mid 344.327226 -276.708616)
					(end 344.980006 -276.708616)
				)
			)
		)
	)
	(zone
		(layers "B.Cu" "In11.Cu" "In13.Cu" "In15.Cu")
		(hatch none 0.5)
		(connect_pads
			(clearance 0)
		)
		(min_thickness 0.25)
		(keepout
			(tracks not_allowed)
			(vias allowed)
			(pads allowed)
			(copperpour not_allowed)
			(footprints allowed)
		)
		(placement
			(enabled no)
			(sheetname "")
		)
		(fill yes
			(thermal_gap 0.5)
			(thermal_bridge_width 0.5)
			(island_removal_mode 0)
		)
		(polygon
			(pts
				(arc
					(start 120.424448 -214.622634)
					(mid 119.771668 -214.622634)
					(end 120.424448 -214.622634)
				)
			)
		)
	)
	(zone
		(layers "B.Cu" "In11.Cu" "In13.Cu" "In15.Cu")
		(hatch none 0.5)
		(connect_pads
			(clearance 0)
		)
		(min_thickness 0.25)
		(keepout
			(tracks not_allowed)
			(vias allowed)
			(pads allowed)
			(copperpour not_allowed)
			(footprints allowed)
		)
		(placement
			(enabled no)
			(sheetname "")
		)
		(fill yes
			(thermal_gap 0.5)
			(thermal_bridge_width 0.5)
			(island_removal_mode 0)
		)
		(polygon
			(pts
				(arc
					(start 280.143204 -230.466646)
					(mid 279.490424 -230.466646)
					(end 280.143204 -230.466646)
				)
			)
		)
	)
	(zone
		(layers "B.Cu" "In11.Cu" "In13.Cu" "In15.Cu")
		(hatch none 0.5)
		(connect_pads
			(clearance 0)
		)
		(min_thickness 0.25)
		(keepout
			(tracks not_allowed)
			(vias allowed)
			(pads allowed)
			(copperpour not_allowed)
			(footprints allowed)
		)
		(placement
			(enabled no)
			(sheetname "")
		)
		(fill yes
			(thermal_gap 0.5)
			(thermal_bridge_width 0.5)
			(island_removal_mode 0)
		)
		(polygon
			(pts
				(arc
					(start 84.237068 -410.030168)
					(mid 83.533488 -410.030168)
					(end 84.237068 -410.030168)
				)
			)
		)
	)
	(zone
		(layers "B.Cu" "In11.Cu" "In13.Cu" "In15.Cu")
		(hatch none 0.5)
		(connect_pads
			(clearance 0)
		)
		(min_thickness 0.25)
		(keepout
			(tracks not_allowed)
			(vias allowed)
			(pads allowed)
			(copperpour not_allowed)
			(footprints allowed)
		)
		(placement
			(enabled no)
			(sheetname "")
		)
		(fill yes
			(thermal_gap 0.5)
			(thermal_bridge_width 0.5)
			(island_removal_mode 0)
		)
		(polygon
			(pts
				(arc
					(start 428.580804 -244.066568)
					(mid 427.928024 -244.066568)
					(end 428.580804 -244.066568)
				)
			)
		)
	)
	(zone
		(layers "B.Cu" "In11.Cu" "In13.Cu" "In15.Cu")
		(hatch none 0.5)
		(connect_pads
			(clearance 0)
		)
		(min_thickness 0.25)
		(keepout
			(tracks not_allowed)
			(vias allowed)
			(pads allowed)
			(copperpour not_allowed)
			(footprints allowed)
		)
		(placement
			(enabled no)
			(sheetname "")
		)
		(fill yes
			(thermal_gap 0.5)
			(thermal_bridge_width 0.5)
			(island_removal_mode 0)
		)
		(polygon
			(pts
				(arc
					(start 351.088452 -279.150318)
					(mid 350.435672 -279.150318)
					(end 351.088452 -279.150318)
				)
			)
		)
	)
	(zone
		(layers "B.Cu" "In11.Cu" "In13.Cu" "In15.Cu")
		(hatch none 0.5)
		(connect_pads
			(clearance 0)
		)
		(min_thickness 0.25)
		(keepout
			(tracks not_allowed)
			(vias allowed)
			(pads allowed)
			(copperpour not_allowed)
			(footprints allowed)
		)
		(placement
			(enabled no)
			(sheetname "")
		)
		(fill yes
			(thermal_gap 0.5)
			(thermal_bridge_width 0.5)
			(island_removal_mode 0)
		)
		(polygon
			(pts
				(arc
					(start 135.571484 -253.919736)
					(mid 134.918704 -253.919736)
					(end 135.571484 -253.919736)
				)
			)
		)
	)
	(zone
		(layers "B.Cu" "In11.Cu" "In13.Cu" "In15.Cu")
		(hatch none 0.5)
		(connect_pads
			(clearance 0)
		)
		(min_thickness 0.25)
		(keepout
			(tracks not_allowed)
			(vias allowed)
			(pads allowed)
			(copperpour not_allowed)
			(footprints allowed)
		)
		(placement
			(enabled no)
			(sheetname "")
		)
		(fill yes
			(thermal_gap 0.5)
			(thermal_bridge_width 0.5)
			(island_removal_mode 0)
		)
		(polygon
			(pts
				(arc
					(start 376.933206 -268.569694)
					(mid 376.280426 -268.569694)
					(end 376.933206 -268.569694)
				)
			)
		)
	)
	(zone
		(layers "B.Cu" "In11.Cu" "In13.Cu" "In15.Cu")
		(hatch none 0.5)
		(connect_pads
			(clearance 0)
		)
		(min_thickness 0.25)
		(keepout
			(tracks not_allowed)
			(vias allowed)
			(pads allowed)
			(copperpour not_allowed)
			(footprints allowed)
		)
		(placement
			(enabled no)
			(sheetname "")
		)
		(fill yes
			(thermal_gap 0.5)
			(thermal_bridge_width 0.5)
			(island_removal_mode 0)
		)
		(polygon
			(pts
				(arc
					(start 348.269052 -254.733552)
					(mid 347.616272 -254.733552)
					(end 348.269052 -254.733552)
				)
			)
		)
	)
	(zone
		(layers "B.Cu" "In11.Cu" "In13.Cu" "In15.Cu")
		(hatch none 0.5)
		(connect_pads
			(clearance 0)
		)
		(min_thickness 0.25)
		(keepout
			(tracks not_allowed)
			(vias allowed)
			(pads allowed)
			(copperpour not_allowed)
			(footprints allowed)
		)
		(placement
			(enabled no)
			(sheetname "")
		)
		(fill yes
			(thermal_gap 0.5)
			(thermal_bridge_width 0.5)
			(island_removal_mode 0)
		)
		(polygon
			(pts
				(arc
					(start 280.143204 -299.316648)
					(mid 279.490424 -299.316648)
					(end 280.143204 -299.316648)
				)
			)
		)
	)
	(zone
		(layers "B.Cu" "In11.Cu" "In13.Cu" "In15.Cu")
		(hatch none 0.5)
		(connect_pads
			(clearance 0)
		)
		(min_thickness 0.25)
		(keepout
			(tracks not_allowed)
			(vias allowed)
			(pads allowed)
			(copperpour not_allowed)
			(footprints allowed)
		)
		(placement
			(enabled no)
			(sheetname "")
		)
		(fill yes
			(thermal_gap 0.5)
			(thermal_bridge_width 0.5)
			(island_removal_mode 0)
		)
		(polygon
			(pts
				(arc
					(start 88.054942 -433.289964)
					(mid 87.24519 -433.289964)
					(end 88.054942 -433.289964)
				)
			)
		)
	)
	(zone
		(layers "B.Cu" "In11.Cu" "In13.Cu" "In15.Cu")
		(hatch none 0.5)
		(connect_pads
			(clearance 0)
		)
		(min_thickness 0.25)
		(keepout
			(tracks not_allowed)
			(vias allowed)
			(pads allowed)
			(copperpour not_allowed)
			(footprints allowed)
		)
		(placement
			(enabled no)
			(sheetname "")
		)
		(fill yes
			(thermal_gap 0.5)
			(thermal_bridge_width 0.5)
			(island_removal_mode 0)
		)
		(polygon
			(pts
				(arc
					(start 323.05498 -427.289976)
					(mid 322.245228 -427.289976)
					(end 323.05498 -427.289976)
				)
			)
		)
	)
	(zone
		(layers "B.Cu" "In11.Cu" "In13.Cu" "In15.Cu")
		(hatch none 0.5)
		(connect_pads
			(clearance 0)
		)
		(min_thickness 0.25)
		(keepout
			(tracks not_allowed)
			(vias allowed)
			(pads allowed)
			(copperpour not_allowed)
			(footprints allowed)
		)
		(placement
			(enabled no)
			(sheetname "")
		)
		(fill yes
			(thermal_gap 0.5)
			(thermal_bridge_width 0.5)
			(island_removal_mode 0)
		)
		(polygon
			(pts
				(arc
					(start 379.752352 -253.919736)
					(mid 379.099572 -253.919736)
					(end 379.752352 -253.919736)
				)
			)
		)
	)
	(zone
		(layers "B.Cu" "In11.Cu" "In13.Cu" "In15.Cu")
		(hatch none 0.5)
		(connect_pads
			(clearance 0)
		)
		(min_thickness 0.25)
		(keepout
			(tracks not_allowed)
			(vias allowed)
			(pads allowed)
			(copperpour not_allowed)
			(footprints allowed)
		)
		(placement
			(enabled no)
			(sheetname "")
		)
		(fill yes
			(thermal_gap 0.5)
			(thermal_bridge_width 0.5)
			(island_removal_mode 0)
		)
		(polygon
			(pts
				(arc
					(start 143.154908 -430.889918)
					(mid 142.345156 -430.889918)
					(end 143.154908 -430.889918)
				)
			)
		)
	)
	(zone
		(layers "B.Cu" "In11.Cu" "In13.Cu" "In15.Cu")
		(hatch none 0.5)
		(connect_pads
			(clearance 0)
		)
		(min_thickness 0.25)
		(keepout
			(tracks not_allowed)
			(vias allowed)
			(pads allowed)
			(copperpour not_allowed)
			(footprints allowed)
		)
		(placement
			(enabled no)
			(sheetname "")
		)
		(fill yes
			(thermal_gap 0.5)
			(thermal_bridge_width 0.5)
			(island_removal_mode 0)
		)
		(polygon
			(pts
				(arc
					(start 138.154918 -429.689768)
					(mid 137.345166 -429.689768)
					(end 138.154918 -429.689768)
				)
			)
		)
	)
	(zone
		(layers "B.Cu" "In11.Cu" "In13.Cu" "In15.Cu")
		(hatch none 0.5)
		(connect_pads
			(clearance 0)
		)
		(min_thickness 0.25)
		(keepout
			(tracks not_allowed)
			(vias allowed)
			(pads allowed)
			(copperpour not_allowed)
			(footprints allowed)
		)
		(placement
			(enabled no)
			(sheetname "")
		)
		(fill yes
			(thermal_gap 0.5)
			(thermal_bridge_width 0.5)
			(island_removal_mode 0)
		)
		(polygon
			(pts
				(arc
					(start 344.870024 -234.15625)
					(mid 344.217244 -234.15625)
					(end 344.870024 -234.15625)
				)
			)
		)
	)
	(zone
		(layers "B.Cu" "In11.Cu" "In13.Cu" "In15.Cu")
		(hatch none 0.5)
		(connect_pads
			(clearance 0)
		)
		(min_thickness 0.25)
		(keepout
			(tracks not_allowed)
			(vias allowed)
			(pads allowed)
			(copperpour not_allowed)
			(footprints allowed)
		)
		(placement
			(enabled no)
			(sheetname "")
		)
		(fill yes
			(thermal_gap 0.5)
			(thermal_bridge_width 0.5)
			(island_removal_mode 0)
		)
		(polygon
			(pts
				(arc
					(start 130.154934 -430.889918)
					(mid 129.345182 -430.889918)
					(end 130.154934 -430.889918)
				)
			)
		)
	)
	(zone
		(layers "B.Cu" "In11.Cu" "In13.Cu" "In15.Cu")
		(hatch none 0.5)
		(connect_pads
			(clearance 0)
		)
		(min_thickness 0.25)
		(keepout
			(tracks not_allowed)
			(vias allowed)
			(pads allowed)
			(copperpour not_allowed)
			(footprints allowed)
		)
		(placement
			(enabled no)
			(sheetname "")
		)
		(fill yes
			(thermal_gap 0.5)
			(thermal_bridge_width 0.5)
			(island_removal_mode 0)
		)
		(polygon
			(pts
				(arc
					(start 88.111584 -280.778204)
					(mid 87.458804 -280.778204)
					(end 88.111584 -280.778204)
				)
			)
		)
	)
	(zone
		(layers "B.Cu" "In11.Cu" "In13.Cu" "In15.Cu")
		(hatch none 0.5)
		(connect_pads
			(clearance 0)
		)
		(min_thickness 0.25)
		(keepout
			(tracks not_allowed)
			(vias allowed)
			(pads allowed)
			(copperpour not_allowed)
			(footprints allowed)
		)
		(placement
			(enabled no)
			(sheetname "")
		)
		(fill yes
			(thermal_gap 0.5)
			(thermal_bridge_width 0.5)
			(island_removal_mode 0)
		)
		(polygon
			(pts
				(arc
					(start 157.16377 -47.943008)
					(mid 156.46019 -47.943008)
					(end 157.16377 -47.943008)
				)
			)
		)
	)
	(zone
		(layers "B.Cu" "In11.Cu" "In13.Cu" "In15.Cu")
		(hatch none 0.5)
		(connect_pads
			(clearance 0)
		)
		(min_thickness 0.25)
		(keepout
			(tracks not_allowed)
			(vias allowed)
			(pads allowed)
			(copperpour not_allowed)
			(footprints allowed)
		)
		(placement
			(enabled no)
			(sheetname "")
		)
		(fill yes
			(thermal_gap 0.5)
			(thermal_bridge_width 0.5)
			(island_removal_mode 0)
		)
		(polygon
			(pts
				(arc
					(start 82.054954 -434.289962)
					(mid 81.245202 -434.289962)
					(end 82.054954 -434.289962)
				)
			)
		)
	)
	(zone
		(layers "B.Cu" "In11.Cu" "In13.Cu" "In15.Cu")
		(hatch none 0.5)
		(connect_pads
			(clearance 0)
		)
		(min_thickness 0.25)
		(keepout
			(tracks not_allowed)
			(vias allowed)
			(pads allowed)
			(copperpour not_allowed)
			(footprints allowed)
		)
		(placement
			(enabled no)
			(sheetname "")
		)
		(fill yes
			(thermal_gap 0.5)
			(thermal_bridge_width 0.5)
			(island_removal_mode 0)
		)
		(polygon
			(pts
				(arc
					(start 319.054988 -427.289976)
					(mid 318.245236 -427.289976)
					(end 319.054988 -427.289976)
				)
			)
		)
	)
	(zone
		(layers "B.Cu" "In11.Cu" "In13.Cu" "In15.Cu")
		(hatch none 0.5)
		(connect_pads
			(clearance 0)
		)
		(min_thickness 0.25)
		(keepout
			(tracks not_allowed)
			(vias allowed)
			(pads allowed)
			(copperpour not_allowed)
			(footprints allowed)
		)
		(placement
			(enabled no)
			(sheetname "")
		)
		(fill yes
			(thermal_gap 0.5)
			(thermal_bridge_width 0.5)
			(island_removal_mode 0)
		)
		(polygon
			(pts
				(arc
					(start 49.677828 -410.030168)
					(mid 48.974248 -410.030168)
					(end 49.677828 -410.030168)
				)
			)
		)
	)
	(zone
		(layers "B.Cu" "In11.Cu" "In13.Cu" "In15.Cu")
		(hatch none 0.5)
		(connect_pads
			(clearance 0)
		)
		(min_thickness 0.25)
		(keepout
			(tracks not_allowed)
			(vias allowed)
			(pads allowed)
			(copperpour not_allowed)
			(footprints allowed)
		)
		(placement
			(enabled no)
			(sheetname "")
		)
		(fill yes
			(thermal_gap 0.5)
			(thermal_bridge_width 0.5)
			(island_removal_mode 0)
		)
		(polygon
			(pts
				(arc
					(start 284.243272 -227.91674)
					(mid 283.590492 -227.91674)
					(end 284.243272 -227.91674)
				)
			)
		)
	)
	(zone
		(layers "B.Cu" "In11.Cu" "In13.Cu" "In15.Cu")
		(hatch none 0.5)
		(connect_pads
			(clearance 0)
		)
		(min_thickness 0.25)
		(keepout
			(tracks not_allowed)
			(vias allowed)
			(pads allowed)
			(copperpour not_allowed)
			(footprints allowed)
		)
		(placement
			(enabled no)
			(sheetname "")
		)
		(fill yes
			(thermal_gap 0.5)
			(thermal_bridge_width 0.5)
			(island_removal_mode 0)
		)
		(polygon
			(pts
				(arc
					(start 128.522984 -272.639282)
					(mid 127.870204 -272.639282)
					(end 128.522984 -272.639282)
				)
			)
		)
	)
	(zone
		(layers "B.Cu" "In11.Cu" "In13.Cu" "In15.Cu")
		(hatch none 0.5)
		(connect_pads
			(clearance 0)
		)
		(min_thickness 0.25)
		(keepout
			(tracks not_allowed)
			(vias allowed)
			(pads allowed)
			(copperpour not_allowed)
			(footprints allowed)
		)
		(placement
			(enabled no)
			(sheetname "")
		)
		(fill yes
			(thermal_gap 0.5)
			(thermal_bridge_width 0.5)
			(island_removal_mode 0)
		)
		(polygon
			(pts
				(arc
					(start 97.509584 -275.8948)
					(mid 96.856804 -275.8948)
					(end 97.509584 -275.8948)
				)
			)
		)
	)
	(zone
		(layers "B.Cu" "In11.Cu" "In13.Cu" "In15.Cu")
		(hatch none 0.5)
		(connect_pads
			(clearance 0)
		)
		(min_thickness 0.25)
		(keepout
			(tracks not_allowed)
			(vias allowed)
			(pads allowed)
			(copperpour not_allowed)
			(footprints allowed)
		)
		(placement
			(enabled no)
			(sheetname "")
		)
		(fill yes
			(thermal_gap 0.5)
			(thermal_bridge_width 0.5)
			(island_removal_mode 0)
		)
		(polygon
			(pts
				(arc
					(start 280.143204 -277.216616)
					(mid 279.490424 -277.216616)
					(end 280.143204 -277.216616)
				)
			)
		)
	)
	(zone
		(layers "B.Cu" "In11.Cu" "In13.Cu" "In15.Cu")
		(hatch none 0.5)
		(connect_pads
			(clearance 0)
		)
		(min_thickness 0.25)
		(keepout
			(tracks not_allowed)
			(vias allowed)
			(pads allowed)
			(copperpour not_allowed)
			(footprints allowed)
		)
		(placement
			(enabled no)
			(sheetname "")
		)
		(fill yes
			(thermal_gap 0.5)
			(thermal_bridge_width 0.5)
			(island_removal_mode 0)
		)
		(polygon
			(pts
				(arc
					(start 128.883156 -230.900478)
					(mid 128.230376 -230.900478)
					(end 128.883156 -230.900478)
				)
			)
		)
	)
	(zone
		(layers "B.Cu" "In11.Cu" "In13.Cu" "In15.Cu")
		(hatch none 0.5)
		(connect_pads
			(clearance 0)
		)
		(min_thickness 0.25)
		(keepout
			(tracks not_allowed)
			(vias allowed)
			(pads allowed)
			(copperpour not_allowed)
			(footprints allowed)
		)
		(placement
			(enabled no)
			(sheetname "")
		)
		(fill yes
			(thermal_gap 0.5)
			(thermal_bridge_width 0.5)
			(island_removal_mode 0)
		)
		(polygon
			(pts
				(arc
					(start 128.522984 -262.872474)
					(mid 127.870204 -262.872474)
					(end 128.522984 -262.872474)
				)
			)
		)
	)
	(zone
		(layers "B.Cu" "In11.Cu" "In13.Cu" "In15.Cu")
		(hatch none 0.5)
		(connect_pads
			(clearance 0)
		)
		(min_thickness 0.25)
		(keepout
			(tracks not_allowed)
			(vias allowed)
			(pads allowed)
			(copperpour not_allowed)
			(footprints allowed)
		)
		(placement
			(enabled no)
			(sheetname "")
		)
		(fill yes
			(thermal_gap 0.5)
			(thermal_bridge_width 0.5)
			(island_removal_mode 0)
		)
		(polygon
			(pts
				(arc
					(start 370.474494 -169.923968)
					(mid 369.770914 -169.923968)
					(end 370.474494 -169.923968)
				)
			)
		)
	)
	(zone
		(layers "B.Cu" "In11.Cu" "In13.Cu" "In15.Cu")
		(hatch none 0.5)
		(connect_pads
			(clearance 0)
		)
		(min_thickness 0.25)
		(keepout
			(tracks not_allowed)
			(vias allowed)
			(pads allowed)
			(copperpour not_allowed)
			(footprints allowed)
		)
		(placement
			(enabled no)
			(sheetname "")
		)
		(fill yes
			(thermal_gap 0.5)
			(thermal_bridge_width 0.5)
			(island_removal_mode 0)
		)
		(polygon
			(pts
				(arc
					(start 156.412184 -410.030168)
					(mid 155.708604 -410.030168)
					(end 156.412184 -410.030168)
				)
			)
		)
	)
	(zone
		(layers "B.Cu" "In11.Cu" "In13.Cu" "In15.Cu")
		(hatch none 0.5)
		(connect_pads
			(clearance 0)
		)
		(min_thickness 0.25)
		(keepout
			(tracks not_allowed)
			(vias allowed)
			(pads allowed)
			(copperpour not_allowed)
			(footprints allowed)
		)
		(placement
			(enabled no)
			(sheetname "")
		)
		(fill yes
			(thermal_gap 0.5)
			(thermal_bridge_width 0.5)
			(island_removal_mode 0)
		)
		(polygon
			(pts
				(arc
					(start 458.781404 -244.066568)
					(mid 458.128624 -244.066568)
					(end 458.781404 -244.066568)
				)
			)
		)
	)
	(zone
		(layers "B.Cu" "In11.Cu" "In13.Cu" "In15.Cu")
		(hatch none 0.5)
		(connect_pads
			(clearance 0)
		)
		(min_thickness 0.25)
		(keepout
			(tracks not_allowed)
			(vias allowed)
			(pads allowed)
			(copperpour not_allowed)
			(footprints allowed)
		)
		(placement
			(enabled no)
			(sheetname "")
		)
		(fill yes
			(thermal_gap 0.5)
			(thermal_bridge_width 0.5)
			(island_removal_mode 0)
		)
		(polygon
			(pts
				(arc
					(start 96.100138 -276.708616)
					(mid 95.447358 -276.708616)
					(end 96.100138 -276.708616)
				)
			)
		)
	)
	(zone
		(layers "B.Cu" "In11.Cu" "In13.Cu" "In15.Cu")
		(hatch none 0.5)
		(connect_pads
			(clearance 0)
		)
		(min_thickness 0.25)
		(keepout
			(tracks not_allowed)
			(vias allowed)
			(pads allowed)
			(copperpour not_allowed)
			(footprints allowed)
		)
		(placement
			(enabled no)
			(sheetname "")
		)
		(fill yes
			(thermal_gap 0.5)
			(thermal_bridge_width 0.5)
			(island_removal_mode 0)
		)
		(polygon
			(pts
				(arc
					(start 129.352802 -234.970066)
					(mid 128.700022 -234.970066)
					(end 129.352802 -234.970066)
				)
			)
		)
	)
	(zone
		(layers "B.Cu" "In11.Cu" "In13.Cu" "In15.Cu")
		(hatch none 0.5)
		(connect_pads
			(clearance 0)
		)
		(min_thickness 0.25)
		(keepout
			(tracks not_allowed)
			(vias allowed)
			(pads allowed)
			(copperpour not_allowed)
			(footprints allowed)
		)
		(placement
			(enabled no)
			(sheetname "")
		)
		(fill yes
			(thermal_gap 0.5)
			(thermal_bridge_width 0.5)
			(island_removal_mode 0)
		)
		(polygon
			(pts
				(arc
					(start 436.150004 -286.56661)
					(mid 435.497224 -286.56661)
					(end 436.150004 -286.56661)
				)
			)
		)
	)
	(zone
		(layers "B.Cu" "In11.Cu" "In13.Cu" "In15.Cu")
		(hatch none 0.5)
		(connect_pads
			(clearance 0)
		)
		(min_thickness 0.25)
		(keepout
			(tracks not_allowed)
			(vias allowed)
			(pads allowed)
			(copperpour not_allowed)
			(footprints allowed)
		)
		(placement
			(enabled no)
			(sheetname "")
		)
		(fill yes
			(thermal_gap 0.5)
			(thermal_bridge_width 0.5)
			(island_removal_mode 0)
		)
		(polygon
			(pts
				(arc
					(start 374.943624 -230.900478)
					(mid 374.290844 -230.900478)
					(end 374.943624 -230.900478)
				)
			)
		)
	)
	(zone
		(layers "B.Cu" "In11.Cu" "In13.Cu" "In15.Cu")
		(hatch none 0.5)
		(connect_pads
			(clearance 0)
		)
		(min_thickness 0.25)
		(keepout
			(tracks not_allowed)
			(vias allowed)
			(pads allowed)
			(copperpour not_allowed)
			(footprints allowed)
		)
		(placement
			(enabled no)
			(sheetname "")
		)
		(fill yes
			(thermal_gap 0.5)
			(thermal_bridge_width 0.5)
			(island_removal_mode 0)
		)
		(polygon
			(pts
				(arc
					(start 188.209936 -224.516696)
					(mid 187.557156 -224.516696)
					(end 188.209936 -224.516696)
				)
			)
		)
	)
	(zone
		(layers "B.Cu" "In11.Cu" "In13.Cu" "In15.Cu")
		(hatch none 0.5)
		(connect_pads
			(clearance 0)
		)
		(min_thickness 0.25)
		(keepout
			(tracks not_allowed)
			(vias allowed)
			(pads allowed)
			(copperpour not_allowed)
			(footprints allowed)
		)
		(placement
			(enabled no)
			(sheetname "")
		)
		(fill yes
			(thermal_gap 0.5)
			(thermal_bridge_width 0.5)
			(island_removal_mode 0)
		)
		(polygon
			(pts
				(arc
					(start 343.570052 -275.8948)
					(mid 342.917272 -275.8948)
					(end 343.570052 -275.8948)
				)
			)
		)
	)
	(zone
		(layers "B.Cu" "In11.Cu" "In13.Cu" "In15.Cu")
		(hatch none 0.5)
		(connect_pads
			(clearance 0)
		)
		(min_thickness 0.25)
		(keepout
			(tracks not_allowed)
			(vias allowed)
			(pads allowed)
			(copperpour not_allowed)
			(footprints allowed)
		)
		(placement
			(enabled no)
			(sheetname "")
		)
		(fill yes
			(thermal_gap 0.5)
			(thermal_bridge_width 0.5)
			(island_removal_mode 0)
		)
		(polygon
			(pts
				(arc
					(start 458.781404 -245.76659)
					(mid 458.128624 -245.76659)
					(end 458.781404 -245.76659)
				)
			)
		)
	)
	(zone
		(layers "B.Cu" "In11.Cu" "In13.Cu" "In15.Cu")
		(hatch none 0.5)
		(connect_pads
			(clearance 0)
		)
		(min_thickness 0.25)
		(keepout
			(tracks not_allowed)
			(vias allowed)
			(pads allowed)
			(copperpour not_allowed)
			(footprints allowed)
		)
		(placement
			(enabled no)
			(sheetname "")
		)
		(fill yes
			(thermal_gap 0.5)
			(thermal_bridge_width 0.5)
			(island_removal_mode 0)
		)
		(polygon
			(pts
				(arc
					(start 129.932938 -278.336502)
					(mid 129.280158 -278.336502)
					(end 129.932938 -278.336502)
				)
			)
		)
	)
	(zone
		(layers "B.Cu" "In11.Cu" "In13.Cu" "In15.Cu")
		(hatch none 0.5)
		(connect_pads
			(clearance 0)
		)
		(min_thickness 0.25)
		(keepout
			(tracks not_allowed)
			(vias allowed)
			(pads allowed)
			(copperpour not_allowed)
			(footprints allowed)
		)
		(placement
			(enabled no)
			(sheetname "")
		)
		(fill yes
			(thermal_gap 0.5)
			(thermal_bridge_width 0.5)
			(island_removal_mode 0)
		)
		(polygon
			(pts
				(arc
					(start 326.638158 -403.883876)
					(mid 325.934578 -403.883876)
					(end 326.638158 -403.883876)
				)
			)
		)
	)
	(zone
		(layers "B.Cu" "In11.Cu" "In13.Cu" "In15.Cu")
		(hatch none 0.5)
		(connect_pads
			(clearance 0)
		)
		(min_thickness 0.25)
		(keepout
			(tracks not_allowed)
			(vias allowed)
			(pads allowed)
			(copperpour not_allowed)
			(footprints allowed)
		)
		(placement
			(enabled no)
			(sheetname "")
		)
		(fill yes
			(thermal_gap 0.5)
			(thermal_bridge_width 0.5)
			(island_removal_mode 0)
		)
		(polygon
			(pts
				(arc
					(start 376.463052 -254.733552)
					(mid 375.810272 -254.733552)
					(end 376.463052 -254.733552)
				)
			)
		)
	)
	(zone
		(layers "B.Cu" "In11.Cu" "In13.Cu" "In15.Cu")
		(hatch none 0.5)
		(connect_pads
			(clearance 0)
		)
		(min_thickness 0.25)
		(keepout
			(tracks not_allowed)
			(vias allowed)
			(pads allowed)
			(copperpour not_allowed)
			(footprints allowed)
		)
		(placement
			(enabled no)
			(sheetname "")
		)
		(fill yes
			(thermal_gap 0.5)
			(thermal_bridge_width 0.5)
			(island_removal_mode 0)
		)
		(polygon
			(pts
				(arc
					(start 310.458358 -403.883876)
					(mid 309.754778 -403.883876)
					(end 310.458358 -403.883876)
				)
			)
		)
	)
	(zone
		(layers "B.Cu" "In11.Cu" "In13.Cu" "In15.Cu")
		(hatch none 0.5)
		(connect_pads
			(clearance 0)
		)
		(min_thickness 0.25)
		(keepout
			(tracks not_allowed)
			(vias allowed)
			(pads allowed)
			(copperpour not_allowed)
			(footprints allowed)
		)
		(placement
			(enabled no)
			(sheetname "")
		)
		(fill yes
			(thermal_gap 0.5)
			(thermal_bridge_width 0.5)
			(island_removal_mode 0)
		)
		(polygon
			(pts
				(arc
					(start 94.110048 -214.622634)
					(mid 93.457268 -214.622634)
					(end 94.110048 -214.622634)
				)
			)
		)
	)
	(zone
		(layers "B.Cu" "In11.Cu" "In13.Cu" "In15.Cu")
		(hatch none 0.5)
		(connect_pads
			(clearance 0)
		)
		(min_thickness 0.25)
		(keepout
			(tracks not_allowed)
			(vias allowed)
			(pads allowed)
			(copperpour not_allowed)
			(footprints allowed)
		)
		(placement
			(enabled no)
			(sheetname "")
		)
		(fill yes
			(thermal_gap 0.5)
			(thermal_bridge_width 0.5)
			(island_removal_mode 0)
		)
		(polygon
			(pts
				(arc
					(start 295.230804 -243.216684)
					(mid 294.578024 -243.216684)
					(end 295.230804 -243.216684)
				)
			)
		)
	)
	(zone
		(layers "B.Cu" "In11.Cu" "In13.Cu" "In15.Cu")
		(hatch none 0.5)
		(connect_pads
			(clearance 0)
		)
		(min_thickness 0.25)
		(keepout
			(tracks not_allowed)
			(vias allowed)
			(pads allowed)
			(copperpour not_allowed)
			(footprints allowed)
		)
		(placement
			(enabled no)
			(sheetname "")
		)
		(fill yes
			(thermal_gap 0.5)
			(thermal_bridge_width 0.5)
			(island_removal_mode 0)
		)
		(polygon
			(pts
				(arc
					(start 343.570052 -274.266914)
					(mid 342.917272 -274.266914)
					(end 343.570052 -274.266914)
				)
			)
		)
	)
	(zone
		(layers "B.Cu" "In11.Cu" "In13.Cu" "In15.Cu")
		(hatch none 0.5)
		(connect_pads
			(clearance 0)
		)
		(min_thickness 0.25)
		(keepout
			(tracks not_allowed)
			(vias allowed)
			(pads allowed)
			(copperpour not_allowed)
			(footprints allowed)
		)
		(placement
			(enabled no)
			(sheetname "")
		)
		(fill yes
			(thermal_gap 0.5)
			(thermal_bridge_width 0.5)
			(island_removal_mode 0)
		)
		(polygon
			(pts
				(arc
					(start 344.870024 -229.272846)
					(mid 344.217244 -229.272846)
					(end 344.870024 -229.272846)
				)
			)
		)
	)
	(zone
		(layers "B.Cu" "In11.Cu" "In13.Cu" "In15.Cu")
		(hatch none 0.5)
		(connect_pads
			(clearance 0)
		)
		(min_thickness 0.25)
		(keepout
			(tracks not_allowed)
			(vias allowed)
			(pads allowed)
			(copperpour not_allowed)
			(footprints allowed)
		)
		(placement
			(enabled no)
			(sheetname "")
		)
		(fill yes
			(thermal_gap 0.5)
			(thermal_bridge_width 0.5)
			(island_removal_mode 0)
		)
		(polygon
			(pts
				(arc
					(start 203.297536 -314.616592)
					(mid 202.644756 -314.616592)
					(end 203.297536 -314.616592)
				)
			)
		)
	)
	(zone
		(layers "B.Cu" "In11.Cu" "In13.Cu" "In15.Cu")
		(hatch none 0.5)
		(connect_pads
			(clearance 0)
		)
		(min_thickness 0.25)
		(keepout
			(tracks not_allowed)
			(vias allowed)
			(pads allowed)
			(copperpour not_allowed)
			(footprints allowed)
		)
		(placement
			(enabled no)
			(sheetname "")
		)
		(fill yes
			(thermal_gap 0.5)
			(thermal_bridge_width 0.5)
			(island_removal_mode 0)
		)
		(polygon
			(pts
				(arc
					(start 158.611824 -410.030168)
					(mid 157.908244 -410.030168)
					(end 158.611824 -410.030168)
				)
			)
		)
	)
	(zone
		(layers "B.Cu" "In11.Cu" "In13.Cu" "In15.Cu")
		(hatch none 0.5)
		(connect_pads
			(clearance 0)
		)
		(min_thickness 0.25)
		(keepout
			(tracks not_allowed)
			(vias allowed)
			(pads allowed)
			(copperpour not_allowed)
			(footprints allowed)
		)
		(placement
			(enabled no)
			(sheetname "")
		)
		(fill yes
			(thermal_gap 0.5)
			(thermal_bridge_width 0.5)
			(island_removal_mode 0)
		)
		(polygon
			(pts
				(arc
					(start 343.930224 -245.55069)
					(mid 343.277444 -245.55069)
					(end 343.930224 -245.55069)
				)
			)
		)
	)
	(zone
		(layers "B.Cu" "In11.Cu" "In13.Cu" "In15.Cu")
		(hatch none 0.5)
		(connect_pads
			(clearance 0)
		)
		(min_thickness 0.25)
		(keepout
			(tracks not_allowed)
			(vias allowed)
			(pads allowed)
			(copperpour not_allowed)
			(footprints allowed)
		)
		(placement
			(enabled no)
			(sheetname "")
		)
		(fill yes
			(thermal_gap 0.5)
			(thermal_bridge_width 0.5)
			(island_removal_mode 0)
		)
		(polygon
			(pts
				(arc
					(start 350.03867 -247.992138)
					(mid 349.38589 -247.992138)
					(end 350.03867 -247.992138)
				)
			)
		)
	)
	(zone
		(layers "B.Cu" "In11.Cu" "In13.Cu" "In15.Cu")
		(hatch none 0.5)
		(connect_pads
			(clearance 0)
		)
		(min_thickness 0.25)
		(keepout
			(tracks not_allowed)
			(vias allowed)
			(pads allowed)
			(copperpour not_allowed)
			(footprints allowed)
		)
		(placement
			(enabled no)
			(sheetname "")
		)
		(fill yes
			(thermal_gap 0.5)
			(thermal_bridge_width 0.5)
			(island_removal_mode 0)
		)
		(polygon
			(pts
				(arc
					(start 338.05495 -427.089824)
					(mid 337.245198 -427.089824)
					(end 338.05495 -427.089824)
				)
			)
		)
	)
	(zone
		(layers "B.Cu" "In11.Cu" "In13.Cu" "In15.Cu")
		(hatch none 0.5)
		(connect_pads
			(clearance 0)
		)
		(min_thickness 0.25)
		(keepout
			(tracks not_allowed)
			(vias allowed)
			(pads allowed)
			(copperpour not_allowed)
			(footprints allowed)
		)
		(placement
			(enabled no)
			(sheetname "")
		)
		(fill yes
			(thermal_gap 0.5)
			(thermal_bridge_width 0.5)
			(island_removal_mode 0)
		)
		(polygon
			(pts
				(arc
					(start 348.628716 -214.622634)
					(mid 347.975936 -214.622634)
					(end 348.628716 -214.622634)
				)
			)
		)
	)
	(zone
		(layers "B.Cu" "In11.Cu" "In13.Cu" "In15.Cu")
		(hatch none 0.5)
		(connect_pads
			(clearance 0)
		)
		(min_thickness 0.25)
		(keepout
			(tracks not_allowed)
			(vias allowed)
			(pads allowed)
			(copperpour not_allowed)
			(footprints allowed)
		)
		(placement
			(enabled no)
			(sheetname "")
		)
		(fill yes
			(thermal_gap 0.5)
			(thermal_bridge_width 0.5)
			(island_removal_mode 0)
		)
		(polygon
			(pts
				(arc
					(start 76.054966 -434.48986)
					(mid 75.245214 -434.48986)
					(end 76.054966 -434.48986)
				)
			)
		)
	)
	(zone
		(layers "B.Cu" "In11.Cu" "In13.Cu" "In15.Cu")
		(hatch none 0.5)
		(connect_pads
			(clearance 0)
		)
		(min_thickness 0.25)
		(keepout
			(tracks not_allowed)
			(vias allowed)
			(pads allowed)
			(copperpour not_allowed)
			(footprints allowed)
		)
		(placement
			(enabled no)
			(sheetname "")
		)
		(fill yes
			(thermal_gap 0.5)
			(thermal_bridge_width 0.5)
			(island_removal_mode 0)
		)
		(polygon
			(pts
				(arc
					(start 343.46007 -243.108988)
					(mid 342.80729 -243.108988)
					(end 343.46007 -243.108988)
				)
			)
		)
	)
	(zone
		(layers "B.Cu" "In11.Cu" "In13.Cu" "In15.Cu")
		(hatch none 0.5)
		(connect_pads
			(clearance 0)
		)
		(min_thickness 0.25)
		(keepout
			(tracks not_allowed)
			(vias allowed)
			(pads allowed)
			(copperpour not_allowed)
			(footprints allowed)
		)
		(placement
			(enabled no)
			(sheetname "")
		)
		(fill yes
			(thermal_gap 0.5)
			(thermal_bridge_width 0.5)
			(island_removal_mode 0)
		)
		(polygon
			(pts
				(arc
					(start 334.054958 -427.089824)
					(mid 333.245206 -427.089824)
					(end 334.054958 -427.089824)
				)
			)
		)
	)
	(zone
		(layers "B.Cu" "In11.Cu" "In13.Cu" "In15.Cu")
		(hatch none 0.5)
		(connect_pads
			(clearance 0)
		)
		(min_thickness 0.25)
		(keepout
			(tracks not_allowed)
			(vias allowed)
			(pads allowed)
			(copperpour not_allowed)
			(footprints allowed)
		)
		(placement
			(enabled no)
			(sheetname "")
		)
		(fill yes
			(thermal_gap 0.5)
			(thermal_bridge_width 0.5)
			(island_removal_mode 0)
		)
		(polygon
			(pts
				(arc
					(start 357.667052 -274.266914)
					(mid 357.014272 -274.266914)
					(end 357.667052 -274.266914)
				)
			)
		)
	)
	(zone
		(layers "B.Cu" "In11.Cu" "In13.Cu" "In15.Cu")
		(hatch none 0.5)
		(connect_pads
			(clearance 0)
		)
		(min_thickness 0.25)
		(keepout
			(tracks not_allowed)
			(vias allowed)
			(pads allowed)
			(copperpour not_allowed)
			(footprints allowed)
		)
		(placement
			(enabled no)
			(sheetname "")
		)
		(fill yes
			(thermal_gap 0.5)
			(thermal_bridge_width 0.5)
			(island_removal_mode 0)
		)
		(polygon
			(pts
				(arc
					(start 436.150004 -219.41663)
					(mid 435.497224 -219.41663)
					(end 436.150004 -219.41663)
				)
			)
		)
	)
	(zone
		(layers "B.Cu" "In11.Cu" "In13.Cu" "In15.Cu")
		(hatch none 0.5)
		(connect_pads
			(clearance 0)
		)
		(min_thickness 0.25)
		(keepout
			(tracks not_allowed)
			(vias allowed)
			(pads allowed)
			(copperpour not_allowed)
			(footprints allowed)
		)
		(placement
			(enabled no)
			(sheetname "")
		)
		(fill yes
			(thermal_gap 0.5)
			(thermal_bridge_width 0.5)
			(island_removal_mode 0)
		)
		(polygon
			(pts
				(arc
					(start 455.337672 -307.816758)
					(mid 454.684892 -307.816758)
					(end 455.337672 -307.816758)
				)
			)
		)
	)
	(zone
		(layers "B.Cu" "In11.Cu" "In13.Cu" "In15.Cu")
		(hatch none 0.5)
		(connect_pads
			(clearance 0)
		)
		(min_thickness 0.25)
		(keepout
			(tracks not_allowed)
			(vias allowed)
			(pads allowed)
			(copperpour not_allowed)
			(footprints allowed)
		)
		(placement
			(enabled no)
			(sheetname "")
		)
		(fill yes
			(thermal_gap 0.5)
			(thermal_bridge_width 0.5)
			(island_removal_mode 0)
		)
		(polygon
			(pts
				(arc
					(start 374.943624 -234.15625)
					(mid 374.290844 -234.15625)
					(end 374.943624 -234.15625)
				)
			)
		)
	)
	(zone
		(layers "B.Cu" "In11.Cu" "In13.Cu" "In15.Cu")
		(hatch none 0.5)
		(connect_pads
			(clearance 0)
		)
		(min_thickness 0.25)
		(keepout
			(tracks not_allowed)
			(vias allowed)
			(pads allowed)
			(copperpour not_allowed)
			(footprints allowed)
		)
		(placement
			(enabled no)
			(sheetname "")
		)
		(fill yes
			(thermal_gap 0.5)
			(thermal_bridge_width 0.5)
			(island_removal_mode 0)
		)
		(polygon
			(pts
				(arc
					(start 36.303204 -229.616762)
					(mid 35.650424 -229.616762)
					(end 36.303204 -229.616762)
				)
			)
		)
	)
	(zone
		(layers "B.Cu" "In11.Cu" "In13.Cu" "In15.Cu")
		(hatch none 0.5)
		(connect_pads
			(clearance 0)
		)
		(min_thickness 0.25)
		(keepout
			(tracks not_allowed)
			(vias allowed)
			(pads allowed)
			(copperpour not_allowed)
			(footprints allowed)
		)
		(placement
			(enabled no)
			(sheetname "")
		)
		(fill yes
			(thermal_gap 0.5)
			(thermal_bridge_width 0.5)
			(island_removal_mode 0)
		)
		(polygon
			(pts
				(arc
					(start 343.46007 -233.34218)
					(mid 342.80729 -233.34218)
					(end 343.46007 -233.34218)
				)
			)
		)
	)
	(zone
		(layers "B.Cu" "In11.Cu" "In13.Cu" "In15.Cu")
		(hatch none 0.5)
		(connect_pads
			(clearance 0)
		)
		(min_thickness 0.25)
		(keepout
			(tracks not_allowed)
			(vias allowed)
			(pads allowed)
			(copperpour not_allowed)
			(footprints allowed)
		)
		(placement
			(enabled no)
			(sheetname "")
		)
		(fill yes
			(thermal_gap 0.5)
			(thermal_bridge_width 0.5)
			(island_removal_mode 0)
		)
		(polygon
			(pts
				(arc
					(start 411.15488 -430.889918)
					(mid 410.345128 -430.889918)
					(end 411.15488 -430.889918)
				)
			)
		)
	)
	(zone
		(layers "B.Cu" "In11.Cu" "In13.Cu" "In15.Cu")
		(hatch none 0.5)
		(connect_pads
			(clearance 0)
		)
		(min_thickness 0.25)
		(keepout
			(tracks not_allowed)
			(vias allowed)
			(pads allowed)
			(copperpour not_allowed)
			(footprints allowed)
		)
		(placement
			(enabled no)
			(sheetname "")
		)
		(fill yes
			(thermal_gap 0.5)
			(thermal_bridge_width 0.5)
			(island_removal_mode 0)
		)
		(polygon
			(pts
				(arc
					(start 230.84917 -58.306716)
					(mid 230.14559 -58.306716)
					(end 230.84917 -58.306716)
				)
			)
		)
	)
	(zone
		(layers "B.Cu" "In11.Cu" "In13.Cu" "In15.Cu")
		(hatch none 0.5)
		(connect_pads
			(clearance 0)
		)
		(min_thickness 0.25)
		(keepout
			(tracks not_allowed)
			(vias allowed)
			(pads allowed)
			(copperpour not_allowed)
			(footprints allowed)
		)
		(placement
			(enabled no)
			(sheetname "")
		)
		(fill yes
			(thermal_gap 0.5)
			(thermal_bridge_width 0.5)
			(island_removal_mode 0)
		)
		(polygon
			(pts
				(arc
					(start 97.039938 -266.941808)
					(mid 96.387158 -266.941808)
					(end 97.039938 -266.941808)
				)
			)
		)
	)
	(zone
		(layers "B.Cu" "In11.Cu" "In13.Cu" "In15.Cu")
		(hatch none 0.5)
		(connect_pads
			(clearance 0)
		)
		(min_thickness 0.25)
		(keepout
			(tracks not_allowed)
			(vias allowed)
			(pads allowed)
			(copperpour not_allowed)
			(footprints allowed)
		)
		(placement
			(enabled no)
			(sheetname "")
		)
		(fill yes
			(thermal_gap 0.5)
			(thermal_bridge_width 0.5)
			(island_removal_mode 0)
		)
		(polygon
			(pts
				(arc
					(start 352.227642 -186.714892)
					(mid 351.524062 -186.714892)
					(end 352.227642 -186.714892)
				)
			)
		)
	)
	(zone
		(layers "B.Cu" "In11.Cu" "In13.Cu" "In15.Cu")
		(hatch none 0.5)
		(connect_pads
			(clearance 0)
		)
		(min_thickness 0.25)
		(keepout
			(tracks not_allowed)
			(vias allowed)
			(pads allowed)
			(copperpour not_allowed)
			(footprints allowed)
		)
		(placement
			(enabled no)
			(sheetname "")
		)
		(fill yes
			(thermal_gap 0.5)
			(thermal_bridge_width 0.5)
			(island_removal_mode 0)
		)
		(polygon
			(pts
				(arc
					(start 95.520002 -233.34218)
					(mid 94.867222 -233.34218)
					(end 95.520002 -233.34218)
				)
			)
		)
	)
	(zone
		(layers "B.Cu" "In11.Cu" "In13.Cu" "In15.Cu")
		(hatch none 0.5)
		(connect_pads
			(clearance 0)
		)
		(min_thickness 0.25)
		(keepout
			(tracks not_allowed)
			(vias allowed)
			(pads allowed)
			(copperpour not_allowed)
			(footprints allowed)
		)
		(placement
			(enabled no)
			(sheetname "")
		)
		(fill yes
			(thermal_gap 0.5)
			(thermal_bridge_width 0.5)
			(island_removal_mode 0)
		)
		(polygon
			(pts
				(arc
					(start 345.442286 -72.299576)
					(mid 344.738706 -72.299576)
					(end 345.442286 -72.299576)
				)
			)
		)
	)
	(zone
		(layers "B.Cu" "In11.Cu" "In13.Cu" "In15.Cu")
		(hatch none 0.5)
		(connect_pads
			(clearance 0)
		)
		(min_thickness 0.25)
		(keepout
			(tracks not_allowed)
			(vias allowed)
			(pads allowed)
			(copperpour not_allowed)
			(footprints allowed)
		)
		(placement
			(enabled no)
			(sheetname "")
		)
		(fill yes
			(thermal_gap 0.5)
			(thermal_bridge_width 0.5)
			(island_removal_mode 0)
		)
		(polygon
			(pts
				(arc
					(start 455.337672 -206.666592)
					(mid 454.684892 -206.666592)
					(end 455.337672 -206.666592)
				)
			)
		)
	)
	(zone
		(layers "B.Cu" "In11.Cu" "In13.Cu" "In15.Cu")
		(hatch none 0.5)
		(connect_pads
			(clearance 0)
		)
		(min_thickness 0.25)
		(keepout
			(tracks not_allowed)
			(vias allowed)
			(pads allowed)
			(copperpour not_allowed)
			(footprints allowed)
		)
		(placement
			(enabled no)
			(sheetname "")
		)
		(fill yes
			(thermal_gap 0.5)
			(thermal_bridge_width 0.5)
			(island_removal_mode 0)
		)
		(polygon
			(pts
				(arc
					(start 338.05495 -435.489858)
					(mid 337.245198 -435.489858)
					(end 338.05495 -435.489858)
				)
			)
		)
	)
	(zone
		(layers "B.Cu" "In11.Cu" "In13.Cu" "In15.Cu")
		(hatch none 0.5)
		(connect_pads
			(clearance 0)
		)
		(min_thickness 0.25)
		(keepout
			(tracks not_allowed)
			(vias allowed)
			(pads allowed)
			(copperpour not_allowed)
			(footprints allowed)
		)
		(placement
			(enabled no)
			(sheetname "")
		)
		(fill yes
			(thermal_gap 0.5)
			(thermal_bridge_width 0.5)
			(island_removal_mode 0)
		)
		(polygon
			(pts
				(arc
					(start 382.154938 -429.689768)
					(mid 381.345186 -429.689768)
					(end 382.154938 -429.689768)
				)
			)
		)
	)
	(zone
		(layers "B.Cu" "In11.Cu" "In13.Cu" "In15.Cu")
		(hatch none 0.5)
		(connect_pads
			(clearance 0)
		)
		(min_thickness 0.25)
		(keepout
			(tracks not_allowed)
			(vias allowed)
			(pads allowed)
			(copperpour not_allowed)
			(footprints allowed)
		)
		(placement
			(enabled no)
			(sheetname "")
		)
		(fill yes
			(thermal_gap 0.5)
			(thermal_bridge_width 0.5)
			(island_removal_mode 0)
		)
		(polygon
			(pts
				(arc
					(start 348.159324 -213.732618)
					(mid 347.506544 -213.732618)
					(end 348.159324 -213.732618)
				)
			)
		)
	)
	(zone
		(layers "B.Cu" "In11.Cu" "In13.Cu" "In15.Cu")
		(hatch none 0.5)
		(connect_pads
			(clearance 0)
		)
		(min_thickness 0.25)
		(keepout
			(tracks not_allowed)
			(vias allowed)
			(pads allowed)
			(copperpour not_allowed)
			(footprints allowed)
		)
		(placement
			(enabled no)
			(sheetname "")
		)
		(fill yes
			(thermal_gap 0.5)
			(thermal_bridge_width 0.5)
			(island_removal_mode 0)
		)
		(polygon
			(pts
				(arc
					(start 284.243272 -199.01662)
					(mid 283.590492 -199.01662)
					(end 284.243272 -199.01662)
				)
			)
		)
	)
	(zone
		(layers "B.Cu" "In11.Cu" "In13.Cu" "In15.Cu")
		(hatch none 0.5)
		(connect_pads
			(clearance 0)
		)
		(min_thickness 0.25)
		(keepout
			(tracks not_allowed)
			(vias allowed)
			(pads allowed)
			(copperpour not_allowed)
			(footprints allowed)
		)
		(placement
			(enabled no)
			(sheetname "")
		)
		(fill yes
			(thermal_gap 0.5)
			(thermal_bridge_width 0.5)
			(island_removal_mode 0)
		)
		(polygon
			(pts
				(arc
					(start 341.58047 -215.436704)
					(mid 340.92769 -215.436704)
					(end 341.58047 -215.436704)
				)
			)
		)
	)
	(zone
		(layers "B.Cu" "In11.Cu" "In13.Cu" "In15.Cu")
		(hatch none 0.5)
		(connect_pads
			(clearance 0)
		)
		(min_thickness 0.25)
		(keepout
			(tracks not_allowed)
			(vias allowed)
			(pads allowed)
			(copperpour not_allowed)
			(footprints allowed)
		)
		(placement
			(enabled no)
			(sheetname "")
		)
		(fill yes
			(thermal_gap 0.5)
			(thermal_bridge_width 0.5)
			(island_removal_mode 0)
		)
		(polygon
			(pts
				(arc
					(start 95.629984 -282.405836)
					(mid 94.977204 -282.405836)
					(end 95.629984 -282.405836)
				)
			)
		)
	)
	(zone
		(layers "B.Cu" "In11.Cu" "In13.Cu" "In15.Cu")
		(hatch none 0.5)
		(connect_pads
			(clearance 0)
		)
		(min_thickness 0.25)
		(keepout
			(tracks not_allowed)
			(vias allowed)
			(pads allowed)
			(copperpour not_allowed)
			(footprints allowed)
		)
		(placement
			(enabled no)
			(sheetname "")
		)
		(fill yes
			(thermal_gap 0.5)
			(thermal_bridge_width 0.5)
			(island_removal_mode 0)
		)
		(polygon
			(pts
				(arc
					(start 36.303204 -270.416782)
					(mid 35.650424 -270.416782)
					(end 36.303204 -270.416782)
				)
			)
		)
	)
	(zone
		(layers "B.Cu" "In11.Cu" "In13.Cu" "In15.Cu")
		(hatch none 0.5)
		(connect_pads
			(clearance 0)
		)
		(min_thickness 0.25)
		(keepout
			(tracks not_allowed)
			(vias allowed)
			(pads allowed)
			(copperpour not_allowed)
			(footprints allowed)
		)
		(placement
			(enabled no)
			(sheetname "")
		)
		(fill yes
			(thermal_gap 0.5)
			(thermal_bridge_width 0.5)
			(island_removal_mode 0)
		)
		(polygon
			(pts
				(arc
					(start 349.517462 -179.757832)
					(mid 348.813882 -179.757832)
					(end 349.517462 -179.757832)
				)
			)
		)
	)
	(zone
		(layers "B.Cu" "In11.Cu" "In13.Cu" "In15.Cu")
		(hatch none 0.5)
		(connect_pads
			(clearance 0)
		)
		(min_thickness 0.25)
		(keepout
			(tracks not_allowed)
			(vias allowed)
			(pads allowed)
			(copperpour not_allowed)
			(footprints allowed)
		)
		(placement
			(enabled no)
			(sheetname "")
		)
		(fill yes
			(thermal_gap 0.5)
			(thermal_bridge_width 0.5)
			(island_removal_mode 0)
		)
		(polygon
			(pts
				(arc
					(start 336.521552 -286.475424)
					(mid 335.868772 -286.475424)
					(end 336.521552 -286.475424)
				)
			)
		)
	)
	(zone
		(layers "B.Cu" "In11.Cu" "In13.Cu" "In15.Cu")
		(hatch none 0.5)
		(connect_pads
			(clearance 0)
		)
		(min_thickness 0.25)
		(keepout
			(tracks not_allowed)
			(vias allowed)
			(pads allowed)
			(copperpour not_allowed)
			(footprints allowed)
		)
		(placement
			(enabled no)
			(sheetname "")
		)
		(fill yes
			(thermal_gap 0.5)
			(thermal_bridge_width 0.5)
			(island_removal_mode 0)
		)
		(polygon
			(pts
				(arc
					(start 350.508824 -247.178322)
					(mid 349.856044 -247.178322)
					(end 350.508824 -247.178322)
				)
			)
		)
	)
	(zone
		(layers "B.Cu" "In11.Cu" "In13.Cu" "In15.Cu")
		(hatch none 0.5)
		(connect_pads
			(clearance 0)
		)
		(min_thickness 0.25)
		(keepout
			(tracks not_allowed)
			(vias allowed)
			(pads allowed)
			(copperpour not_allowed)
			(footprints allowed)
		)
		(placement
			(enabled no)
			(sheetname "")
		)
		(fill yes
			(thermal_gap 0.5)
			(thermal_bridge_width 0.5)
			(island_removal_mode 0)
		)
		(polygon
			(pts
				(arc
					(start 140.154914 -437.889904)
					(mid 139.345162 -437.889904)
					(end 140.154914 -437.889904)
				)
			)
		)
	)
	(zone
		(layers "B.Cu" "In11.Cu" "In13.Cu" "In15.Cu")
		(hatch none 0.5)
		(connect_pads
			(clearance 0)
		)
		(min_thickness 0.25)
		(keepout
			(tracks not_allowed)
			(vias allowed)
			(pads allowed)
			(copperpour not_allowed)
			(footprints allowed)
		)
		(placement
			(enabled no)
			(sheetname "")
		)
		(fill yes
			(thermal_gap 0.5)
			(thermal_bridge_width 0.5)
			(island_removal_mode 0)
		)
		(polygon
			(pts
				(arc
					(start 95.989648 -214.622634)
					(mid 95.336868 -214.622634)
					(end 95.989648 -214.622634)
				)
			)
		)
	)
	(zone
		(layers "B.Cu" "In11.Cu" "In13.Cu" "In15.Cu")
		(hatch none 0.5)
		(connect_pads
			(clearance 0)
		)
		(min_thickness 0.25)
		(keepout
			(tracks not_allowed)
			(vias allowed)
			(pads allowed)
			(copperpour not_allowed)
			(footprints allowed)
		)
		(placement
			(enabled no)
			(sheetname "")
		)
		(fill yes
			(thermal_gap 0.5)
			(thermal_bridge_width 0.5)
			(island_removal_mode 0)
		)
		(polygon
			(pts
				(arc
					(start 192.310004 -217.716608)
					(mid 191.657224 -217.716608)
					(end 192.310004 -217.716608)
				)
			)
		)
	)
	(zone
		(layers "B.Cu" "In11.Cu" "In13.Cu" "In15.Cu")
		(hatch none 0.5)
		(connect_pads
			(clearance 0)
		)
		(min_thickness 0.25)
		(keepout
			(tracks not_allowed)
			(vias allowed)
			(pads allowed)
			(copperpour not_allowed)
			(footprints allowed)
		)
		(placement
			(enabled no)
			(sheetname "")
		)
		(fill yes
			(thermal_gap 0.5)
			(thermal_bridge_width 0.5)
			(island_removal_mode 0)
		)
		(polygon
			(pts
				(arc
					(start 95.629984 -264.50036)
					(mid 94.977204 -264.50036)
					(end 95.629984 -264.50036)
				)
			)
		)
	)
	(zone
		(layers "B.Cu" "In11.Cu" "In13.Cu" "In15.Cu")
		(hatch none 0.5)
		(connect_pads
			(clearance 0)
		)
		(min_thickness 0.25)
		(keepout
			(tracks not_allowed)
			(vias allowed)
			(pads allowed)
			(copperpour not_allowed)
			(footprints allowed)
		)
		(placement
			(enabled no)
			(sheetname "")
		)
		(fill yes
			(thermal_gap 0.5)
			(thermal_bridge_width 0.5)
			(island_removal_mode 0)
		)
		(polygon
			(pts
				(arc
					(start 376.823224 -230.900478)
					(mid 376.170444 -230.900478)
					(end 376.823224 -230.900478)
				)
			)
		)
	)
	(zone
		(layers "B.Cu" "In11.Cu" "In13.Cu" "In15.Cu")
		(hatch none 0.5)
		(connect_pads
			(clearance 0)
		)
		(min_thickness 0.25)
		(keepout
			(tracks not_allowed)
			(vias allowed)
			(pads allowed)
			(copperpour not_allowed)
			(footprints allowed)
		)
		(placement
			(enabled no)
			(sheetname "")
		)
		(fill yes
			(thermal_gap 0.5)
			(thermal_bridge_width 0.5)
			(island_removal_mode 0)
		)
		(polygon
			(pts
				(arc
					(start 399.154904 -429.689768)
					(mid 398.345152 -429.689768)
					(end 399.154904 -429.689768)
				)
			)
		)
	)
	(zone
		(layers "B.Cu" "In11.Cu" "In13.Cu" "In15.Cu")
		(hatch none 0.5)
		(connect_pads
			(clearance 0)
		)
		(min_thickness 0.25)
		(keepout
			(tracks not_allowed)
			(vias allowed)
			(pads allowed)
			(copperpour not_allowed)
			(footprints allowed)
		)
		(placement
			(enabled no)
			(sheetname "")
		)
		(fill yes
			(thermal_gap 0.5)
			(thermal_bridge_width 0.5)
			(island_removal_mode 0)
		)
		(polygon
			(pts
				(arc
					(start 97.039938 -271.825212)
					(mid 96.387158 -271.825212)
					(end 97.039938 -271.825212)
				)
			)
		)
	)
	(zone
		(layers "B.Cu" "In11.Cu" "In13.Cu" "In15.Cu")
		(hatch none 0.5)
		(connect_pads
			(clearance 0)
		)
		(min_thickness 0.25)
		(keepout
			(tracks not_allowed)
			(vias allowed)
			(pads allowed)
			(copperpour not_allowed)
			(footprints allowed)
		)
		(placement
			(enabled no)
			(sheetname "")
		)
		(fill yes
			(thermal_gap 0.5)
			(thermal_bridge_width 0.5)
			(island_removal_mode 0)
		)
		(polygon
			(pts
				(arc
					(start 428.580804 -243.216684)
					(mid 427.928024 -243.216684)
					(end 428.580804 -243.216684)
				)
			)
		)
	)
	(zone
		(layers "B.Cu" "In11.Cu" "In13.Cu" "In15.Cu")
		(hatch none 0.5)
		(connect_pads
			(clearance 0)
		)
		(min_thickness 0.25)
		(keepout
			(tracks not_allowed)
			(vias allowed)
			(pads allowed)
			(copperpour not_allowed)
			(footprints allowed)
		)
		(placement
			(enabled no)
			(sheetname "")
		)
		(fill yes
			(thermal_gap 0.5)
			(thermal_bridge_width 0.5)
			(island_removal_mode 0)
		)
		(polygon
			(pts
				(arc
					(start 97.039938 -270.19758)
					(mid 96.387158 -270.19758)
					(end 97.039938 -270.19758)
				)
			)
		)
	)
	(zone
		(layers "B.Cu" "In11.Cu" "In13.Cu" "In15.Cu")
		(hatch none 0.5)
		(connect_pads
			(clearance 0)
		)
		(min_thickness 0.25)
		(keepout
			(tracks not_allowed)
			(vias allowed)
			(pads allowed)
			(copperpour not_allowed)
			(footprints allowed)
		)
		(placement
			(enabled no)
			(sheetname "")
		)
		(fill yes
			(thermal_gap 0.5)
			(thermal_bridge_width 0.5)
			(island_removal_mode 0)
		)
		(polygon
			(pts
				(arc
					(start 160.38195 -47.943008)
					(mid 159.67837 -47.943008)
					(end 160.38195 -47.943008)
				)
			)
		)
	)
	(zone
		(layers "B.Cu" "In11.Cu" "In13.Cu" "In15.Cu")
		(hatch none 0.5)
		(connect_pads
			(clearance 0)
		)
		(min_thickness 0.25)
		(keepout
			(tracks not_allowed)
			(vias allowed)
			(pads allowed)
			(copperpour not_allowed)
			(footprints allowed)
		)
		(placement
			(enabled no)
			(sheetname "")
		)
		(fill yes
			(thermal_gap 0.5)
			(thermal_bridge_width 0.5)
			(island_removal_mode 0)
		)
		(polygon
			(pts
				(arc
					(start 340.054946 -426.089826)
					(mid 339.245194 -426.089826)
					(end 340.054946 -426.089826)
				)
			)
		)
	)
	(zone
		(layers "B.Cu" "In11.Cu" "In13.Cu" "In15.Cu")
		(hatch none 0.5)
		(connect_pads
			(clearance 0)
		)
		(min_thickness 0.25)
		(keepout
			(tracks not_allowed)
			(vias allowed)
			(pads allowed)
			(copperpour not_allowed)
			(footprints allowed)
		)
		(placement
			(enabled no)
			(sheetname "")
		)
		(fill yes
			(thermal_gap 0.5)
			(thermal_bridge_width 0.5)
			(island_removal_mode 0)
		)
		(polygon
			(pts
				(arc
					(start 128.522984 -264.50036)
					(mid 127.870204 -264.50036)
					(end 128.522984 -264.50036)
				)
			)
		)
	)
	(zone
		(layers "B.Cu" "In11.Cu" "In13.Cu" "In15.Cu")
		(hatch none 0.5)
		(connect_pads
			(clearance 0)
		)
		(min_thickness 0.25)
		(keepout
			(tracks not_allowed)
			(vias allowed)
			(pads allowed)
			(copperpour not_allowed)
			(footprints allowed)
		)
		(placement
			(enabled no)
			(sheetname "")
		)
		(fill yes
			(thermal_gap 0.5)
			(thermal_bridge_width 0.5)
			(island_removal_mode 0)
		)
		(polygon
			(pts
				(arc
					(start 284.243272 -216.016586)
					(mid 283.590492 -216.016586)
					(end 284.243272 -216.016586)
				)
			)
		)
	)
	(zone
		(layers "B.Cu" "In11.Cu" "In13.Cu" "In15.Cu")
		(hatch none 0.5)
		(connect_pads
			(clearance 0)
		)
		(min_thickness 0.25)
		(keepout
			(tracks not_allowed)
			(vias allowed)
			(pads allowed)
			(copperpour not_allowed)
			(footprints allowed)
		)
		(placement
			(enabled no)
			(sheetname "")
		)
		(fill yes
			(thermal_gap 0.5)
			(thermal_bridge_width 0.5)
			(island_removal_mode 0)
		)
		(polygon
			(pts
				(arc
					(start 390.154922 -438.089802)
					(mid 389.34517 -438.089802)
					(end 390.154922 -438.089802)
				)
			)
		)
	)
	(zone
		(layers "B.Cu" "In11.Cu" "In13.Cu" "In15.Cu")
		(hatch none 0.5)
		(connect_pads
			(clearance 0)
		)
		(min_thickness 0.25)
		(keepout
			(tracks not_allowed)
			(vias allowed)
			(pads allowed)
			(copperpour not_allowed)
			(footprints allowed)
		)
		(placement
			(enabled no)
			(sheetname "")
		)
		(fill yes
			(thermal_gap 0.5)
			(thermal_bridge_width 0.5)
			(island_removal_mode 0)
		)
		(polygon
			(pts
				(arc
					(start 373.446294 -185.011568)
					(mid 372.742714 -185.011568)
					(end 373.446294 -185.011568)
				)
			)
		)
	)
	(zone
		(layers "B.Cu" "In11.Cu" "In13.Cu" "In15.Cu")
		(hatch none 0.5)
		(connect_pads
			(clearance 0)
		)
		(min_thickness 0.25)
		(keepout
			(tracks not_allowed)
			(vias allowed)
			(pads allowed)
			(copperpour not_allowed)
			(footprints allowed)
		)
		(placement
			(enabled no)
			(sheetname "")
		)
		(fill yes
			(thermal_gap 0.5)
			(thermal_bridge_width 0.5)
			(island_removal_mode 0)
		)
		(polygon
			(pts
				(arc
					(start 56.667908 -410.030168)
					(mid 55.964328 -410.030168)
					(end 56.667908 -410.030168)
				)
			)
		)
	)
	(zone
		(layers "B.Cu" "In11.Cu" "In13.Cu" "In15.Cu")
		(hatch none 0.5)
		(connect_pads
			(clearance 0)
		)
		(min_thickness 0.25)
		(keepout
			(tracks not_allowed)
			(vias allowed)
			(pads allowed)
			(copperpour not_allowed)
			(footprints allowed)
		)
		(placement
			(enabled no)
			(sheetname "")
		)
		(fill yes
			(thermal_gap 0.5)
			(thermal_bridge_width 0.5)
			(island_removal_mode 0)
		)
		(polygon
			(pts
				(arc
					(start 67.054984 -426.089826)
					(mid 66.245232 -426.089826)
					(end 67.054984 -426.089826)
				)
			)
		)
	)
	(zone
		(layers "B.Cu" "In11.Cu" "In13.Cu" "In15.Cu")
		(hatch none 0.5)
		(connect_pads
			(clearance 0)
		)
		(min_thickness 0.25)
		(keepout
			(tracks not_allowed)
			(vias allowed)
			(pads allowed)
			(copperpour not_allowed)
			(footprints allowed)
		)
		(placement
			(enabled no)
			(sheetname "")
		)
		(fill yes
			(thermal_gap 0.5)
			(thermal_bridge_width 0.5)
			(island_removal_mode 0)
		)
		(polygon
			(pts
				(arc
					(start 284.243272 -306.116736)
					(mid 283.590492 -306.116736)
					(end 284.243272 -306.116736)
				)
			)
		)
	)
	(zone
		(layers "B.Cu" "In11.Cu" "In13.Cu" "In15.Cu")
		(hatch none 0.5)
		(connect_pads
			(clearance 0)
		)
		(min_thickness 0.25)
		(keepout
			(tracks not_allowed)
			(vias allowed)
			(pads allowed)
			(copperpour not_allowed)
			(footprints allowed)
		)
		(placement
			(enabled no)
			(sheetname "")
		)
		(fill yes
			(thermal_gap 0.5)
			(thermal_bridge_width 0.5)
			(island_removal_mode 0)
		)
		(polygon
			(pts
				(arc
					(start 388.154926 -430.689766)
					(mid 387.345174 -430.689766)
					(end 388.154926 -430.689766)
				)
			)
		)
	)
	(zone
		(layers "B.Cu" "In11.Cu" "In13.Cu" "In15.Cu")
		(hatch none 0.5)
		(connect_pads
			(clearance 0)
		)
		(min_thickness 0.25)
		(keepout
			(tracks not_allowed)
			(vias allowed)
			(pads allowed)
			(copperpour not_allowed)
			(footprints allowed)
		)
		(placement
			(enabled no)
			(sheetname "")
		)
		(fill yes
			(thermal_gap 0.5)
			(thermal_bridge_width 0.5)
			(island_removal_mode 0)
		)
		(polygon
			(pts
				(arc
					(start 32.203136 -280.61666)
					(mid 31.550356 -280.61666)
					(end 32.203136 -280.61666)
				)
			)
		)
	)
	(zone
		(layers "B.Cu" "In11.Cu" "In13.Cu" "In15.Cu")
		(hatch none 0.5)
		(connect_pads
			(clearance 0)
		)
		(min_thickness 0.25)
		(keepout
			(tracks not_allowed)
			(vias allowed)
			(pads allowed)
			(copperpour not_allowed)
			(footprints allowed)
		)
		(placement
			(enabled no)
			(sheetname "")
		)
		(fill yes
			(thermal_gap 0.5)
			(thermal_bridge_width 0.5)
			(island_removal_mode 0)
		)
		(polygon
			(pts
				(arc
					(start 127.113538 -263.686544)
					(mid 126.460758 -263.686544)
					(end 127.113538 -263.686544)
				)
			)
		)
	)
	(zone
		(layers "B.Cu" "In11.Cu" "In13.Cu" "In15.Cu")
		(hatch none 0.5)
		(connect_pads
			(clearance 0)
		)
		(min_thickness 0.25)
		(keepout
			(tracks not_allowed)
			(vias allowed)
			(pads allowed)
			(copperpour not_allowed)
			(footprints allowed)
		)
		(placement
			(enabled no)
			(sheetname "")
		)
		(fill yes
			(thermal_gap 0.5)
			(thermal_bridge_width 0.5)
			(island_removal_mode 0)
		)
		(polygon
			(pts
				(arc
					(start 126.063248 -214.622634)
					(mid 125.410468 -214.622634)
					(end 126.063248 -214.622634)
				)
			)
		)
	)
	(zone
		(layers "B.Cu" "In11.Cu" "In13.Cu" "In15.Cu")
		(hatch none 0.5)
		(connect_pads
			(clearance 0)
		)
		(min_thickness 0.25)
		(keepout
			(tracks not_allowed)
			(vias allowed)
			(pads allowed)
			(copperpour not_allowed)
			(footprints allowed)
		)
		(placement
			(enabled no)
			(sheetname "")
		)
		(fill yes
			(thermal_gap 0.5)
			(thermal_bridge_width 0.5)
			(island_removal_mode 0)
		)
		(polygon
			(pts
				(arc
					(start 327.054972 -427.289976)
					(mid 326.24522 -427.289976)
					(end 327.054972 -427.289976)
				)
			)
		)
	)
	(zone
		(layers "B.Cu" "In11.Cu" "In13.Cu" "In15.Cu")
		(hatch none 0.5)
		(connect_pads
			(clearance 0)
		)
		(min_thickness 0.25)
		(keepout
			(tracks not_allowed)
			(vias allowed)
			(pads allowed)
			(copperpour not_allowed)
			(footprints allowed)
		)
		(placement
			(enabled no)
			(sheetname "")
		)
		(fill yes
			(thermal_gap 0.5)
			(thermal_bridge_width 0.5)
			(island_removal_mode 0)
		)
		(polygon
			(pts
				(arc
					(start 203.297536 -211.766658)
					(mid 202.644756 -211.766658)
					(end 203.297536 -211.766658)
				)
			)
		)
	)
	(zone
		(layers "B.Cu" "In11.Cu" "In13.Cu" "In15.Cu")
		(hatch none 0.5)
		(connect_pads
			(clearance 0)
		)
		(min_thickness 0.25)
		(keepout
			(tracks not_allowed)
			(vias allowed)
			(pads allowed)
			(copperpour not_allowed)
			(footprints allowed)
		)
		(placement
			(enabled no)
			(sheetname "")
		)
		(fill yes
			(thermal_gap 0.5)
			(thermal_bridge_width 0.5)
			(island_removal_mode 0)
		)
		(polygon
			(pts
				(arc
					(start 59.055 -427.289976)
					(mid 58.245248 -427.289976)
					(end 59.055 -427.289976)
				)
			)
		)
	)
	(zone
		(layers "B.Cu" "In11.Cu" "In13.Cu" "In15.Cu")
		(hatch none 0.5)
		(connect_pads
			(clearance 0)
		)
		(min_thickness 0.25)
		(keepout
			(tracks not_allowed)
			(vias allowed)
			(pads allowed)
			(copperpour not_allowed)
			(footprints allowed)
		)
		(placement
			(enabled no)
			(sheetname "")
		)
		(fill yes
			(thermal_gap 0.5)
			(thermal_bridge_width 0.5)
			(island_removal_mode 0)
		)
		(polygon
			(pts
				(arc
					(start 342.050116 -214.622634)
					(mid 341.397336 -214.622634)
					(end 342.050116 -214.622634)
				)
			)
		)
	)
	(zone
		(layers "B.Cu" "In11.Cu" "In13.Cu" "In15.Cu")
		(hatch none 0.5)
		(connect_pads
			(clearance 0)
		)
		(min_thickness 0.25)
		(keepout
			(tracks not_allowed)
			(vias allowed)
			(pads allowed)
			(copperpour not_allowed)
			(footprints allowed)
		)
		(placement
			(enabled no)
			(sheetname "")
		)
		(fill yes
			(thermal_gap 0.5)
			(thermal_bridge_width 0.5)
			(island_removal_mode 0)
		)
		(polygon
			(pts
				(arc
					(start 129.352802 -239.853216)
					(mid 128.700022 -239.853216)
					(end 129.352802 -239.853216)
				)
			)
		)
	)
	(zone
		(layers "B.Cu" "In11.Cu" "In13.Cu" "In15.Cu")
		(hatch none 0.5)
		(connect_pads
			(clearance 0)
		)
		(min_thickness 0.25)
		(keepout
			(tracks not_allowed)
			(vias allowed)
			(pads allowed)
			(copperpour not_allowed)
			(footprints allowed)
		)
		(placement
			(enabled no)
			(sheetname "")
		)
		(fill yes
			(thermal_gap 0.5)
			(thermal_bridge_width 0.5)
			(island_removal_mode 0)
		)
		(polygon
			(pts
				(arc
					(start 440.250072 -231.316784)
					(mid 439.597292 -231.316784)
					(end 440.250072 -231.316784)
				)
			)
		)
	)
	(zone
		(layers "B.Cu" "In11.Cu" "In13.Cu" "In15.Cu")
		(hatch none 0.5)
		(connect_pads
			(clearance 0)
		)
		(min_thickness 0.25)
		(keepout
			(tracks not_allowed)
			(vias allowed)
			(pads allowed)
			(copperpour not_allowed)
			(footprints allowed)
		)
		(placement
			(enabled no)
			(sheetname "")
		)
		(fill yes
			(thermal_gap 0.5)
			(thermal_bridge_width 0.5)
			(island_removal_mode 0)
		)
		(polygon
			(pts
				(arc
					(start 348.080838 -403.883876)
					(mid 347.377258 -403.883876)
					(end 348.080838 -403.883876)
				)
			)
		)
	)
	(zone
		(layers "B.Cu" "In11.Cu" "In13.Cu" "In15.Cu")
		(hatch none 0.5)
		(connect_pads
			(clearance 0)
		)
		(min_thickness 0.25)
		(keepout
			(tracks not_allowed)
			(vias allowed)
			(pads allowed)
			(copperpour not_allowed)
			(footprints allowed)
		)
		(placement
			(enabled no)
			(sheetname "")
		)
		(fill yes
			(thermal_gap 0.5)
			(thermal_bridge_width 0.5)
			(island_removal_mode 0)
		)
		(polygon
			(pts
				(arc
					(start 407.154888 -430.889918)
					(mid 406.345136 -430.889918)
					(end 407.154888 -430.889918)
				)
			)
		)
	)
	(zone
		(layers "B.Cu" "In11.Cu" "In13.Cu" "In15.Cu")
		(hatch none 0.5)
		(connect_pads
			(clearance 0)
		)
		(min_thickness 0.25)
		(keepout
			(tracks not_allowed)
			(vias allowed)
			(pads allowed)
			(copperpour not_allowed)
			(footprints allowed)
		)
		(placement
			(enabled no)
			(sheetname "")
		)
		(fill yes
			(thermal_gap 0.5)
			(thermal_bridge_width 0.5)
			(island_removal_mode 0)
		)
		(polygon
			(pts
				(arc
					(start 346.279724 -213.732618)
					(mid 345.626944 -213.732618)
					(end 346.279724 -213.732618)
				)
			)
		)
	)
	(zone
		(layers "B.Cu" "In11.Cu" "In13.Cu" "In15.Cu")
		(hatch none 0.5)
		(connect_pads
			(clearance 0)
		)
		(min_thickness 0.25)
		(keepout
			(tracks not_allowed)
			(vias allowed)
			(pads allowed)
			(copperpour not_allowed)
			(footprints allowed)
		)
		(placement
			(enabled no)
			(sheetname "")
		)
		(fill yes
			(thermal_gap 0.5)
			(thermal_bridge_width 0.5)
			(island_removal_mode 0)
		)
		(polygon
			(pts
				(arc
					(start 32.203136 -199.866758)
					(mid 31.550356 -199.866758)
					(end 32.203136 -199.866758)
				)
			)
		)
	)
	(zone
		(layers "B.Cu" "In11.Cu" "In13.Cu" "In15.Cu")
		(hatch none 0.5)
		(connect_pads
			(clearance 0)
		)
		(min_thickness 0.25)
		(keepout
			(tracks not_allowed)
			(vias allowed)
			(pads allowed)
			(copperpour not_allowed)
			(footprints allowed)
		)
		(placement
			(enabled no)
			(sheetname "")
		)
		(fill yes
			(thermal_gap 0.5)
			(thermal_bridge_width 0.5)
			(island_removal_mode 0)
		)
		(polygon
			(pts
				(arc
					(start 151.154892 -429.689768)
					(mid 150.34514 -429.689768)
					(end 151.154892 -429.689768)
				)
			)
		)
	)
	(zone
		(layers "B.Cu" "In11.Cu" "In13.Cu" "In15.Cu")
		(hatch none 0.5)
		(connect_pads
			(clearance 0)
		)
		(min_thickness 0.25)
		(keepout
			(tracks not_allowed)
			(vias allowed)
			(pads allowed)
			(copperpour not_allowed)
			(footprints allowed)
		)
		(placement
			(enabled no)
			(sheetname "")
		)
		(fill yes
			(thermal_gap 0.5)
			(thermal_bridge_width 0.5)
			(island_removal_mode 0)
		)
		(polygon
			(pts
				(arc
					(start 124.183648 -214.622634)
					(mid 123.530868 -214.622634)
					(end 124.183648 -214.622634)
				)
			)
		)
	)
	(zone
		(layers "B.Cu" "In11.Cu" "In13.Cu" "In15.Cu")
		(hatch none 0.5)
		(connect_pads
			(clearance 0)
		)
		(min_thickness 0.25)
		(keepout
			(tracks not_allowed)
			(vias allowed)
			(pads allowed)
			(copperpour not_allowed)
			(footprints allowed)
		)
		(placement
			(enabled no)
			(sheetname "")
		)
		(fill yes
			(thermal_gap 0.5)
			(thermal_bridge_width 0.5)
			(island_removal_mode 0)
		)
		(polygon
			(pts
				(arc
					(start 343.929716 -214.622634)
					(mid 343.276936 -214.622634)
					(end 343.929716 -214.622634)
				)
			)
		)
	)
	(zone
		(layers "B.Cu" "In11.Cu" "In13.Cu" "In15.Cu")
		(hatch none 0.5)
		(connect_pads
			(clearance 0)
		)
		(min_thickness 0.25)
		(keepout
			(tracks not_allowed)
			(vias allowed)
			(pads allowed)
			(copperpour not_allowed)
			(footprints allowed)
		)
		(placement
			(enabled no)
			(sheetname "")
		)
		(fill yes
			(thermal_gap 0.5)
			(thermal_bridge_width 0.5)
			(island_removal_mode 0)
		)
		(polygon
			(pts
				(arc
					(start 95.990156 -235.783882)
					(mid 95.337376 -235.783882)
					(end 95.990156 -235.783882)
				)
			)
		)
	)
	(zone
		(layers "B.Cu" "In11.Cu" "In13.Cu" "In15.Cu")
		(hatch none 0.5)
		(connect_pads
			(clearance 0)
		)
		(min_thickness 0.25)
		(keepout
			(tracks not_allowed)
			(vias allowed)
			(pads allowed)
			(copperpour not_allowed)
			(footprints allowed)
		)
		(placement
			(enabled no)
			(sheetname "")
		)
		(fill yes
			(thermal_gap 0.5)
			(thermal_bridge_width 0.5)
			(island_removal_mode 0)
		)
		(polygon
			(pts
				(arc
					(start 137.169144 -410.030168)
					(mid 136.465564 -410.030168)
					(end 137.169144 -410.030168)
				)
			)
		)
	)
	(zone
		(layers "B.Cu" "In11.Cu" "In13.Cu" "In15.Cu")
		(hatch none 0.5)
		(connect_pads
			(clearance 0)
		)
		(min_thickness 0.25)
		(keepout
			(tracks not_allowed)
			(vias allowed)
			(pads allowed)
			(copperpour not_allowed)
			(footprints allowed)
		)
		(placement
			(enabled no)
			(sheetname "")
		)
		(fill yes
			(thermal_gap 0.5)
			(thermal_bridge_width 0.5)
			(island_removal_mode 0)
		)
		(polygon
			(pts
				(arc
					(start 151.154892 -436.889906)
					(mid 150.34514 -436.889906)
					(end 151.154892 -436.889906)
				)
			)
		)
	)
	(zone
		(layers "B.Cu" "In11.Cu" "In13.Cu" "In15.Cu")
		(hatch none 0.5)
		(connect_pads
			(clearance 0)
		)
		(min_thickness 0.25)
		(keepout
			(tracks not_allowed)
			(vias allowed)
			(pads allowed)
			(copperpour not_allowed)
			(footprints allowed)
		)
		(placement
			(enabled no)
			(sheetname "")
		)
		(fill yes
			(thermal_gap 0.5)
			(thermal_bridge_width 0.5)
			(island_removal_mode 0)
		)
		(polygon
			(pts
				(arc
					(start 345.449652 -275.8948)
					(mid 344.796872 -275.8948)
					(end 345.449652 -275.8948)
				)
			)
		)
	)
	(zone
		(layers "B.Cu" "In11.Cu" "In13.Cu" "In15.Cu")
		(hatch none 0.5)
		(connect_pads
			(clearance 0)
		)
		(min_thickness 0.25)
		(keepout
			(tracks not_allowed)
			(vias allowed)
			(pads allowed)
			(copperpour not_allowed)
			(footprints allowed)
		)
		(placement
			(enabled no)
			(sheetname "")
		)
		(fill yes
			(thermal_gap 0.5)
			(thermal_bridge_width 0.5)
			(island_removal_mode 0)
		)
		(polygon
			(pts
				(arc
					(start 144.159224 -410.030168)
					(mid 143.455644 -410.030168)
					(end 144.159224 -410.030168)
				)
			)
		)
	)
	(zone
		(layers "B.Cu" "In11.Cu" "In13.Cu" "In15.Cu")
		(hatch none 0.5)
		(connect_pads
			(clearance 0)
		)
		(min_thickness 0.25)
		(keepout
			(tracks not_allowed)
			(vias allowed)
			(pads allowed)
			(copperpour not_allowed)
			(footprints allowed)
		)
		(placement
			(enabled no)
			(sheetname "")
		)
		(fill yes
			(thermal_gap 0.5)
			(thermal_bridge_width 0.5)
			(island_removal_mode 0)
		)
		(polygon
			(pts
				(arc
					(start 440.208162 -281.466798)
					(mid 439.555382 -281.466798)
					(end 440.208162 -281.466798)
				)
			)
		)
	)
	(zone
		(layers "B.Cu" "In11.Cu" "In13.Cu" "In15.Cu")
		(hatch none 0.5)
		(connect_pads
			(clearance 0)
		)
		(min_thickness 0.25)
		(keepout
			(tracks not_allowed)
			(vias allowed)
			(pads allowed)
			(copperpour not_allowed)
			(footprints allowed)
		)
		(placement
			(enabled no)
			(sheetname "")
		)
		(fill yes
			(thermal_gap 0.5)
			(thermal_bridge_width 0.5)
			(island_removal_mode 0)
		)
		(polygon
			(pts
				(arc
					(start 345.919806 -260.430772)
					(mid 345.267026 -260.430772)
					(end 345.919806 -260.430772)
				)
			)
		)
	)
	(zone
		(layers "B.Cu" "In11.Cu" "In13.Cu" "In15.Cu")
		(hatch none 0.5)
		(connect_pads
			(clearance 0)
		)
		(min_thickness 0.25)
		(keepout
			(tracks not_allowed)
			(vias allowed)
			(pads allowed)
			(copperpour not_allowed)
			(footprints allowed)
		)
		(placement
			(enabled no)
			(sheetname "")
		)
		(fill yes
			(thermal_gap 0.5)
			(thermal_bridge_width 0.5)
			(island_removal_mode 0)
		)
		(polygon
			(pts
				(arc
					(start 36.303204 -304.416714)
					(mid 35.650424 -304.416714)
					(end 36.303204 -304.416714)
				)
			)
		)
	)
	(zone
		(layers "B.Cu" "In11.Cu" "In13.Cu" "In15.Cu")
		(hatch none 0.5)
		(connect_pads
			(clearance 0)
		)
		(min_thickness 0.25)
		(keepout
			(tracks not_allowed)
			(vias allowed)
			(pads allowed)
			(copperpour not_allowed)
			(footprints allowed)
		)
		(placement
			(enabled no)
			(sheetname "")
		)
		(fill yes
			(thermal_gap 0.5)
			(thermal_bridge_width 0.5)
			(island_removal_mode 0)
		)
		(polygon
			(pts
				(arc
					(start 310.318404 -244.066568)
					(mid 309.665624 -244.066568)
					(end 310.318404 -244.066568)
				)
			)
		)
	)
	(zone
		(layers "B.Cu" "In11.Cu" "In13.Cu" "In15.Cu")
		(hatch none 0.5)
		(connect_pads
			(clearance 0)
		)
		(min_thickness 0.25)
		(keepout
			(tracks not_allowed)
			(vias allowed)
			(pads allowed)
			(copperpour not_allowed)
			(footprints allowed)
		)
		(placement
			(enabled no)
			(sheetname "")
		)
		(fill yes
			(thermal_gap 0.5)
			(thermal_bridge_width 0.5)
			(island_removal_mode 0)
		)
		(polygon
			(pts
				(arc
					(start 319.054988 -426.089826)
					(mid 318.245236 -426.089826)
					(end 319.054988 -426.089826)
				)
			)
		)
	)
	(zone
		(layers "B.Cu" "In11.Cu" "In13.Cu" "In15.Cu")
		(hatch none 0.5)
		(connect_pads
			(clearance 0)
		)
		(min_thickness 0.25)
		(keepout
			(tracks not_allowed)
			(vias allowed)
			(pads allowed)
			(copperpour not_allowed)
			(footprints allowed)
		)
		(placement
			(enabled no)
			(sheetname "")
		)
		(fill yes
			(thermal_gap 0.5)
			(thermal_bridge_width 0.5)
			(island_removal_mode 0)
		)
		(polygon
			(pts
				(arc
					(start 344.870024 -227.64496)
					(mid 344.217244 -227.64496)
					(end 344.870024 -227.64496)
				)
			)
		)
	)
	(zone
		(layers "B.Cu" "In11.Cu" "In13.Cu" "In15.Cu")
		(hatch none 0.5)
		(connect_pads
			(clearance 0)
		)
		(min_thickness 0.25)
		(keepout
			(tracks not_allowed)
			(vias allowed)
			(pads allowed)
			(copperpour not_allowed)
			(footprints allowed)
		)
		(placement
			(enabled no)
			(sheetname "")
		)
		(fill yes
			(thermal_gap 0.5)
			(thermal_bridge_width 0.5)
			(island_removal_mode 0)
		)
		(polygon
			(pts
				(arc
					(start 129.352802 -215.436704)
					(mid 128.700022 -215.436704)
					(end 129.352802 -215.436704)
				)
			)
		)
	)
	(zone
		(layers "B.Cu" "In11.Cu" "In13.Cu" "In15.Cu")
		(hatch none 0.5)
		(connect_pads
			(clearance 0)
		)
		(min_thickness 0.25)
		(keepout
			(tracks not_allowed)
			(vias allowed)
			(pads allowed)
			(copperpour not_allowed)
			(footprints allowed)
		)
		(placement
			(enabled no)
			(sheetname "")
		)
		(fill yes
			(thermal_gap 0.5)
			(thermal_bridge_width 0.5)
			(island_removal_mode 0)
		)
		(polygon
			(pts
				(arc
					(start 229.54869 -52.043076)
					(mid 228.84511 -52.043076)
					(end 229.54869 -52.043076)
				)
			)
		)
	)
	(zone
		(layers "B.Cu" "In11.Cu" "In13.Cu" "In15.Cu")
		(hatch none 0.5)
		(connect_pads
			(clearance 0)
		)
		(min_thickness 0.25)
		(keepout
			(tracks not_allowed)
			(vias allowed)
			(pads allowed)
			(copperpour not_allowed)
			(footprints allowed)
		)
		(placement
			(enabled no)
			(sheetname "")
		)
		(fill yes
			(thermal_gap 0.5)
			(thermal_bridge_width 0.5)
			(island_removal_mode 0)
		)
		(polygon
			(pts
				(arc
					(start 167.801544 -410.030168)
					(mid 167.097964 -410.030168)
					(end 167.801544 -410.030168)
				)
			)
		)
	)
	(zone
		(layers "B.Cu" "In11.Cu" "In13.Cu" "In15.Cu")
		(hatch none 0.5)
		(connect_pads
			(clearance 0)
		)
		(min_thickness 0.25)
		(keepout
			(tracks not_allowed)
			(vias allowed)
			(pads allowed)
			(copperpour not_allowed)
			(footprints allowed)
		)
		(placement
			(enabled no)
			(sheetname "")
		)
		(fill yes
			(thermal_gap 0.5)
			(thermal_bridge_width 0.5)
			(island_removal_mode 0)
		)
		(polygon
			(pts
				(arc
					(start 375.523252 -261.244842)
					(mid 374.870472 -261.244842)
					(end 375.523252 -261.244842)
				)
			)
		)
	)
	(zone
		(layers "B.Cu" "In11.Cu" "In13.Cu" "In15.Cu")
		(hatch none 0.5)
		(connect_pads
			(clearance 0)
		)
		(min_thickness 0.25)
		(keepout
			(tracks not_allowed)
			(vias allowed)
			(pads allowed)
			(copperpour not_allowed)
			(footprints allowed)
		)
		(placement
			(enabled no)
			(sheetname "")
		)
		(fill yes
			(thermal_gap 0.5)
			(thermal_bridge_width 0.5)
			(island_removal_mode 0)
		)
		(polygon
			(pts
				(arc
					(start 126.643384 -277.522432)
					(mid 125.990604 -277.522432)
					(end 126.643384 -277.522432)
				)
			)
		)
	)
	(zone
		(layers "B.Cu" "In11.Cu" "In13.Cu" "In15.Cu")
		(hatch none 0.5)
		(connect_pads
			(clearance 0)
		)
		(min_thickness 0.25)
		(keepout
			(tracks not_allowed)
			(vias allowed)
			(pads allowed)
			(copperpour not_allowed)
			(footprints allowed)
		)
		(placement
			(enabled no)
			(sheetname "")
		)
		(fill yes
			(thermal_gap 0.5)
			(thermal_bridge_width 0.5)
			(island_removal_mode 0)
		)
		(polygon
			(pts
				(arc
					(start 372.124224 -248.806208)
					(mid 371.471444 -248.806208)
					(end 372.124224 -248.806208)
				)
			)
		)
	)
	(zone
		(layers "B.Cu" "In11.Cu" "In13.Cu" "In15.Cu")
		(hatch none 0.5)
		(connect_pads
			(clearance 0)
		)
		(min_thickness 0.25)
		(keepout
			(tracks not_allowed)
			(vias allowed)
			(pads allowed)
			(copperpour not_allowed)
			(footprints allowed)
		)
		(placement
			(enabled no)
			(sheetname "")
		)
		(fill yes
			(thermal_gap 0.5)
			(thermal_bridge_width 0.5)
			(island_removal_mode 0)
		)
		(polygon
			(pts
				(arc
					(start 343.46007 -238.225584)
					(mid 342.80729 -238.225584)
					(end 343.46007 -238.225584)
				)
			)
		)
	)
	(zone
		(layers "B.Cu" "In11.Cu" "In13.Cu" "In15.Cu")
		(hatch none 0.5)
		(connect_pads
			(clearance 0)
		)
		(min_thickness 0.25)
		(keepout
			(tracks not_allowed)
			(vias allowed)
			(pads allowed)
			(copperpour not_allowed)
			(footprints allowed)
		)
		(placement
			(enabled no)
			(sheetname "")
		)
		(fill yes
			(thermal_gap 0.5)
			(thermal_bridge_width 0.5)
			(island_removal_mode 0)
		)
		(polygon
			(pts
				(arc
					(start 413.493204 -243.216684)
					(mid 412.840424 -243.216684)
					(end 413.493204 -243.216684)
				)
			)
		)
	)
	(zone
		(layers "B.Cu" "In11.Cu" "In13.Cu" "In15.Cu")
		(hatch none 0.5)
		(connect_pads
			(clearance 0)
		)
		(min_thickness 0.25)
		(keepout
			(tracks not_allowed)
			(vias allowed)
			(pads allowed)
			(copperpour not_allowed)
			(footprints allowed)
		)
		(placement
			(enabled no)
			(sheetname "")
		)
		(fill yes
			(thermal_gap 0.5)
			(thermal_bridge_width 0.5)
			(island_removal_mode 0)
		)
		(polygon
			(pts
				(arc
					(start 284.243272 -227.066602)
					(mid 283.590492 -227.066602)
					(end 284.243272 -227.066602)
				)
			)
		)
	)
	(zone
		(layers "B.Cu" "In11.Cu" "In13.Cu" "In15.Cu")
		(hatch none 0.5)
		(connect_pads
			(clearance 0)
		)
		(min_thickness 0.25)
		(keepout
			(tracks not_allowed)
			(vias allowed)
			(pads allowed)
			(copperpour not_allowed)
			(footprints allowed)
		)
		(placement
			(enabled no)
			(sheetname "")
		)
		(fill yes
			(thermal_gap 0.5)
			(thermal_bridge_width 0.5)
			(island_removal_mode 0)
		)
		(polygon
			(pts
				(arc
					(start 136.154922 -439.0898)
					(mid 135.34517 -439.0898)
					(end 136.154922 -439.0898)
				)
			)
		)
	)
	(zone
		(layers "B.Cu" "In11.Cu" "In13.Cu" "In15.Cu")
		(hatch none 0.5)
		(connect_pads
			(clearance 0)
		)
		(min_thickness 0.25)
		(keepout
			(tracks not_allowed)
			(vias allowed)
			(pads allowed)
			(copperpour not_allowed)
			(footprints allowed)
		)
		(placement
			(enabled no)
			(sheetname "")
		)
		(fill yes
			(thermal_gap 0.5)
			(thermal_bridge_width 0.5)
			(island_removal_mode 0)
		)
		(polygon
			(pts
				(arc
					(start 376.932952 -253.919736)
					(mid 376.280172 -253.919736)
					(end 376.932952 -253.919736)
				)
			)
		)
	)
	(zone
		(layers "B.Cu" "In11.Cu" "In13.Cu" "In15.Cu")
		(hatch none 0.5)
		(connect_pads
			(clearance 0)
		)
		(min_thickness 0.25)
		(keepout
			(tracks not_allowed)
			(vias allowed)
			(pads allowed)
			(copperpour not_allowed)
			(footprints allowed)
		)
		(placement
			(enabled no)
			(sheetname "")
		)
		(fill yes
			(thermal_gap 0.5)
			(thermal_bridge_width 0.5)
			(island_removal_mode 0)
		)
		(polygon
			(pts
				(arc
					(start 96.929956 -240.667286)
					(mid 96.277176 -240.667286)
					(end 96.929956 -240.667286)
				)
			)
		)
	)
	(zone
		(layers "B.Cu" "In11.Cu" "In13.Cu" "In15.Cu")
		(hatch none 0.5)
		(connect_pads
			(clearance 0)
		)
		(min_thickness 0.25)
		(keepout
			(tracks not_allowed)
			(vias allowed)
			(pads allowed)
			(copperpour not_allowed)
			(footprints allowed)
		)
		(placement
			(enabled no)
			(sheetname "")
		)
		(fill yes
			(thermal_gap 0.5)
			(thermal_bridge_width 0.5)
			(island_removal_mode 0)
		)
		(polygon
			(pts
				(arc
					(start 280.143204 -202.416664)
					(mid 279.490424 -202.416664)
					(end 280.143204 -202.416664)
				)
			)
		)
	)
	(zone
		(layers "B.Cu" "In11.Cu" "In13.Cu" "In15.Cu")
		(hatch none 0.5)
		(connect_pads
			(clearance 0)
		)
		(min_thickness 0.25)
		(keepout
			(tracks not_allowed)
			(vias allowed)
			(pads allowed)
			(copperpour not_allowed)
			(footprints allowed)
		)
		(placement
			(enabled no)
			(sheetname "")
		)
		(fill yes
			(thermal_gap 0.5)
			(thermal_bridge_width 0.5)
			(island_removal_mode 0)
		)
		(polygon
			(pts
				(arc
					(start 90.054938 -427.089824)
					(mid 89.245186 -427.089824)
					(end 90.054938 -427.089824)
				)
			)
		)
	)
	(zone
		(layers "B.Cu" "In11.Cu" "In13.Cu" "In15.Cu")
		(hatch none 0.5)
		(connect_pads
			(clearance 0)
		)
		(min_thickness 0.25)
		(keepout
			(tracks not_allowed)
			(vias allowed)
			(pads allowed)
			(copperpour not_allowed)
			(footprints allowed)
		)
		(placement
			(enabled no)
			(sheetname "")
		)
		(fill yes
			(thermal_gap 0.5)
			(thermal_bridge_width 0.5)
			(island_removal_mode 0)
		)
		(polygon
			(pts
				(arc
					(start 32.203136 -282.316682)
					(mid 31.550356 -282.316682)
					(end 32.203136 -282.316682)
				)
			)
		)
	)
	(zone
		(layers "B.Cu" "In11.Cu" "In13.Cu" "In15.Cu")
		(hatch none 0.5)
		(connect_pads
			(clearance 0)
		)
		(min_thickness 0.25)
		(keepout
			(tracks not_allowed)
			(vias allowed)
			(pads allowed)
			(copperpour not_allowed)
			(footprints allowed)
		)
		(placement
			(enabled no)
			(sheetname "")
		)
		(fill yes
			(thermal_gap 0.5)
			(thermal_bridge_width 0.5)
			(island_removal_mode 0)
		)
		(polygon
			(pts
				(arc
					(start 455.337672 -210.916774)
					(mid 454.684892 -210.916774)
					(end 455.337672 -210.916774)
				)
			)
		)
	)
	(zone
		(layers "B.Cu" "In11.Cu" "In13.Cu" "In15.Cu")
		(hatch none 0.5)
		(connect_pads
			(clearance 0)
		)
		(min_thickness 0.25)
		(keepout
			(tracks not_allowed)
			(vias allowed)
			(pads allowed)
			(copperpour not_allowed)
			(footprints allowed)
		)
		(placement
			(enabled no)
			(sheetname "")
		)
		(fill yes
			(thermal_gap 0.5)
			(thermal_bridge_width 0.5)
			(island_removal_mode 0)
		)
		(polygon
			(pts
				(arc
					(start 280.143204 -302.716692)
					(mid 279.490424 -302.716692)
					(end 280.143204 -302.716692)
				)
			)
		)
	)
	(zone
		(layers "B.Cu" "In11.Cu" "In13.Cu" "In15.Cu")
		(hatch none 0.5)
		(connect_pads
			(clearance 0)
		)
		(min_thickness 0.25)
		(keepout
			(tracks not_allowed)
			(vias allowed)
			(pads allowed)
			(copperpour not_allowed)
			(footprints allowed)
		)
		(placement
			(enabled no)
			(sheetname "")
		)
		(fill yes
			(thermal_gap 0.5)
			(thermal_bridge_width 0.5)
			(island_removal_mode 0)
		)
		(polygon
			(pts
				(arc
					(start 128.522984 -261.244842)
					(mid 127.870204 -261.244842)
					(end 128.522984 -261.244842)
				)
			)
		)
	)
	(zone
		(layers "B.Cu" "In11.Cu" "In13.Cu" "In15.Cu")
		(hatch none 0.5)
		(connect_pads
			(clearance 0)
		)
		(min_thickness 0.25)
		(keepout
			(tracks not_allowed)
			(vias allowed)
			(pads allowed)
			(copperpour not_allowed)
			(footprints allowed)
		)
		(placement
			(enabled no)
			(sheetname "")
		)
		(fill yes
			(thermal_gap 0.5)
			(thermal_bridge_width 0.5)
			(island_removal_mode 0)
		)
		(polygon
			(pts
				(arc
					(start 332.054962 -434.48986)
					(mid 331.24521 -434.48986)
					(end 332.054962 -434.48986)
				)
			)
		)
	)
	(zone
		(layers "B.Cu" "In11.Cu" "In13.Cu" "In15.Cu")
		(hatch none 0.5)
		(connect_pads
			(clearance 0)
		)
		(min_thickness 0.25)
		(keepout
			(tracks not_allowed)
			(vias allowed)
			(pads allowed)
			(copperpour not_allowed)
			(footprints allowed)
		)
		(placement
			(enabled no)
			(sheetname "")
		)
		(fill yes
			(thermal_gap 0.5)
			(thermal_bridge_width 0.5)
			(island_removal_mode 0)
		)
		(polygon
			(pts
				(arc
					(start 386.221224 -216.25052)
					(mid 385.568444 -216.25052)
					(end 386.221224 -216.25052)
				)
			)
		)
	)
	(zone
		(layers "B.Cu" "In11.Cu" "In13.Cu" "In15.Cu")
		(hatch none 0.5)
		(connect_pads
			(clearance 0)
		)
		(min_thickness 0.25)
		(keepout
			(tracks not_allowed)
			(vias allowed)
			(pads allowed)
			(copperpour not_allowed)
			(footprints allowed)
		)
		(placement
			(enabled no)
			(sheetname "")
		)
		(fill yes
			(thermal_gap 0.5)
			(thermal_bridge_width 0.5)
			(island_removal_mode 0)
		)
		(polygon
			(pts
				(arc
					(start 396.15491 -430.689766)
					(mid 395.345158 -430.689766)
					(end 396.15491 -430.689766)
				)
			)
		)
	)
	(zone
		(layers "B.Cu" "In11.Cu" "In13.Cu" "In15.Cu")
		(hatch none 0.5)
		(connect_pads
			(clearance 0)
		)
		(min_thickness 0.25)
		(keepout
			(tracks not_allowed)
			(vias allowed)
			(pads allowed)
			(copperpour not_allowed)
			(footprints allowed)
		)
		(placement
			(enabled no)
			(sheetname "")
		)
		(fill yes
			(thermal_gap 0.5)
			(thermal_bridge_width 0.5)
			(island_removal_mode 0)
		)
		(polygon
			(pts
				(arc
					(start 399.154904 -438.089802)
					(mid 398.345152 -438.089802)
					(end 399.154904 -438.089802)
				)
			)
		)
	)
	(zone
		(layers "B.Cu" "In11.Cu" "In13.Cu" "In15.Cu")
		(hatch none 0.5)
		(connect_pads
			(clearance 0)
		)
		(min_thickness 0.25)
		(keepout
			(tracks not_allowed)
			(vias allowed)
			(pads allowed)
			(copperpour not_allowed)
			(footprints allowed)
		)
		(placement
			(enabled no)
			(sheetname "")
		)
		(fill yes
			(thermal_gap 0.5)
			(thermal_bridge_width 0.5)
			(island_removal_mode 0)
		)
		(polygon
			(pts
				(arc
					(start 321.054984 -434.289962)
					(mid 320.245232 -434.289962)
					(end 321.054984 -434.289962)
				)
			)
		)
	)
	(zone
		(layers "B.Cu" "In11.Cu" "In13.Cu" "In15.Cu")
		(hatch none 0.5)
		(connect_pads
			(clearance 0)
		)
		(min_thickness 0.25)
		(keepout
			(tracks not_allowed)
			(vias allowed)
			(pads allowed)
			(copperpour not_allowed)
			(footprints allowed)
		)
		(placement
			(enabled no)
			(sheetname "")
		)
		(fill yes
			(thermal_gap 0.5)
			(thermal_bridge_width 0.5)
			(island_removal_mode 0)
		)
		(polygon
			(pts
				(arc
					(start 361.31627 -226.831144)
					(mid 360.66349 -226.831144)
					(end 361.31627 -226.831144)
				)
			)
		)
	)
	(zone
		(layers "B.Cu" "In11.Cu" "In13.Cu" "In15.Cu")
		(hatch none 0.5)
		(connect_pads
			(clearance 0)
		)
		(min_thickness 0.25)
		(keepout
			(tracks not_allowed)
			(vias allowed)
			(pads allowed)
			(copperpour not_allowed)
			(footprints allowed)
		)
		(placement
			(enabled no)
			(sheetname "")
		)
		(fill yes
			(thermal_gap 0.5)
			(thermal_bridge_width 0.5)
			(island_removal_mode 0)
		)
		(polygon
			(pts
				(arc
					(start 331.901038 -403.883876)
					(mid 331.197458 -403.883876)
					(end 331.901038 -403.883876)
				)
			)
		)
	)
	(zone
		(layers "B.Cu" "In11.Cu" "In13.Cu" "In15.Cu")
		(hatch none 0.5)
		(connect_pads
			(clearance 0)
		)
		(min_thickness 0.25)
		(keepout
			(tracks not_allowed)
			(vias allowed)
			(pads allowed)
			(copperpour not_allowed)
			(footprints allowed)
		)
		(placement
			(enabled no)
			(sheetname "")
		)
		(fill yes
			(thermal_gap 0.5)
			(thermal_bridge_width 0.5)
			(island_removal_mode 0)
		)
		(polygon
			(pts
				(arc
					(start 132.282692 -254.733552)
					(mid 131.629912 -254.733552)
					(end 132.282692 -254.733552)
				)
			)
		)
	)
	(zone
		(layers "B.Cu" "In11.Cu" "In13.Cu" "In15.Cu")
		(hatch none 0.5)
		(connect_pads
			(clearance 0)
		)
		(min_thickness 0.25)
		(keepout
			(tracks not_allowed)
			(vias allowed)
			(pads allowed)
			(copperpour not_allowed)
			(footprints allowed)
		)
		(placement
			(enabled no)
			(sheetname "")
		)
		(fill yes
			(thermal_gap 0.5)
			(thermal_bridge_width 0.5)
			(island_removal_mode 0)
		)
		(polygon
			(pts
				(arc
					(start 155.548584 -410.030168)
					(mid 154.845004 -410.030168)
					(end 155.548584 -410.030168)
				)
			)
		)
	)
	(zone
		(layers "B.Cu" "In11.Cu" "In13.Cu" "In15.Cu")
		(hatch none 0.5)
		(connect_pads
			(clearance 0)
		)
		(min_thickness 0.25)
		(keepout
			(tracks not_allowed)
			(vias allowed)
			(pads allowed)
			(copperpour not_allowed)
			(footprints allowed)
		)
		(placement
			(enabled no)
			(sheetname "")
		)
		(fill yes
			(thermal_gap 0.5)
			(thermal_bridge_width 0.5)
			(island_removal_mode 0)
		)
		(polygon
			(pts
				(arc
					(start 451.237604 -312.91657)
					(mid 450.584824 -312.91657)
					(end 451.237604 -312.91657)
				)
			)
		)
	)
	(zone
		(layers "B.Cu" "In11.Cu" "In13.Cu" "In15.Cu")
		(hatch none 0.5)
		(connect_pads
			(clearance 0)
		)
		(min_thickness 0.25)
		(keepout
			(tracks not_allowed)
			(vias allowed)
			(pads allowed)
			(copperpour not_allowed)
			(footprints allowed)
		)
		(placement
			(enabled no)
			(sheetname "")
		)
		(fill yes
			(thermal_gap 0.5)
			(thermal_bridge_width 0.5)
			(island_removal_mode 0)
		)
		(polygon
			(pts
				(arc
					(start 96.490028 -410.030168)
					(mid 95.786448 -410.030168)
					(end 96.490028 -410.030168)
				)
			)
		)
	)
	(zone
		(layers "B.Cu" "In11.Cu" "In13.Cu" "In15.Cu")
		(hatch none 0.5)
		(connect_pads
			(clearance 0)
		)
		(min_thickness 0.25)
		(keepout
			(tracks not_allowed)
			(vias allowed)
			(pads allowed)
			(copperpour not_allowed)
			(footprints allowed)
		)
		(placement
			(enabled no)
			(sheetname "")
		)
		(fill yes
			(thermal_gap 0.5)
			(thermal_bridge_width 0.5)
			(island_removal_mode 0)
		)
		(polygon
			(pts
				(arc
					(start 347.21927 -215.436704)
					(mid 346.56649 -215.436704)
					(end 347.21927 -215.436704)
				)
			)
		)
	)
	(zone
		(layers "B.Cu" "In11.Cu" "In13.Cu" "In15.Cu")
		(hatch none 0.5)
		(connect_pads
			(clearance 0)
		)
		(min_thickness 0.25)
		(keepout
			(tracks not_allowed)
			(vias allowed)
			(pads allowed)
			(copperpour not_allowed)
			(footprints allowed)
		)
		(placement
			(enabled no)
			(sheetname "")
		)
		(fill yes
			(thermal_gap 0.5)
			(thermal_bridge_width 0.5)
			(island_removal_mode 0)
		)
		(polygon
			(pts
				(arc
					(start 280.143204 -196.466714)
					(mid 279.490424 -196.466714)
					(end 280.143204 -196.466714)
				)
			)
		)
	)
	(zone
		(layers "B.Cu" "In11.Cu" "In13.Cu" "In15.Cu")
		(hatch none 0.5)
		(connect_pads
			(clearance 0)
		)
		(min_thickness 0.25)
		(keepout
			(tracks not_allowed)
			(vias allowed)
			(pads allowed)
			(copperpour not_allowed)
			(footprints allowed)
		)
		(placement
			(enabled no)
			(sheetname "")
		)
		(fill yes
			(thermal_gap 0.5)
			(thermal_bridge_width 0.5)
			(island_removal_mode 0)
		)
		(polygon
			(pts
				(arc
					(start 302.774604 -244.066568)
					(mid 302.121824 -244.066568)
					(end 302.774604 -244.066568)
				)
			)
		)
	)
	(zone
		(layers "B.Cu" "In11.Cu" "In13.Cu" "In15.Cu")
		(hatch none 0.5)
		(connect_pads
			(clearance 0)
		)
		(min_thickness 0.25)
		(keepout
			(tracks not_allowed)
			(vias allowed)
			(pads allowed)
			(copperpour not_allowed)
			(footprints allowed)
		)
		(placement
			(enabled no)
			(sheetname "")
		)
		(fill yes
			(thermal_gap 0.5)
			(thermal_bridge_width 0.5)
			(island_removal_mode 0)
		)
		(polygon
			(pts
				(arc
					(start 343.570052 -271.011396)
					(mid 342.917272 -271.011396)
					(end 343.570052 -271.011396)
				)
			)
		)
	)
	(zone
		(layers "B.Cu" "In11.Cu" "In13.Cu" "In15.Cu")
		(hatch none 0.5)
		(connect_pads
			(clearance 0)
		)
		(min_thickness 0.25)
		(keepout
			(tracks not_allowed)
			(vias allowed)
			(pads allowed)
			(copperpour not_allowed)
			(footprints allowed)
		)
		(placement
			(enabled no)
			(sheetname "")
		)
		(fill yes
			(thermal_gap 0.5)
			(thermal_bridge_width 0.5)
			(island_removal_mode 0)
		)
		(polygon
			(pts
				(arc
					(start 162.538664 -410.030168)
					(mid 161.835084 -410.030168)
					(end 162.538664 -410.030168)
				)
			)
		)
	)
	(zone
		(layers "B.Cu" "In11.Cu" "In13.Cu" "In15.Cu")
		(hatch none 0.5)
		(connect_pads
			(clearance 0)
		)
		(min_thickness 0.25)
		(keepout
			(tracks not_allowed)
			(vias allowed)
			(pads allowed)
			(copperpour not_allowed)
			(footprints allowed)
		)
		(placement
			(enabled no)
			(sheetname "")
		)
		(fill yes
			(thermal_gap 0.5)
			(thermal_bridge_width 0.5)
			(island_removal_mode 0)
		)
		(polygon
			(pts
				(arc
					(start 345.33967 -246.364506)
					(mid 344.68689 -246.364506)
					(end 345.33967 -246.364506)
				)
			)
		)
	)
	(zone
		(layers "B.Cu" "In11.Cu" "In13.Cu" "In15.Cu")
		(hatch none 0.5)
		(connect_pads
			(clearance 0)
		)
		(min_thickness 0.25)
		(keepout
			(tracks not_allowed)
			(vias allowed)
			(pads allowed)
			(copperpour not_allowed)
			(footprints allowed)
		)
		(placement
			(enabled no)
			(sheetname "")
		)
		(fill yes
			(thermal_gap 0.5)
			(thermal_bridge_width 0.5)
			(island_removal_mode 0)
		)
		(polygon
			(pts
				(arc
					(start 346.054934 -434.289962)
					(mid 345.245182 -434.289962)
					(end 346.054934 -434.289962)
				)
			)
		)
	)
	(zone
		(layers "B.Cu" "In11.Cu" "In13.Cu" "In15.Cu")
		(hatch none 0.5)
		(connect_pads
			(clearance 0)
		)
		(min_thickness 0.25)
		(keepout
			(tracks not_allowed)
			(vias allowed)
			(pads allowed)
			(copperpour not_allowed)
			(footprints allowed)
		)
		(placement
			(enabled no)
			(sheetname "")
		)
		(fill yes
			(thermal_gap 0.5)
			(thermal_bridge_width 0.5)
			(island_removal_mode 0)
		)
		(polygon
			(pts
				(arc
					(start 405.949404 -244.066568)
					(mid 405.296624 -244.066568)
					(end 405.949404 -244.066568)
				)
			)
		)
	)
	(zone
		(layers "B.Cu" "In11.Cu" "In13.Cu" "In15.Cu")
		(hatch none 0.5)
		(connect_pads
			(clearance 0)
		)
		(min_thickness 0.25)
		(keepout
			(tracks not_allowed)
			(vias allowed)
			(pads allowed)
			(copperpour not_allowed)
			(footprints allowed)
		)
		(placement
			(enabled no)
			(sheetname "")
		)
		(fill yes
			(thermal_gap 0.5)
			(thermal_bridge_width 0.5)
			(island_removal_mode 0)
		)
		(polygon
			(pts
				(arc
					(start 36.303204 -199.01662)
					(mid 35.650424 -199.01662)
					(end 36.303204 -199.01662)
				)
			)
		)
	)
	(zone
		(layers "B.Cu" "In11.Cu" "In13.Cu" "In15.Cu")
		(hatch none 0.5)
		(connect_pads
			(clearance 0)
		)
		(min_thickness 0.25)
		(keepout
			(tracks not_allowed)
			(vias allowed)
			(pads allowed)
			(copperpour not_allowed)
			(footprints allowed)
		)
		(placement
			(enabled no)
			(sheetname "")
		)
		(fill yes
			(thermal_gap 0.5)
			(thermal_bridge_width 0.5)
			(island_removal_mode 0)
		)
		(polygon
			(pts
				(arc
					(start 375.183146 -182.242968)
					(mid 374.479566 -182.242968)
					(end 375.183146 -182.242968)
				)
			)
		)
	)
	(zone
		(layers "B.Cu" "In11.Cu" "In13.Cu" "In15.Cu")
		(hatch none 0.5)
		(connect_pads
			(clearance 0)
		)
		(min_thickness 0.25)
		(keepout
			(tracks not_allowed)
			(vias allowed)
			(pads allowed)
			(copperpour not_allowed)
			(footprints allowed)
		)
		(placement
			(enabled no)
			(sheetname "")
		)
		(fill yes
			(thermal_gap 0.5)
			(thermal_bridge_width 0.5)
			(island_removal_mode 0)
		)
		(polygon
			(pts
				(arc
					(start 345.449652 -261.244842)
					(mid 344.796872 -261.244842)
					(end 345.449652 -261.244842)
				)
			)
		)
	)
	(zone
		(layers "B.Cu" "In11.Cu" "In13.Cu" "In15.Cu")
		(hatch none 0.5)
		(connect_pads
			(clearance 0)
		)
		(min_thickness 0.25)
		(keepout
			(tracks not_allowed)
			(vias allowed)
			(pads allowed)
			(copperpour not_allowed)
			(footprints allowed)
		)
		(placement
			(enabled no)
			(sheetname "")
		)
		(fill yes
			(thermal_gap 0.5)
			(thermal_bridge_width 0.5)
			(island_removal_mode 0)
		)
		(polygon
			(pts
				(arc
					(start 97.869756 -237.411514)
					(mid 97.216976 -237.411514)
					(end 97.869756 -237.411514)
				)
			)
		)
	)
	(zone
		(layers "B.Cu" "In11.Cu" "In13.Cu" "In15.Cu")
		(hatch none 0.5)
		(connect_pads
			(clearance 0)
		)
		(min_thickness 0.25)
		(keepout
			(tracks not_allowed)
			(vias allowed)
			(pads allowed)
			(copperpour not_allowed)
			(footprints allowed)
		)
		(placement
			(enabled no)
			(sheetname "")
		)
		(fill yes
			(thermal_gap 0.5)
			(thermal_bridge_width 0.5)
			(island_removal_mode 0)
		)
		(polygon
			(pts
				(arc
					(start 36.303204 -203.266802)
					(mid 35.650424 -203.266802)
					(end 36.303204 -203.266802)
				)
			)
		)
	)
	(zone
		(layers "B.Cu" "In11.Cu" "In13.Cu" "In15.Cu")
		(hatch none 0.5)
		(connect_pads
			(clearance 0)
		)
		(min_thickness 0.25)
		(keepout
			(tracks not_allowed)
			(vias allowed)
			(pads allowed)
			(copperpour not_allowed)
			(footprints allowed)
		)
		(placement
			(enabled no)
			(sheetname "")
		)
		(fill yes
			(thermal_gap 0.5)
			(thermal_bridge_width 0.5)
			(island_removal_mode 0)
		)
		(polygon
			(pts
				(arc
					(start 376.35307 -230.086662)
					(mid 375.70029 -230.086662)
					(end 376.35307 -230.086662)
				)
			)
		)
	)
	(zone
		(layers "B.Cu" "In11.Cu" "In13.Cu" "In15.Cu")
		(hatch none 0.5)
		(connect_pads
			(clearance 0)
		)
		(min_thickness 0.25)
		(keepout
			(tracks not_allowed)
			(vias allowed)
			(pads allowed)
			(copperpour not_allowed)
			(footprints allowed)
		)
		(placement
			(enabled no)
			(sheetname "")
		)
		(fill yes
			(thermal_gap 0.5)
			(thermal_bridge_width 0.5)
			(island_removal_mode 0)
		)
		(polygon
			(pts
				(arc
					(start 134.969504 -410.030168)
					(mid 134.265924 -410.030168)
					(end 134.969504 -410.030168)
				)
			)
		)
	)
	(zone
		(layers "B.Cu" "In11.Cu" "In13.Cu" "In15.Cu")
		(hatch none 0.5)
		(connect_pads
			(clearance 0)
		)
		(min_thickness 0.25)
		(keepout
			(tracks not_allowed)
			(vias allowed)
			(pads allowed)
			(copperpour not_allowed)
			(footprints allowed)
		)
		(placement
			(enabled no)
			(sheetname "")
		)
		(fill yes
			(thermal_gap 0.5)
			(thermal_bridge_width 0.5)
			(island_removal_mode 0)
		)
		(polygon
			(pts
				(arc
					(start 96.100138 -275.08073)
					(mid 95.447358 -275.08073)
					(end 96.100138 -275.08073)
				)
			)
		)
	)
	(zone
		(layers "B.Cu" "In11.Cu" "In13.Cu" "In15.Cu")
		(hatch none 0.5)
		(connect_pads
			(clearance 0)
		)
		(min_thickness 0.25)
		(keepout
			(tracks not_allowed)
			(vias allowed)
			(pads allowed)
			(copperpour not_allowed)
			(footprints allowed)
		)
		(placement
			(enabled no)
			(sheetname "")
		)
		(fill yes
			(thermal_gap 0.5)
			(thermal_bridge_width 0.5)
			(island_removal_mode 0)
		)
		(polygon
			(pts
				(arc
					(start 203.297536 -209.216752)
					(mid 202.644756 -209.216752)
					(end 203.297536 -209.216752)
				)
			)
		)
	)
	(zone
		(layers "B.Cu" "In11.Cu" "In13.Cu" "In15.Cu")
		(hatch none 0.5)
		(connect_pads
			(clearance 0)
		)
		(min_thickness 0.25)
		(keepout
			(tracks not_allowed)
			(vias allowed)
			(pads allowed)
			(copperpour not_allowed)
			(footprints allowed)
		)
		(placement
			(enabled no)
			(sheetname "")
		)
		(fill yes
			(thermal_gap 0.5)
			(thermal_bridge_width 0.5)
			(island_removal_mode 0)
		)
		(polygon
			(pts
				(arc
					(start 102.098856 -213.732618)
					(mid 101.446076 -213.732618)
					(end 102.098856 -213.732618)
				)
			)
		)
	)
	(zone
		(layers "B.Cu" "In11.Cu" "In13.Cu" "In15.Cu")
		(hatch none 0.5)
		(connect_pads
			(clearance 0)
		)
		(min_thickness 0.25)
		(keepout
			(tracks not_allowed)
			(vias allowed)
			(pads allowed)
			(copperpour not_allowed)
			(footprints allowed)
		)
		(placement
			(enabled no)
			(sheetname "")
		)
		(fill yes
			(thermal_gap 0.5)
			(thermal_bridge_width 0.5)
			(island_removal_mode 0)
		)
		(polygon
			(pts
				(arc
					(start 327.054972 -433.289964)
					(mid 326.24522 -433.289964)
					(end 327.054972 -433.289964)
				)
			)
		)
	)
	(zone
		(layers "B.Cu" "In11.Cu" "In13.Cu" "In15.Cu")
		(hatch none 0.5)
		(connect_pads
			(clearance 0)
		)
		(min_thickness 0.25)
		(keepout
			(tracks not_allowed)
			(vias allowed)
			(pads allowed)
			(copperpour not_allowed)
			(footprints allowed)
		)
		(placement
			(enabled no)
			(sheetname "")
		)
		(fill yes
			(thermal_gap 0.5)
			(thermal_bridge_width 0.5)
			(island_removal_mode 0)
		)
		(polygon
			(pts
				(arc
					(start 99.279202 -215.436704)
					(mid 98.626422 -215.436704)
					(end 99.279202 -215.436704)
				)
			)
		)
	)
	(zone
		(layers "B.Cu" "In11.Cu" "In13.Cu" "In15.Cu")
		(hatch none 0.5)
		(connect_pads
			(clearance 0)
		)
		(min_thickness 0.25)
		(keepout
			(tracks not_allowed)
			(vias allowed)
			(pads allowed)
			(copperpour not_allowed)
			(footprints allowed)
		)
		(placement
			(enabled no)
			(sheetname "")
		)
		(fill yes
			(thermal_gap 0.5)
			(thermal_bridge_width 0.5)
			(island_removal_mode 0)
		)
		(polygon
			(pts
				(arc
					(start 344.980006 -257.175254)
					(mid 344.327226 -257.175254)
					(end 344.980006 -257.175254)
				)
			)
		)
	)
	(zone
		(layers "B.Cu" "In11.Cu" "In13.Cu" "In15.Cu")
		(hatch none 0.5)
		(connect_pads
			(clearance 0)
		)
		(min_thickness 0.25)
		(keepout
			(tracks not_allowed)
			(vias allowed)
			(pads allowed)
			(copperpour not_allowed)
			(footprints allowed)
		)
		(placement
			(enabled no)
			(sheetname "")
		)
		(fill yes
			(thermal_gap 0.5)
			(thermal_bridge_width 0.5)
			(island_removal_mode 0)
		)
		(polygon
			(pts
				(arc
					(start 317.054992 -428.28972)
					(mid 316.24524 -428.28972)
					(end 317.054992 -428.28972)
				)
			)
		)
	)
	(zone
		(layers "B.Cu" "In11.Cu" "In13.Cu" "In15.Cu")
		(hatch none 0.5)
		(connect_pads
			(clearance 0)
		)
		(min_thickness 0.25)
		(keepout
			(tracks not_allowed)
			(vias allowed)
			(pads allowed)
			(copperpour not_allowed)
			(footprints allowed)
		)
		(placement
			(enabled no)
			(sheetname "")
		)
		(fill yes
			(thermal_gap 0.5)
			(thermal_bridge_width 0.5)
			(island_removal_mode 0)
		)
		(polygon
			(pts
				(arc
					(start 103.148384 -275.8948)
					(mid 102.495604 -275.8948)
					(end 103.148384 -275.8948)
				)
			)
		)
	)
	(zone
		(layers "B.Cu" "In11.Cu" "In13.Cu" "In15.Cu")
		(hatch none 0.5)
		(connect_pads
			(clearance 0)
		)
		(min_thickness 0.25)
		(keepout
			(tracks not_allowed)
			(vias allowed)
			(pads allowed)
			(copperpour not_allowed)
			(footprints allowed)
		)
		(placement
			(enabled no)
			(sheetname "")
		)
		(fill yes
			(thermal_gap 0.5)
			(thermal_bridge_width 0.5)
			(island_removal_mode 0)
		)
		(polygon
			(pts
				(arc
					(start 287.687004 -244.066568)
					(mid 287.034224 -244.066568)
					(end 287.687004 -244.066568)
				)
			)
		)
	)
	(zone
		(layers "B.Cu" "In11.Cu" "In13.Cu" "In15.Cu")
		(hatch none 0.5)
		(connect_pads
			(clearance 0)
		)
		(min_thickness 0.25)
		(keepout
			(tracks not_allowed)
			(vias allowed)
			(pads allowed)
			(copperpour not_allowed)
			(footprints allowed)
		)
		(placement
			(enabled no)
			(sheetname "")
		)
		(fill yes
			(thermal_gap 0.5)
			(thermal_bridge_width 0.5)
			(island_removal_mode 0)
		)
		(polygon
			(pts
				(arc
					(start 376.35307 -238.225584)
					(mid 375.70029 -238.225584)
					(end 376.35307 -238.225584)
				)
			)
		)
	)
	(zone
		(layers "B.Cu" "In11.Cu" "In13.Cu" "In15.Cu")
		(hatch none 0.5)
		(connect_pads
			(clearance 0)
		)
		(min_thickness 0.25)
		(keepout
			(tracks not_allowed)
			(vias allowed)
			(pads allowed)
			(copperpour not_allowed)
			(footprints allowed)
		)
		(placement
			(enabled no)
			(sheetname "")
		)
		(fill yes
			(thermal_gap 0.5)
			(thermal_bridge_width 0.5)
			(island_removal_mode 0)
		)
		(polygon
			(pts
				(arc
					(start 188.209936 -204.116686)
					(mid 187.557156 -204.116686)
					(end 188.209936 -204.116686)
				)
			)
		)
	)
	(zone
		(layers "B.Cu" "In11.Cu" "In13.Cu" "In15.Cu")
		(hatch none 0.5)
		(connect_pads
			(clearance 0)
		)
		(min_thickness 0.25)
		(keepout
			(tracks not_allowed)
			(vias allowed)
			(pads allowed)
			(copperpour not_allowed)
			(footprints allowed)
		)
		(placement
			(enabled no)
			(sheetname "")
		)
		(fill yes
			(thermal_gap 0.5)
			(thermal_bridge_width 0.5)
			(island_removal_mode 0)
		)
		(polygon
			(pts
				(arc
					(start 390.154922 -429.689768)
					(mid 389.34517 -429.689768)
					(end 390.154922 -429.689768)
				)
			)
		)
	)
	(zone
		(layers "B.Cu" "In11.Cu" "In13.Cu" "In15.Cu")
		(hatch none 0.5)
		(connect_pads
			(clearance 0)
		)
		(min_thickness 0.25)
		(keepout
			(tracks not_allowed)
			(vias allowed)
			(pads allowed)
			(copperpour not_allowed)
			(footprints allowed)
		)
		(placement
			(enabled no)
			(sheetname "")
		)
		(fill yes
			(thermal_gap 0.5)
			(thermal_bridge_width 0.5)
			(island_removal_mode 0)
		)
		(polygon
			(pts
				(arc
					(start 375.523252 -274.266914)
					(mid 374.870472 -274.266914)
					(end 375.523252 -274.266914)
				)
			)
		)
	)
	(zone
		(layers "B.Cu" "In11.Cu" "In13.Cu" "In15.Cu")
		(hatch none 0.5)
		(connect_pads
			(clearance 0)
		)
		(min_thickness 0.25)
		(keepout
			(tracks not_allowed)
			(vias allowed)
			(pads allowed)
			(copperpour not_allowed)
			(footprints allowed)
		)
		(placement
			(enabled no)
			(sheetname "")
		)
		(fill yes
			(thermal_gap 0.5)
			(thermal_bridge_width 0.5)
			(island_removal_mode 0)
		)
		(polygon
			(pts
				(arc
					(start 113.845848 -214.546434)
					(mid 113.193068 -214.546434)
					(end 113.845848 -214.546434)
				)
			)
		)
	)
	(zone
		(layers "B.Cu" "In11.Cu" "In13.Cu" "In15.Cu")
		(hatch none 0.5)
		(connect_pads
			(clearance 0)
		)
		(min_thickness 0.25)
		(keepout
			(tracks not_allowed)
			(vias allowed)
			(pads allowed)
			(copperpour not_allowed)
			(footprints allowed)
		)
		(placement
			(enabled no)
			(sheetname "")
		)
		(fill yes
			(thermal_gap 0.5)
			(thermal_bridge_width 0.5)
			(island_removal_mode 0)
		)
		(polygon
			(pts
				(arc
					(start 347.688916 -214.622634)
					(mid 347.036136 -214.622634)
					(end 347.688916 -214.622634)
				)
			)
		)
	)
	(zone
		(layers "B.Cu" "In11.Cu" "In13.Cu" "In15.Cu")
		(hatch none 0.5)
		(connect_pads
			(clearance 0)
		)
		(min_thickness 0.25)
		(keepout
			(tracks not_allowed)
			(vias allowed)
			(pads allowed)
			(copperpour not_allowed)
			(footprints allowed)
		)
		(placement
			(enabled no)
			(sheetname "")
		)
		(fill yes
			(thermal_gap 0.5)
			(thermal_bridge_width 0.5)
			(island_removal_mode 0)
		)
		(polygon
			(pts
				(arc
					(start 158.009336 -243.216684)
					(mid 157.356556 -243.216684)
					(end 158.009336 -243.216684)
				)
			)
		)
	)
	(zone
		(layers "B.Cu" "In11.Cu" "In13.Cu" "In15.Cu")
		(hatch none 0.5)
		(connect_pads
			(clearance 0)
		)
		(min_thickness 0.25)
		(keepout
			(tracks not_allowed)
			(vias allowed)
			(pads allowed)
			(copperpour not_allowed)
			(footprints allowed)
		)
		(placement
			(enabled no)
			(sheetname "")
		)
		(fill yes
			(thermal_gap 0.5)
			(thermal_bridge_width 0.5)
			(island_removal_mode 0)
		)
		(polygon
			(pts
				(arc
					(start 77.246988 -410.030168)
					(mid 76.543408 -410.030168)
					(end 77.246988 -410.030168)
				)
			)
		)
	)
	(zone
		(layers "B.Cu" "In11.Cu" "In13.Cu" "In15.Cu")
		(hatch none 0.5)
		(connect_pads
			(clearance 0)
		)
		(min_thickness 0.25)
		(keepout
			(tracks not_allowed)
			(vias allowed)
			(pads allowed)
			(copperpour not_allowed)
			(footprints allowed)
		)
		(placement
			(enabled no)
			(sheetname "")
		)
		(fill yes
			(thermal_gap 0.5)
			(thermal_bridge_width 0.5)
			(island_removal_mode 0)
		)
		(polygon
			(pts
				(arc
					(start 128.413002 -233.34218)
					(mid 127.760222 -233.34218)
					(end 128.413002 -233.34218)
				)
			)
		)
	)
	(zone
		(layers "B.Cu" "In11.Cu" "In13.Cu" "In15.Cu")
		(hatch none 0.5)
		(connect_pads
			(clearance 0)
		)
		(min_thickness 0.25)
		(keepout
			(tracks not_allowed)
			(vias allowed)
			(pads allowed)
			(copperpour not_allowed)
			(footprints allowed)
		)
		(placement
			(enabled no)
			(sheetname "")
		)
		(fill yes
			(thermal_gap 0.5)
			(thermal_bridge_width 0.5)
			(island_removal_mode 0)
		)
		(polygon
			(pts
				(arc
					(start 336.054954 -434.48986)
					(mid 335.245202 -434.48986)
					(end 336.054954 -434.48986)
				)
			)
		)
	)
	(zone
		(layers "B.Cu" "In11.Cu" "In13.Cu" "In15.Cu")
		(hatch none 0.5)
		(connect_pads
			(clearance 0)
		)
		(min_thickness 0.25)
		(keepout
			(tracks not_allowed)
			(vias allowed)
			(pads allowed)
			(copperpour not_allowed)
			(footprints allowed)
		)
		(placement
			(enabled no)
			(sheetname "")
		)
		(fill yes
			(thermal_gap 0.5)
			(thermal_bridge_width 0.5)
			(island_removal_mode 0)
		)
		(polygon
			(pts
				(arc
					(start 125.123448 -214.622634)
					(mid 124.470668 -214.622634)
					(end 125.123448 -214.622634)
				)
			)
		)
	)
	(zone
		(layers "B.Cu" "In11.Cu" "In13.Cu" "In15.Cu")
		(hatch none 0.5)
		(connect_pads
			(clearance 0)
		)
		(min_thickness 0.25)
		(keepout
			(tracks not_allowed)
			(vias allowed)
			(pads allowed)
			(copperpour not_allowed)
			(footprints allowed)
		)
		(placement
			(enabled no)
			(sheetname "")
		)
		(fill yes
			(thermal_gap 0.5)
			(thermal_bridge_width 0.5)
			(island_removal_mode 0)
		)
		(polygon
			(pts
				(arc
					(start 376.463052 -275.8948)
					(mid 375.810272 -275.8948)
					(end 376.463052 -275.8948)
				)
			)
		)
	)
	(zone
		(layers "B.Cu" "In11.Cu" "In13.Cu" "In15.Cu")
		(hatch none 0.5)
		(connect_pads
			(clearance 0)
		)
		(min_thickness 0.25)
		(keepout
			(tracks not_allowed)
			(vias allowed)
			(pads allowed)
			(copperpour not_allowed)
			(footprints allowed)
		)
		(placement
			(enabled no)
			(sheetname "")
		)
		(fill yes
			(thermal_gap 0.5)
			(thermal_bridge_width 0.5)
			(island_removal_mode 0)
		)
		(polygon
			(pts
				(arc
					(start 147.222464 -410.030168)
					(mid 146.518884 -410.030168)
					(end 147.222464 -410.030168)
				)
			)
		)
	)
	(zone
		(layers "B.Cu" "In11.Cu" "In13.Cu" "In15.Cu")
		(hatch none 0.5)
		(connect_pads
			(clearance 0)
		)
		(min_thickness 0.25)
		(keepout
			(tracks not_allowed)
			(vias allowed)
			(pads allowed)
			(copperpour not_allowed)
			(footprints allowed)
		)
		(placement
			(enabled no)
			(sheetname "")
		)
		(fill yes
			(thermal_gap 0.5)
			(thermal_bridge_width 0.5)
			(island_removal_mode 0)
		)
		(polygon
			(pts
				(arc
					(start 376.933206 -263.686544)
					(mid 376.280426 -263.686544)
					(end 376.933206 -263.686544)
				)
			)
		)
	)
	(zone
		(layers "B.Cu" "In11.Cu" "In13.Cu" "In15.Cu")
		(hatch none 0.5)
		(connect_pads
			(clearance 0)
		)
		(min_thickness 0.25)
		(keepout
			(tracks not_allowed)
			(vias allowed)
			(pads allowed)
			(copperpour not_allowed)
			(footprints allowed)
		)
		(placement
			(enabled no)
			(sheetname "")
		)
		(fill yes
			(thermal_gap 0.5)
			(thermal_bridge_width 0.5)
			(island_removal_mode 0)
		)
		(polygon
			(pts
				(arc
					(start 353.302062 -171.985432)
					(mid 352.598482 -171.985432)
					(end 353.302062 -171.985432)
				)
			)
		)
	)
	(zone
		(layers "B.Cu" "In11.Cu" "In13.Cu" "In15.Cu")
		(hatch none 0.5)
		(connect_pads
			(clearance 0)
		)
		(min_thickness 0.25)
		(keepout
			(tracks not_allowed)
			(vias allowed)
			(pads allowed)
			(copperpour not_allowed)
			(footprints allowed)
		)
		(placement
			(enabled no)
			(sheetname "")
		)
		(fill yes
			(thermal_gap 0.5)
			(thermal_bridge_width 0.5)
			(island_removal_mode 0)
		)
		(polygon
			(pts
				(arc
					(start 95.050356 -242.294918)
					(mid 94.397576 -242.294918)
					(end 95.050356 -242.294918)
				)
			)
		)
	)
	(zone
		(layers "B.Cu" "In11.Cu" "In13.Cu" "In15.Cu")
		(hatch none 0.5)
		(connect_pads
			(clearance 0)
		)
		(min_thickness 0.25)
		(keepout
			(tracks not_allowed)
			(vias allowed)
			(pads allowed)
			(copperpour not_allowed)
			(footprints allowed)
		)
		(placement
			(enabled no)
			(sheetname "")
		)
		(fill yes
			(thermal_gap 0.5)
			(thermal_bridge_width 0.5)
			(island_removal_mode 0)
		)
		(polygon
			(pts
				(arc
					(start 359.43667 -226.831144)
					(mid 358.78389 -226.831144)
					(end 359.43667 -226.831144)
				)
			)
		)
	)
	(zone
		(layers "B.Cu" "In11.Cu" "In13.Cu" "In15.Cu")
		(hatch none 0.5)
		(connect_pads
			(clearance 0)
		)
		(min_thickness 0.25)
		(keepout
			(tracks not_allowed)
			(vias allowed)
			(pads allowed)
			(copperpour not_allowed)
			(footprints allowed)
		)
		(placement
			(enabled no)
			(sheetname "")
		)
		(fill yes
			(thermal_gap 0.5)
			(thermal_bridge_width 0.5)
			(island_removal_mode 0)
		)
		(polygon
			(pts
				(arc
					(start 21.215604 -206.666592)
					(mid 20.562824 -206.666592)
					(end 21.215604 -206.666592)
				)
			)
		)
	)
	(zone
		(layers "B.Cu" "In11.Cu" "In13.Cu" "In15.Cu")
		(hatch none 0.5)
		(connect_pads
			(clearance 0)
		)
		(min_thickness 0.25)
		(keepout
			(tracks not_allowed)
			(vias allowed)
			(pads allowed)
			(copperpour not_allowed)
			(footprints allowed)
		)
		(placement
			(enabled no)
			(sheetname "")
		)
		(fill yes
			(thermal_gap 0.5)
			(thermal_bridge_width 0.5)
			(island_removal_mode 0)
		)
		(polygon
			(pts
				(arc
					(start 440.250072 -276.366732)
					(mid 439.597292 -276.366732)
					(end 440.250072 -276.366732)
				)
			)
		)
	)
	(zone
		(layers "B.Cu" "In11.Cu" "In13.Cu" "In15.Cu")
		(hatch none 0.5)
		(connect_pads
			(clearance 0)
		)
		(min_thickness 0.25)
		(keepout
			(tracks not_allowed)
			(vias allowed)
			(pads allowed)
			(copperpour not_allowed)
			(footprints allowed)
		)
		(placement
			(enabled no)
			(sheetname "")
		)
		(fill yes
			(thermal_gap 0.5)
			(thermal_bridge_width 0.5)
			(island_removal_mode 0)
		)
		(polygon
			(pts
				(arc
					(start 63.054992 -434.48986)
					(mid 62.24524 -434.48986)
					(end 63.054992 -434.48986)
				)
			)
		)
	)
	(zone
		(layers "B.Cu" "In11.Cu" "In13.Cu" "In15.Cu")
		(hatch none 0.5)
		(connect_pads
			(clearance 0)
		)
		(min_thickness 0.25)
		(keepout
			(tracks not_allowed)
			(vias allowed)
			(pads allowed)
			(copperpour not_allowed)
			(footprints allowed)
		)
		(placement
			(enabled no)
			(sheetname "")
		)
		(fill yes
			(thermal_gap 0.5)
			(thermal_bridge_width 0.5)
			(island_removal_mode 0)
		)
		(polygon
			(pts
				(arc
					(start 354.847652 -280.778204)
					(mid 354.194872 -280.778204)
					(end 354.847652 -280.778204)
				)
			)
		)
	)
	(zone
		(layers "B.Cu" "In11.Cu" "In13.Cu" "In15.Cu")
		(hatch none 0.5)
		(connect_pads
			(clearance 0)
		)
		(min_thickness 0.25)
		(keepout
			(tracks not_allowed)
			(vias allowed)
			(pads allowed)
			(copperpour not_allowed)
			(footprints allowed)
		)
		(placement
			(enabled no)
			(sheetname "")
		)
		(fill yes
			(thermal_gap 0.5)
			(thermal_bridge_width 0.5)
			(island_removal_mode 0)
		)
		(polygon
			(pts
				(arc
					(start 128.883156 -239.0394)
					(mid 128.230376 -239.0394)
					(end 128.883156 -239.0394)
				)
			)
		)
	)
	(zone
		(layers "B.Cu" "In11.Cu" "In13.Cu" "In15.Cu")
		(hatch none 0.5)
		(connect_pads
			(clearance 0)
		)
		(min_thickness 0.25)
		(keepout
			(tracks not_allowed)
			(vias allowed)
			(pads allowed)
			(copperpour not_allowed)
			(footprints allowed)
		)
		(placement
			(enabled no)
			(sheetname "")
		)
		(fill yes
			(thermal_gap 0.5)
			(thermal_bridge_width 0.5)
			(island_removal_mode 0)
		)
		(polygon
			(pts
				(arc
					(start 440.250072 -304.416714)
					(mid 439.597292 -304.416714)
					(end 440.250072 -304.416714)
				)
			)
		)
	)
	(zone
		(layers "B.Cu" "In11.Cu" "In13.Cu" "In15.Cu")
		(hatch none 0.5)
		(connect_pads
			(clearance 0)
		)
		(min_thickness 0.25)
		(keepout
			(tracks not_allowed)
			(vias allowed)
			(pads allowed)
			(copperpour not_allowed)
			(footprints allowed)
		)
		(placement
			(enabled no)
			(sheetname "")
		)
		(fill yes
			(thermal_gap 0.5)
			(thermal_bridge_width 0.5)
			(island_removal_mode 0)
		)
		(polygon
			(pts
				(arc
					(start 128.883156 -235.783882)
					(mid 128.230376 -235.783882)
					(end 128.883156 -235.783882)
				)
			)
		)
	)
	(zone
		(layers "B.Cu" "In11.Cu" "In13.Cu" "In15.Cu")
		(hatch none 0.5)
		(connect_pads
			(clearance 0)
		)
		(min_thickness 0.25)
		(keepout
			(tracks not_allowed)
			(vias allowed)
			(pads allowed)
			(copperpour not_allowed)
			(footprints allowed)
		)
		(placement
			(enabled no)
			(sheetname "")
		)
		(fill yes
			(thermal_gap 0.5)
			(thermal_bridge_width 0.5)
			(island_removal_mode 0)
		)
		(polygon
			(pts
				(arc
					(start 376.18416 -410.030168)
					(mid 375.48058 -410.030168)
					(end 376.18416 -410.030168)
				)
			)
		)
	)
	(zone
		(layers "B.Cu" "In11.Cu" "In13.Cu" "In15.Cu")
		(hatch none 0.5)
		(connect_pads
			(clearance 0)
		)
		(min_thickness 0.25)
		(keepout
			(tracks not_allowed)
			(vias allowed)
			(pads allowed)
			(copperpour not_allowed)
			(footprints allowed)
		)
		(placement
			(enabled no)
			(sheetname "")
		)
		(fill yes
			(thermal_gap 0.5)
			(thermal_bridge_width 0.5)
			(island_removal_mode 0)
		)
		(polygon
			(pts
				(arc
					(start 398.49044 -410.030168)
					(mid 397.78686 -410.030168)
					(end 398.49044 -410.030168)
				)
			)
		)
	)
	(zone
		(layers "B.Cu" "In11.Cu" "In13.Cu" "In15.Cu")
		(hatch none 0.5)
		(connect_pads
			(clearance 0)
		)
		(min_thickness 0.25)
		(keepout
			(tracks not_allowed)
			(vias allowed)
			(pads allowed)
			(copperpour not_allowed)
			(footprints allowed)
		)
		(placement
			(enabled no)
			(sheetname "")
		)
		(fill yes
			(thermal_gap 0.5)
			(thermal_bridge_width 0.5)
			(island_removal_mode 0)
		)
		(polygon
			(pts
				(arc
					(start 131.342384 -279.150318)
					(mid 130.689604 -279.150318)
					(end 131.342384 -279.150318)
				)
			)
		)
	)
	(zone
		(layers "B.Cu" "In11.Cu" "In13.Cu" "In15.Cu")
		(hatch none 0.5)
		(connect_pads
			(clearance 0)
		)
		(min_thickness 0.25)
		(keepout
			(tracks not_allowed)
			(vias allowed)
			(pads allowed)
			(copperpour not_allowed)
			(footprints allowed)
		)
		(placement
			(enabled no)
			(sheetname "")
		)
		(fill yes
			(thermal_gap 0.5)
			(thermal_bridge_width 0.5)
			(island_removal_mode 0)
		)
		(polygon
			(pts
				(arc
					(start 146.358864 -410.030168)
					(mid 145.655284 -410.030168)
					(end 146.358864 -410.030168)
				)
			)
		)
	)
	(zone
		(layers "B.Cu" "In11.Cu" "In13.Cu" "In15.Cu")
		(hatch none 0.5)
		(connect_pads
			(clearance 0)
		)
		(min_thickness 0.25)
		(keepout
			(tracks not_allowed)
			(vias allowed)
			(pads allowed)
			(copperpour not_allowed)
			(footprints allowed)
		)
		(placement
			(enabled no)
			(sheetname "")
		)
		(fill yes
			(thermal_gap 0.5)
			(thermal_bridge_width 0.5)
			(island_removal_mode 0)
		)
		(polygon
			(pts
				(arc
					(start 351.024698 -50.207672)
					(mid 350.321118 -50.207672)
					(end 351.024698 -50.207672)
				)
			)
		)
	)
	(zone
		(layers "B.Cu" "In11.Cu" "In13.Cu" "In15.Cu")
		(hatch none 0.5)
		(connect_pads
			(clearance 0)
		)
		(min_thickness 0.25)
		(keepout
			(tracks not_allowed)
			(vias allowed)
			(pads allowed)
			(copperpour not_allowed)
			(footprints allowed)
		)
		(placement
			(enabled no)
			(sheetname "")
		)
		(fill yes
			(thermal_gap 0.5)
			(thermal_bridge_width 0.5)
			(island_removal_mode 0)
		)
		(polygon
			(pts
				(arc
					(start 364.24743 -55.884572)
					(mid 363.54385 -55.884572)
					(end 364.24743 -55.884572)
				)
			)
		)
	)
	(zone
		(layers "B.Cu" "In11.Cu" "In13.Cu" "In15.Cu")
		(hatch none 0.5)
		(connect_pads
			(clearance 0)
		)
		(min_thickness 0.25)
		(keepout
			(tracks not_allowed)
			(vias allowed)
			(pads allowed)
			(copperpour not_allowed)
			(footprints allowed)
		)
		(placement
			(enabled no)
			(sheetname "")
		)
		(fill yes
			(thermal_gap 0.5)
			(thermal_bridge_width 0.5)
			(island_removal_mode 0)
		)
		(polygon
			(pts
				(arc
					(start 131.906264 -410.030168)
					(mid 131.202684 -410.030168)
					(end 131.906264 -410.030168)
				)
			)
		)
	)
	(zone
		(layers "B.Cu" "In11.Cu" "In13.Cu" "In15.Cu")
		(hatch none 0.5)
		(connect_pads
			(clearance 0)
		)
		(min_thickness 0.25)
		(keepout
			(tracks not_allowed)
			(vias allowed)
			(pads allowed)
			(copperpour not_allowed)
			(footprints allowed)
		)
		(placement
			(enabled no)
			(sheetname "")
		)
		(fill yes
			(thermal_gap 0.5)
			(thermal_bridge_width 0.5)
			(island_removal_mode 0)
		)
		(polygon
			(pts
				(arc
					(start 129.462784 -267.755878)
					(mid 128.810004 -267.755878)
					(end 129.462784 -267.755878)
				)
			)
		)
	)
	(zone
		(layers "B.Cu" "In11.Cu" "In13.Cu" "In15.Cu")
		(hatch none 0.5)
		(connect_pads
			(clearance 0)
		)
		(min_thickness 0.25)
		(keepout
			(tracks not_allowed)
			(vias allowed)
			(pads allowed)
			(copperpour not_allowed)
			(footprints allowed)
		)
		(placement
			(enabled no)
			(sheetname "")
		)
		(fill yes
			(thermal_gap 0.5)
			(thermal_bridge_width 0.5)
			(island_removal_mode 0)
		)
		(polygon
			(pts
				(arc
					(start 59.055 -433.289964)
					(mid 58.245248 -433.289964)
					(end 59.055 -433.289964)
				)
			)
		)
	)
	(zone
		(layers "B.Cu" "In11.Cu" "In13.Cu" "In15.Cu")
		(hatch none 0.5)
		(connect_pads
			(clearance 0)
		)
		(min_thickness 0.25)
		(keepout
			(tracks not_allowed)
			(vias allowed)
			(pads allowed)
			(copperpour not_allowed)
			(footprints allowed)
		)
		(placement
			(enabled no)
			(sheetname "")
		)
		(fill yes
			(thermal_gap 0.5)
			(thermal_bridge_width 0.5)
			(island_removal_mode 0)
		)
		(polygon
			(pts
				(arc
					(start 61.054996 -428.28972)
					(mid 60.245244 -428.28972)
					(end 61.054996 -428.28972)
				)
			)
		)
	)
	(zone
		(layers "B.Cu" "In11.Cu" "In13.Cu" "In15.Cu")
		(hatch none 0.5)
		(connect_pads
			(clearance 0)
		)
		(min_thickness 0.25)
		(keepout
			(tracks not_allowed)
			(vias allowed)
			(pads allowed)
			(copperpour not_allowed)
			(footprints allowed)
		)
		(placement
			(enabled no)
			(sheetname "")
		)
		(fill yes
			(thermal_gap 0.5)
			(thermal_bridge_width 0.5)
			(island_removal_mode 0)
		)
		(polygon
			(pts
				(arc
					(start 354.378006 -281.59202)
					(mid 353.725226 -281.59202)
					(end 354.378006 -281.59202)
				)
			)
		)
	)
	(zone
		(layers "B.Cu" "In11.Cu" "In13.Cu" "In15.Cu")
		(hatch none 0.5)
		(connect_pads
			(clearance 0)
		)
		(min_thickness 0.25)
		(keepout
			(tracks not_allowed)
			(vias allowed)
			(pads allowed)
			(copperpour not_allowed)
			(footprints allowed)
		)
		(placement
			(enabled no)
			(sheetname "")
		)
		(fill yes
			(thermal_gap 0.5)
			(thermal_bridge_width 0.5)
			(island_removal_mode 0)
		)
		(polygon
			(pts
				(arc
					(start 62.378336 -243.216684)
					(mid 61.725556 -243.216684)
					(end 62.378336 -243.216684)
				)
			)
		)
	)
	(zone
		(layers "B.Cu" "In11.Cu" "In13.Cu" "In15.Cu")
		(hatch none 0.5)
		(connect_pads
			(clearance 0)
		)
		(min_thickness 0.25)
		(keepout
			(tracks not_allowed)
			(vias allowed)
			(pads allowed)
			(copperpour not_allowed)
			(footprints allowed)
		)
		(placement
			(enabled no)
			(sheetname "")
		)
		(fill yes
			(thermal_gap 0.5)
			(thermal_bridge_width 0.5)
			(island_removal_mode 0)
		)
		(polygon
			(pts
				(arc
					(start 132.15493 -437.889904)
					(mid 131.345178 -437.889904)
					(end 132.15493 -437.889904)
				)
			)
		)
	)
	(zone
		(layers "B.Cu" "In11.Cu" "In13.Cu" "In15.Cu")
		(hatch none 0.5)
		(connect_pads
			(clearance 0)
		)
		(min_thickness 0.25)
		(keepout
			(tracks not_allowed)
			(vias allowed)
			(pads allowed)
			(copperpour not_allowed)
			(footprints allowed)
		)
		(placement
			(enabled no)
			(sheetname "")
		)
		(fill yes
			(thermal_gap 0.5)
			(thermal_bridge_width 0.5)
			(island_removal_mode 0)
		)
		(polygon
			(pts
				(arc
					(start 336.054954 -433.289964)
					(mid 335.245202 -433.289964)
					(end 336.054954 -433.289964)
				)
			)
		)
	)
	(zone
		(layers "B.Cu" "In11.Cu" "In13.Cu" "In15.Cu")
		(hatch none 0.5)
		(connect_pads
			(clearance 0)
		)
		(min_thickness 0.25)
		(keepout
			(tracks not_allowed)
			(vias allowed)
			(pads allowed)
			(copperpour not_allowed)
			(footprints allowed)
		)
		(placement
			(enabled no)
			(sheetname "")
		)
		(fill yes
			(thermal_gap 0.5)
			(thermal_bridge_width 0.5)
			(island_removal_mode 0)
		)
		(polygon
			(pts
				(arc
					(start 284.243272 -300.166786)
					(mid 283.590492 -300.166786)
					(end 284.243272 -300.166786)
				)
			)
		)
	)
	(zone
		(layers "B.Cu" "In11.Cu" "In13.Cu" "In15.Cu")
		(hatch none 0.5)
		(connect_pads
			(clearance 0)
		)
		(min_thickness 0.25)
		(keepout
			(tracks not_allowed)
			(vias allowed)
			(pads allowed)
			(copperpour not_allowed)
			(footprints allowed)
		)
		(placement
			(enabled no)
			(sheetname "")
		)
		(fill yes
			(thermal_gap 0.5)
			(thermal_bridge_width 0.5)
			(island_removal_mode 0)
		)
		(polygon
			(pts
				(arc
					(start 130.292856 -213.732618)
					(mid 129.640076 -213.732618)
					(end 130.292856 -213.732618)
				)
			)
		)
	)
	(zone
		(layers "B.Cu" "In11.Cu" "In13.Cu" "In15.Cu")
		(hatch none 0.5)
		(connect_pads
			(clearance 0)
		)
		(min_thickness 0.25)
		(keepout
			(tracks not_allowed)
			(vias allowed)
			(pads allowed)
			(copperpour not_allowed)
			(footprints allowed)
		)
		(placement
			(enabled no)
			(sheetname "")
		)
		(fill yes
			(thermal_gap 0.5)
			(thermal_bridge_width 0.5)
			(island_removal_mode 0)
		)
		(polygon
			(pts
				(arc
					(start 121.852944 -410.030168)
					(mid 121.149364 -410.030168)
					(end 121.852944 -410.030168)
				)
			)
		)
	)
	(zone
		(layers "B.Cu" "In11.Cu" "In13.Cu" "In15.Cu")
		(hatch none 0.5)
		(connect_pads
			(clearance 0)
		)
		(min_thickness 0.25)
		(keepout
			(tracks not_allowed)
			(vias allowed)
			(pads allowed)
			(copperpour not_allowed)
			(footprints allowed)
		)
		(placement
			(enabled no)
			(sheetname "")
		)
		(fill yes
			(thermal_gap 0.5)
			(thermal_bridge_width 0.5)
			(island_removal_mode 0)
		)
		(polygon
			(pts
				(arc
					(start 58.867548 -410.030168)
					(mid 58.163968 -410.030168)
					(end 58.867548 -410.030168)
				)
			)
		)
	)
	(zone
		(layers "B.Cu" "In11.Cu" "In13.Cu" "In15.Cu")
		(hatch none 0.5)
		(connect_pads
			(clearance 0)
		)
		(min_thickness 0.25)
		(keepout
			(tracks not_allowed)
			(vias allowed)
			(pads allowed)
			(copperpour not_allowed)
			(footprints allowed)
		)
		(placement
			(enabled no)
			(sheetname "")
		)
		(fill yes
			(thermal_gap 0.5)
			(thermal_bridge_width 0.5)
			(island_removal_mode 0)
		)
		(polygon
			(pts
				(arc
					(start 385.37388 -410.030168)
					(mid 384.6703 -410.030168)
					(end 385.37388 -410.030168)
				)
			)
		)
	)
	(zone
		(layers "B.Cu" "In11.Cu" "In13.Cu" "In15.Cu")
		(hatch none 0.5)
		(connect_pads
			(clearance 0)
		)
		(min_thickness 0.25)
		(keepout
			(tracks not_allowed)
			(vias allowed)
			(pads allowed)
			(copperpour not_allowed)
			(footprints allowed)
		)
		(placement
			(enabled no)
			(sheetname "")
		)
		(fill yes
			(thermal_gap 0.5)
			(thermal_bridge_width 0.5)
			(island_removal_mode 0)
		)
		(polygon
			(pts
				(arc
					(start 345.809824 -232.528364)
					(mid 345.157044 -232.528364)
					(end 345.809824 -232.528364)
				)
			)
		)
	)
	(zone
		(layers "B.Cu" "In11.Cu" "In13.Cu" "In15.Cu")
		(hatch none 0.5)
		(connect_pads
			(clearance 0)
		)
		(min_thickness 0.25)
		(keepout
			(tracks not_allowed)
			(vias allowed)
			(pads allowed)
			(copperpour not_allowed)
			(footprints allowed)
		)
		(placement
			(enabled no)
			(sheetname "")
		)
		(fill yes
			(thermal_gap 0.5)
			(thermal_bridge_width 0.5)
			(island_removal_mode 0)
		)
		(polygon
			(pts
				(arc
					(start 127.583184 -274.266914)
					(mid 126.930404 -274.266914)
					(end 127.583184 -274.266914)
				)
			)
		)
	)
	(zone
		(layers "B.Cu" "In11.Cu" "In13.Cu" "In15.Cu")
		(hatch none 0.5)
		(connect_pads
			(clearance 0)
		)
		(min_thickness 0.25)
		(keepout
			(tracks not_allowed)
			(vias allowed)
			(pads allowed)
			(copperpour not_allowed)
			(footprints allowed)
		)
		(placement
			(enabled no)
			(sheetname "")
		)
		(fill yes
			(thermal_gap 0.5)
			(thermal_bridge_width 0.5)
			(island_removal_mode 0)
		)
		(polygon
			(pts
				(arc
					(start 47.290736 -243.216684)
					(mid 46.637956 -243.216684)
					(end 47.290736 -243.216684)
				)
			)
		)
	)
	(zone
		(layers "B.Cu" "In11.Cu" "In13.Cu" "In15.Cu")
		(hatch none 0.5)
		(connect_pads
			(clearance 0)
		)
		(min_thickness 0.25)
		(keepout
			(tracks not_allowed)
			(vias allowed)
			(pads allowed)
			(copperpour not_allowed)
			(footprints allowed)
		)
		(placement
			(enabled no)
			(sheetname "")
		)
		(fill yes
			(thermal_gap 0.5)
			(thermal_bridge_width 0.5)
			(island_removal_mode 0)
		)
		(polygon
			(pts
				(arc
					(start 126.533402 -234.970066)
					(mid 125.880622 -234.970066)
					(end 126.533402 -234.970066)
				)
			)
		)
	)
	(zone
		(layers "B.Cu" "In11.Cu" "In13.Cu" "In15.Cu")
		(hatch none 0.5)
		(connect_pads
			(clearance 0)
		)
		(min_thickness 0.25)
		(keepout
			(tracks not_allowed)
			(vias allowed)
			(pads allowed)
			(copperpour not_allowed)
			(footprints allowed)
		)
		(placement
			(enabled no)
			(sheetname "")
		)
		(fill yes
			(thermal_gap 0.5)
			(thermal_bridge_width 0.5)
			(island_removal_mode 0)
		)
		(polygon
			(pts
				(arc
					(start 381.632206 -253.919736)
					(mid 380.979426 -253.919736)
					(end 381.632206 -253.919736)
				)
			)
		)
	)
	(zone
		(layers "B.Cu" "In11.Cu" "In13.Cu" "In15.Cu")
		(hatch none 0.5)
		(connect_pads
			(clearance 0)
		)
		(min_thickness 0.25)
		(keepout
			(tracks not_allowed)
			(vias allowed)
			(pads allowed)
			(copperpour not_allowed)
			(footprints allowed)
		)
		(placement
			(enabled no)
			(sheetname "")
		)
		(fill yes
			(thermal_gap 0.5)
			(thermal_bridge_width 0.5)
			(island_removal_mode 0)
		)
		(polygon
			(pts
				(arc
					(start 436.150004 -243.216684)
					(mid 435.497224 -243.216684)
					(end 436.150004 -243.216684)
				)
			)
		)
	)
	(zone
		(layers "B.Cu" "In11.Cu" "In13.Cu" "In15.Cu")
		(hatch none 0.5)
		(connect_pads
			(clearance 0)
		)
		(min_thickness 0.25)
		(keepout
			(tracks not_allowed)
			(vias allowed)
			(pads allowed)
			(copperpour not_allowed)
			(footprints allowed)
		)
		(placement
			(enabled no)
			(sheetname "")
		)
		(fill yes
			(thermal_gap 0.5)
			(thermal_bridge_width 0.5)
			(island_removal_mode 0)
		)
		(polygon
			(pts
				(arc
					(start 349.208852 -280.778204)
					(mid 348.556072 -280.778204)
					(end 349.208852 -280.778204)
				)
			)
		)
	)
	(zone
		(layers "B.Cu" "In11.Cu" "In13.Cu" "In15.Cu")
		(hatch none 0.5)
		(connect_pads
			(clearance 0)
		)
		(min_thickness 0.25)
		(keepout
			(tracks not_allowed)
			(vias allowed)
			(pads allowed)
			(copperpour not_allowed)
			(footprints allowed)
		)
		(placement
			(enabled no)
			(sheetname "")
		)
		(fill yes
			(thermal_gap 0.5)
			(thermal_bridge_width 0.5)
			(island_removal_mode 0)
		)
		(polygon
			(pts
				(arc
					(start 344.040206 -273.453098)
					(mid 343.387426 -273.453098)
					(end 344.040206 -273.453098)
				)
			)
		)
	)
	(zone
		(layers "B.Cu" "In11.Cu" "In13.Cu" "In15.Cu")
		(hatch none 0.5)
		(connect_pads
			(clearance 0)
		)
		(min_thickness 0.25)
		(keepout
			(tracks not_allowed)
			(vias allowed)
			(pads allowed)
			(copperpour not_allowed)
			(footprints allowed)
		)
		(placement
			(enabled no)
			(sheetname "")
		)
		(fill yes
			(thermal_gap 0.5)
			(thermal_bridge_width 0.5)
			(island_removal_mode 0)
		)
		(polygon
			(pts
				(arc
					(start 405.154892 -431.889916)
					(mid 404.34514 -431.889916)
					(end 405.154892 -431.889916)
				)
			)
		)
	)
	(zone
		(layers "B.Cu" "In11.Cu" "In13.Cu" "In15.Cu")
		(hatch none 0.5)
		(connect_pads
			(clearance 0)
		)
		(min_thickness 0.25)
		(keepout
			(tracks not_allowed)
			(vias allowed)
			(pads allowed)
			(copperpour not_allowed)
			(footprints allowed)
		)
		(placement
			(enabled no)
			(sheetname "")
		)
		(fill yes
			(thermal_gap 0.5)
			(thermal_bridge_width 0.5)
			(island_removal_mode 0)
		)
		(polygon
			(pts
				(arc
					(start 348.739206 -253.919736)
					(mid 348.086426 -253.919736)
					(end 348.739206 -253.919736)
				)
			)
		)
	)
	(zone
		(layers "B.Cu" "In11.Cu" "In13.Cu" "In15.Cu")
		(hatch none 0.5)
		(connect_pads
			(clearance 0)
		)
		(min_thickness 0.25)
		(keepout
			(tracks not_allowed)
			(vias allowed)
			(pads allowed)
			(copperpour not_allowed)
			(footprints allowed)
		)
		(placement
			(enabled no)
			(sheetname "")
		)
		(fill yes
			(thermal_gap 0.5)
			(thermal_bridge_width 0.5)
			(island_removal_mode 0)
		)
		(polygon
			(pts
				(arc
					(start 97.979738 -265.314176)
					(mid 97.326958 -265.314176)
					(end 97.979738 -265.314176)
				)
			)
		)
	)
	(zone
		(layers "B.Cu" "In11.Cu" "In13.Cu" "In15.Cu")
		(hatch none 0.5)
		(connect_pads
			(clearance 0)
		)
		(min_thickness 0.25)
		(keepout
			(tracks not_allowed)
			(vias allowed)
			(pads allowed)
			(copperpour not_allowed)
			(footprints allowed)
		)
		(placement
			(enabled no)
			(sheetname "")
		)
		(fill yes
			(thermal_gap 0.5)
			(thermal_bridge_width 0.5)
			(island_removal_mode 0)
		)
		(polygon
			(pts
				(arc
					(start 165.553136 -244.066568)
					(mid 164.900356 -244.066568)
					(end 165.553136 -244.066568)
				)
			)
		)
	)
	(zone
		(layers "B.Cu" "In11.Cu" "In13.Cu" "In15.Cu")
		(hatch none 0.5)
		(connect_pads
			(clearance 0)
		)
		(min_thickness 0.25)
		(keepout
			(tracks not_allowed)
			(vias allowed)
			(pads allowed)
			(copperpour not_allowed)
			(footprints allowed)
		)
		(placement
			(enabled no)
			(sheetname "")
		)
		(fill yes
			(thermal_gap 0.5)
			(thermal_bridge_width 0.5)
			(island_removal_mode 0)
		)
		(polygon
			(pts
				(arc
					(start 384.341624 -219.506038)
					(mid 383.688844 -219.506038)
					(end 384.341624 -219.506038)
				)
			)
		)
	)
	(zone
		(layers "B.Cu" "In11.Cu" "In13.Cu" "In15.Cu")
		(hatch none 0.5)
		(connect_pads
			(clearance 0)
		)
		(min_thickness 0.25)
		(keepout
			(tracks not_allowed)
			(vias allowed)
			(pads allowed)
			(copperpour not_allowed)
			(footprints allowed)
		)
		(placement
			(enabled no)
			(sheetname "")
		)
		(fill yes
			(thermal_gap 0.5)
			(thermal_bridge_width 0.5)
			(island_removal_mode 0)
		)
		(polygon
			(pts
				(arc
					(start 86.436708 -410.030168)
					(mid 85.733128 -410.030168)
					(end 86.436708 -410.030168)
				)
			)
		)
	)
	(zone
		(layers "B.Cu" "In11.Cu" "In13.Cu" "In15.Cu")
		(hatch none 0.5)
		(connect_pads
			(clearance 0)
		)
		(min_thickness 0.25)
		(keepout
			(tracks not_allowed)
			(vias allowed)
			(pads allowed)
			(copperpour not_allowed)
			(footprints allowed)
		)
		(placement
			(enabled no)
			(sheetname "")
		)
		(fill yes
			(thermal_gap 0.5)
			(thermal_bridge_width 0.5)
			(island_removal_mode 0)
		)
		(polygon
			(pts
				(arc
					(start 249.500136 2.4892)
					(mid 248.796556 2.4892)
					(end 249.500136 2.4892)
				)
			)
		)
	)
	(zone
		(layers "B.Cu" "In11.Cu" "In13.Cu" "In15.Cu")
		(hatch none 0.5)
		(connect_pads
			(clearance 0)
		)
		(min_thickness 0.25)
		(keepout
			(tracks not_allowed)
			(vias allowed)
			(pads allowed)
			(copperpour not_allowed)
			(footprints allowed)
		)
		(placement
			(enabled no)
			(sheetname "")
		)
		(fill yes
			(thermal_gap 0.5)
			(thermal_bridge_width 0.5)
			(island_removal_mode 0)
		)
		(polygon
			(pts
				(arc
					(start 188.209936 -280.61666)
					(mid 187.557156 -280.61666)
					(end 188.209936 -280.61666)
				)
			)
		)
	)
	(zone
		(layers "B.Cu" "In11.Cu" "In13.Cu" "In15.Cu")
		(hatch none 0.5)
		(connect_pads
			(clearance 0)
		)
		(min_thickness 0.25)
		(keepout
			(tracks not_allowed)
			(vias allowed)
			(pads allowed)
			(copperpour not_allowed)
			(footprints allowed)
		)
		(placement
			(enabled no)
			(sheetname "")
		)
		(fill yes
			(thermal_gap 0.5)
			(thermal_bridge_width 0.5)
			(island_removal_mode 0)
		)
		(polygon
			(pts
				(arc
					(start 375.523252 -266.128246)
					(mid 374.870472 -266.128246)
					(end 375.523252 -266.128246)
				)
			)
		)
	)
	(zone
		(layers "B.Cu" "In11.Cu" "In13.Cu" "In15.Cu")
		(hatch none 0.5)
		(connect_pads
			(clearance 0)
		)
		(min_thickness 0.25)
		(keepout
			(tracks not_allowed)
			(vias allowed)
			(pads allowed)
			(copperpour not_allowed)
			(footprints allowed)
		)
		(placement
			(enabled no)
			(sheetname "")
		)
		(fill yes
			(thermal_gap 0.5)
			(thermal_bridge_width 0.5)
			(island_removal_mode 0)
		)
		(polygon
			(pts
				(arc
					(start 354.847652 -282.405836)
					(mid 354.194872 -282.405836)
					(end 354.847652 -282.405836)
				)
			)
		)
	)
	(zone
		(layers "B.Cu" "In11.Cu" "In13.Cu" "In15.Cu")
		(hatch none 0.5)
		(connect_pads
			(clearance 0)
		)
		(min_thickness 0.25)
		(keepout
			(tracks not_allowed)
			(vias allowed)
			(pads allowed)
			(copperpour not_allowed)
			(footprints allowed)
		)
		(placement
			(enabled no)
			(sheetname "")
		)
		(fill yes
			(thermal_gap 0.5)
			(thermal_bridge_width 0.5)
			(island_removal_mode 0)
		)
		(polygon
			(pts
				(arc
					(start 137.811256 -217.064336)
					(mid 137.158476 -217.064336)
					(end 137.811256 -217.064336)
				)
			)
		)
	)
	(zone
		(layers "B.Cu" "In11.Cu" "In13.Cu" "In15.Cu")
		(hatch none 0.5)
		(connect_pads
			(clearance 0)
		)
		(min_thickness 0.25)
		(keepout
			(tracks not_allowed)
			(vias allowed)
			(pads allowed)
			(copperpour not_allowed)
			(footprints allowed)
		)
		(placement
			(enabled no)
			(sheetname "")
		)
		(fill yes
			(thermal_gap 0.5)
			(thermal_bridge_width 0.5)
			(island_removal_mode 0)
		)
		(polygon
			(pts
				(arc
					(start 329.054968 -434.289962)
					(mid 328.245216 -434.289962)
					(end 329.054968 -434.289962)
				)
			)
		)
	)
	(zone
		(layers "B.Cu" "In11.Cu" "In13.Cu" "In15.Cu")
		(hatch none 0.5)
		(connect_pads
			(clearance 0)
		)
		(min_thickness 0.25)
		(keepout
			(tracks not_allowed)
			(vias allowed)
			(pads allowed)
			(copperpour not_allowed)
			(footprints allowed)
		)
		(placement
			(enabled no)
			(sheetname "")
		)
		(fill yes
			(thermal_gap 0.5)
			(thermal_bridge_width 0.5)
			(island_removal_mode 0)
		)
		(polygon
			(pts
				(arc
					(start 61.930788 -410.030168)
					(mid 61.227208 -410.030168)
					(end 61.930788 -410.030168)
				)
			)
		)
	)
	(zone
		(layers "B.Cu" "In11.Cu" "In13.Cu" "In15.Cu")
		(hatch none 0.5)
		(connect_pads
			(clearance 0)
		)
		(min_thickness 0.25)
		(keepout
			(tracks not_allowed)
			(vias allowed)
			(pads allowed)
			(copperpour not_allowed)
			(footprints allowed)
		)
		(placement
			(enabled no)
			(sheetname "")
		)
		(fill yes
			(thermal_gap 0.5)
			(thermal_bridge_width 0.5)
			(island_removal_mode 0)
		)
		(polygon
			(pts
				(arc
					(start 9.571736 -244.066568)
					(mid 8.918956 -244.066568)
					(end 9.571736 -244.066568)
				)
			)
		)
	)
	(zone
		(layers "B.Cu" "In11.Cu" "In13.Cu" "In15.Cu")
		(hatch none 0.5)
		(connect_pads
			(clearance 0)
		)
		(min_thickness 0.25)
		(keepout
			(tracks not_allowed)
			(vias allowed)
			(pads allowed)
			(copperpour not_allowed)
			(footprints allowed)
		)
		(placement
			(enabled no)
			(sheetname "")
		)
		(fill yes
			(thermal_gap 0.5)
			(thermal_bridge_width 0.5)
			(island_removal_mode 0)
		)
		(polygon
			(pts
				(arc
					(start 184.004204 3.3528)
					(mid 183.300624 3.3528)
					(end 184.004204 3.3528)
				)
			)
		)
	)
	(zone
		(layers "B.Cu" "In11.Cu" "In13.Cu" "In15.Cu")
		(hatch none 0.5)
		(connect_pads
			(clearance 0)
		)
		(min_thickness 0.25)
		(keepout
			(tracks not_allowed)
			(vias allowed)
			(pads allowed)
			(copperpour not_allowed)
			(footprints allowed)
		)
		(placement
			(enabled no)
			(sheetname "")
		)
		(fill yes
			(thermal_gap 0.5)
			(thermal_bridge_width 0.5)
			(island_removal_mode 0)
		)
		(polygon
			(pts
				(arc
					(start 122.304048 -214.622634)
					(mid 121.651268 -214.622634)
					(end 122.304048 -214.622634)
				)
			)
		)
	)
	(zone
		(layers "B.Cu" "In11.Cu" "In13.Cu" "In15.Cu")
		(hatch none 0.5)
		(connect_pads
			(clearance 0)
		)
		(min_thickness 0.25)
		(keepout
			(tracks not_allowed)
			(vias allowed)
			(pads allowed)
			(copperpour not_allowed)
			(footprints allowed)
		)
		(placement
			(enabled no)
			(sheetname "")
		)
		(fill yes
			(thermal_gap 0.5)
			(thermal_bridge_width 0.5)
			(island_removal_mode 0)
		)
		(polygon
			(pts
				(arc
					(start 156.30017 -47.943008)
					(mid 155.59659 -47.943008)
					(end 156.30017 -47.943008)
				)
			)
		)
	)
	(zone
		(layers "B.Cu" "In11.Cu" "In13.Cu" "In15.Cu")
		(hatch none 0.5)
		(connect_pads
			(clearance 0)
		)
		(min_thickness 0.25)
		(keepout
			(tracks not_allowed)
			(vias allowed)
			(pads allowed)
			(copperpour not_allowed)
			(footprints allowed)
		)
		(placement
			(enabled no)
			(sheetname "")
		)
		(fill yes
			(thermal_gap 0.5)
			(thermal_bridge_width 0.5)
			(island_removal_mode 0)
		)
		(polygon
			(pts
				(arc
					(start 440.250072 -287.416748)
					(mid 439.597292 -287.416748)
					(end 440.250072 -287.416748)
				)
			)
		)
	)
	(zone
		(layers "B.Cu" "In11.Cu" "In13.Cu" "In15.Cu")
		(hatch none 0.5)
		(connect_pads
			(clearance 0)
		)
		(min_thickness 0.25)
		(keepout
			(tracks not_allowed)
			(vias allowed)
			(pads allowed)
			(copperpour not_allowed)
			(footprints allowed)
		)
		(placement
			(enabled no)
			(sheetname "")
		)
		(fill yes
			(thermal_gap 0.5)
			(thermal_bridge_width 0.5)
			(island_removal_mode 0)
		)
		(polygon
			(pts
				(arc
					(start 344.980006 -266.941808)
					(mid 344.327226 -266.941808)
					(end 344.980006 -266.941808)
				)
			)
		)
	)
	(zone
		(layers "B.Cu" "In11.Cu" "In13.Cu" "In15.Cu")
		(hatch none 0.5)
		(connect_pads
			(clearance 0)
		)
		(min_thickness 0.25)
		(keepout
			(tracks not_allowed)
			(vias allowed)
			(pads allowed)
			(copperpour not_allowed)
			(footprints allowed)
		)
		(placement
			(enabled no)
			(sheetname "")
		)
		(fill yes
			(thermal_gap 0.5)
			(thermal_bridge_width 0.5)
			(island_removal_mode 0)
		)
		(polygon
			(pts
				(arc
					(start 188.209936 -232.166668)
					(mid 187.557156 -232.166668)
					(end 188.209936 -232.166668)
				)
			)
		)
	)
	(zone
		(layers "B.Cu" "In11.Cu" "In13.Cu" "In15.Cu")
		(hatch none 0.5)
		(connect_pads
			(clearance 0)
		)
		(min_thickness 0.25)
		(keepout
			(tracks not_allowed)
			(vias allowed)
			(pads allowed)
			(copperpour not_allowed)
			(footprints allowed)
		)
		(placement
			(enabled no)
			(sheetname "")
		)
		(fill yes
			(thermal_gap 0.5)
			(thermal_bridge_width 0.5)
			(island_removal_mode 0)
		)
		(polygon
			(pts
				(arc
					(start 87.171784 -280.778204)
					(mid 86.519004 -280.778204)
					(end 87.171784 -280.778204)
				)
			)
		)
	)
	(zone
		(layers "B.Cu" "In11.Cu" "In13.Cu" "In15.Cu")
		(hatch none 0.5)
		(connect_pads
			(clearance 0)
		)
		(min_thickness 0.25)
		(keepout
			(tracks not_allowed)
			(vias allowed)
			(pads allowed)
			(copperpour not_allowed)
			(footprints allowed)
		)
		(placement
			(enabled no)
			(sheetname "")
		)
		(fill yes
			(thermal_gap 0.5)
			(thermal_bridge_width 0.5)
			(island_removal_mode 0)
		)
		(polygon
			(pts
				(arc
					(start 108.677202 -215.436704)
					(mid 108.024422 -215.436704)
					(end 108.677202 -215.436704)
				)
			)
		)
	)
	(zone
		(layers "B.Cu" "In11.Cu" "In13.Cu" "In15.Cu")
		(hatch none 0.5)
		(connect_pads
			(clearance 0)
		)
		(min_thickness 0.25)
		(keepout
			(tracks not_allowed)
			(vias allowed)
			(pads allowed)
			(copperpour not_allowed)
			(footprints allowed)
		)
		(placement
			(enabled no)
			(sheetname "")
		)
		(fill yes
			(thermal_gap 0.5)
			(thermal_bridge_width 0.5)
			(island_removal_mode 0)
		)
		(polygon
			(pts
				(arc
					(start 421.062404 -244.066568)
					(mid 420.409624 -244.066568)
					(end 421.062404 -244.066568)
				)
			)
		)
	)
	(zone
		(layers "B.Cu" "In11.Cu" "In13.Cu" "In15.Cu")
		(hatch none 0.5)
		(connect_pads
			(clearance 0)
		)
		(min_thickness 0.25)
		(keepout
			(tracks not_allowed)
			(vias allowed)
			(pads allowed)
			(copperpour not_allowed)
			(footprints allowed)
		)
		(placement
			(enabled no)
			(sheetname "")
		)
		(fill yes
			(thermal_gap 0.5)
			(thermal_bridge_width 0.5)
			(island_removal_mode 0)
		)
		(polygon
			(pts
				(arc
					(start 63.054992 -427.289976)
					(mid 62.24524 -427.289976)
					(end 63.054992 -427.289976)
				)
			)
		)
	)
	(zone
		(layers "B.Cu" "In11.Cu" "In13.Cu" "In15.Cu")
		(hatch none 0.5)
		(connect_pads
			(clearance 0)
		)
		(min_thickness 0.25)
		(keepout
			(tracks not_allowed)
			(vias allowed)
			(pads allowed)
			(copperpour not_allowed)
			(footprints allowed)
		)
		(placement
			(enabled no)
			(sheetname "")
		)
		(fill yes
			(thermal_gap 0.5)
			(thermal_bridge_width 0.5)
			(island_removal_mode 0)
		)
		(polygon
			(pts
				(arc
					(start 97.039938 -276.708616)
					(mid 96.387158 -276.708616)
					(end 97.039938 -276.708616)
				)
			)
		)
	)
	(zone
		(layers "B.Cu" "In11.Cu" "In13.Cu" "In15.Cu")
		(hatch none 0.5)
		(connect_pads
			(clearance 0)
		)
		(min_thickness 0.25)
		(keepout
			(tracks not_allowed)
			(vias allowed)
			(pads allowed)
			(copperpour not_allowed)
			(footprints allowed)
		)
		(placement
			(enabled no)
			(sheetname "")
		)
		(fill yes
			(thermal_gap 0.5)
			(thermal_bridge_width 0.5)
			(island_removal_mode 0)
		)
		(polygon
			(pts
				(arc
					(start 155.154884 -436.889906)
					(mid 154.345132 -436.889906)
					(end 155.154884 -436.889906)
				)
			)
		)
	)
	(zone
		(layers "B.Cu" "In11.Cu" "In13.Cu" "In15.Cu")
		(hatch none 0.5)
		(connect_pads
			(clearance 0)
		)
		(min_thickness 0.25)
		(keepout
			(tracks not_allowed)
			(vias allowed)
			(pads allowed)
			(copperpour not_allowed)
			(footprints allowed)
		)
		(placement
			(enabled no)
			(sheetname "")
		)
		(fill yes
			(thermal_gap 0.5)
			(thermal_bridge_width 0.5)
			(island_removal_mode 0)
		)
		(polygon
			(pts
				(arc
					(start 97.979738 -270.19758)
					(mid 97.326958 -270.19758)
					(end 97.979738 -270.19758)
				)
			)
		)
	)
	(zone
		(layers "B.Cu" "In11.Cu" "In13.Cu" "In15.Cu")
		(hatch none 0.5)
		(connect_pads
			(clearance 0)
		)
		(min_thickness 0.25)
		(keepout
			(tracks not_allowed)
			(vias allowed)
			(pads allowed)
			(copperpour not_allowed)
			(footprints allowed)
		)
		(placement
			(enabled no)
			(sheetname "")
		)
		(fill yes
			(thermal_gap 0.5)
			(thermal_bridge_width 0.5)
			(island_removal_mode 0)
		)
		(polygon
			(pts
				(arc
					(start 383.511552 -253.919736)
					(mid 382.858772 -253.919736)
					(end 383.511552 -253.919736)
				)
			)
		)
	)
	(zone
		(layers "B.Cu" "In11.Cu" "In13.Cu" "In15.Cu")
		(hatch none 0.5)
		(connect_pads
			(clearance 0)
		)
		(min_thickness 0.25)
		(keepout
			(tracks not_allowed)
			(vias allowed)
			(pads allowed)
			(copperpour not_allowed)
			(footprints allowed)
		)
		(placement
			(enabled no)
			(sheetname "")
		)
		(fill yes
			(thermal_gap 0.5)
			(thermal_bridge_width 0.5)
			(island_removal_mode 0)
		)
		(polygon
			(pts
				(arc
					(start 374.259094 -174.343568)
					(mid 373.555514 -174.343568)
					(end 374.259094 -174.343568)
				)
			)
		)
	)
	(zone
		(layers "B.Cu" "In11.Cu" "In13.Cu" "In15.Cu")
		(hatch none 0.5)
		(connect_pads
			(clearance 0)
		)
		(min_thickness 0.25)
		(keepout
			(tracks not_allowed)
			(vias allowed)
			(pads allowed)
			(copperpour not_allowed)
			(footprints allowed)
		)
		(placement
			(enabled no)
			(sheetname "")
		)
		(fill yes
			(thermal_gap 0.5)
			(thermal_bridge_width 0.5)
			(island_removal_mode 0)
		)
		(polygon
			(pts
				(arc
					(start 128.413002 -238.225584)
					(mid 127.760222 -238.225584)
					(end 128.413002 -238.225584)
				)
			)
		)
	)
	(zone
		(layers "B.Cu" "In11.Cu" "In13.Cu" "In15.Cu")
		(hatch none 0.5)
		(connect_pads
			(clearance 0)
		)
		(min_thickness 0.25)
		(keepout
			(tracks not_allowed)
			(vias allowed)
			(pads allowed)
			(copperpour not_allowed)
			(footprints allowed)
		)
		(placement
			(enabled no)
			(sheetname "")
		)
		(fill yes
			(thermal_gap 0.5)
			(thermal_bridge_width 0.5)
			(island_removal_mode 0)
		)
		(polygon
			(pts
				(arc
					(start 334.641952 -284.847538)
					(mid 333.989172 -284.847538)
					(end 334.641952 -284.847538)
				)
			)
		)
	)
	(zone
		(layers "B.Cu" "In11.Cu" "In13.Cu" "In15.Cu")
		(hatch none 0.5)
		(connect_pads
			(clearance 0)
		)
		(min_thickness 0.25)
		(keepout
			(tracks not_allowed)
			(vias allowed)
			(pads allowed)
			(copperpour not_allowed)
			(footprints allowed)
		)
		(placement
			(enabled no)
			(sheetname "")
		)
		(fill yes
			(thermal_gap 0.5)
			(thermal_bridge_width 0.5)
			(island_removal_mode 0)
		)
		(polygon
			(pts
				(arc
					(start 119.954802 -215.436704)
					(mid 119.302022 -215.436704)
					(end 119.954802 -215.436704)
				)
			)
		)
	)
	(zone
		(layers "B.Cu" "In11.Cu" "In13.Cu" "In15.Cu")
		(hatch none 0.5)
		(connect_pads
			(clearance 0)
		)
		(min_thickness 0.25)
		(keepout
			(tracks not_allowed)
			(vias allowed)
			(pads allowed)
			(copperpour not_allowed)
			(footprints allowed)
		)
		(placement
			(enabled no)
			(sheetname "")
		)
		(fill yes
			(thermal_gap 0.5)
			(thermal_bridge_width 0.5)
			(island_removal_mode 0)
		)
		(polygon
			(pts
				(arc
					(start 358.967024 -227.64496)
					(mid 358.314244 -227.64496)
					(end 358.967024 -227.64496)
				)
			)
		)
	)
	(zone
		(layers "B.Cu" "In11.Cu" "In13.Cu" "In15.Cu")
		(hatch none 0.5)
		(connect_pads
			(clearance 0)
		)
		(min_thickness 0.25)
		(keepout
			(tracks not_allowed)
			(vias allowed)
			(pads allowed)
			(copperpour not_allowed)
			(footprints allowed)
		)
		(placement
			(enabled no)
			(sheetname "")
		)
		(fill yes
			(thermal_gap 0.5)
			(thermal_bridge_width 0.5)
			(island_removal_mode 0)
		)
		(polygon
			(pts
				(arc
					(start 32.203136 -305.266598)
					(mid 31.550356 -305.266598)
					(end 32.203136 -305.266598)
				)
			)
		)
	)
	(zone
		(layers "B.Cu" "In11.Cu" "In13.Cu" "In15.Cu")
		(hatch none 0.5)
		(connect_pads
			(clearance 0)
		)
		(min_thickness 0.25)
		(keepout
			(tracks not_allowed)
			(vias allowed)
			(pads allowed)
			(copperpour not_allowed)
			(footprints allowed)
		)
		(placement
			(enabled no)
			(sheetname "")
		)
		(fill yes
			(thermal_gap 0.5)
			(thermal_bridge_width 0.5)
			(island_removal_mode 0)
		)
		(polygon
			(pts
				(arc
					(start 375.523252 -275.8948)
					(mid 374.870472 -275.8948)
					(end 375.523252 -275.8948)
				)
			)
		)
	)
	(zone
		(layers "B.Cu" "In11.Cu" "In13.Cu" "In15.Cu")
		(hatch none 0.5)
		(connect_pads
			(clearance 0)
		)
		(min_thickness 0.25)
		(keepout
			(tracks not_allowed)
			(vias allowed)
			(pads allowed)
			(copperpour not_allowed)
			(footprints allowed)
		)
		(placement
			(enabled no)
			(sheetname "")
		)
		(fill yes
			(thermal_gap 0.5)
			(thermal_bridge_width 0.5)
			(island_removal_mode 0)
		)
		(polygon
			(pts
				(arc
					(start 353.907852 -282.405836)
					(mid 353.255072 -282.405836)
					(end 353.907852 -282.405836)
				)
			)
		)
	)
	(zone
		(layers "B.Cu" "In11.Cu" "In13.Cu" "In15.Cu")
		(hatch none 0.5)
		(connect_pads
			(clearance 0)
		)
		(min_thickness 0.25)
		(keepout
			(tracks not_allowed)
			(vias allowed)
			(pads allowed)
			(copperpour not_allowed)
			(footprints allowed)
		)
		(placement
			(enabled no)
			(sheetname "")
		)
		(fill yes
			(thermal_gap 0.5)
			(thermal_bridge_width 0.5)
			(island_removal_mode 0)
		)
		(polygon
			(pts
				(arc
					(start 127.003556 -240.667286)
					(mid 126.350776 -240.667286)
					(end 127.003556 -240.667286)
				)
			)
		)
	)
	(zone
		(layers "B.Cu" "In11.Cu" "In13.Cu" "In15.Cu")
		(hatch none 0.5)
		(connect_pads
			(clearance 0)
		)
		(min_thickness 0.25)
		(keepout
			(tracks not_allowed)
			(vias allowed)
			(pads allowed)
			(copperpour not_allowed)
			(footprints allowed)
		)
		(placement
			(enabled no)
			(sheetname "")
		)
		(fill yes
			(thermal_gap 0.5)
			(thermal_bridge_width 0.5)
			(island_removal_mode 0)
		)
		(polygon
			(pts
				(arc
					(start 82.054954 -435.489858)
					(mid 81.245202 -435.489858)
					(end 82.054954 -435.489858)
				)
			)
		)
	)
	(zone
		(layers "B.Cu" "In11.Cu" "In13.Cu" "In15.Cu")
		(hatch none 0.5)
		(connect_pads
			(clearance 0)
		)
		(min_thickness 0.25)
		(keepout
			(tracks not_allowed)
			(vias allowed)
			(pads allowed)
			(copperpour not_allowed)
			(footprints allowed)
		)
		(placement
			(enabled no)
			(sheetname "")
		)
		(fill yes
			(thermal_gap 0.5)
			(thermal_bridge_width 0.5)
			(island_removal_mode 0)
		)
		(polygon
			(pts
				(arc
					(start 32.203136 -271.266666)
					(mid 31.550356 -271.266666)
					(end 32.203136 -271.266666)
				)
			)
		)
	)
	(zone
		(layers "B.Cu" "In11.Cu" "In13.Cu" "In15.Cu")
		(hatch none 0.5)
		(connect_pads
			(clearance 0)
		)
		(min_thickness 0.25)
		(keepout
			(tracks not_allowed)
			(vias allowed)
			(pads allowed)
			(copperpour not_allowed)
			(footprints allowed)
		)
		(placement
			(enabled no)
			(sheetname "")
		)
		(fill yes
			(thermal_gap 0.5)
			(thermal_bridge_width 0.5)
			(island_removal_mode 0)
		)
		(polygon
			(pts
				(arc
					(start 302.774604 -243.216684)
					(mid 302.121824 -243.216684)
					(end 302.774604 -243.216684)
				)
			)
		)
	)
	(zone
		(layers "B.Cu" "In11.Cu" "In13.Cu" "In15.Cu")
		(hatch none 0.5)
		(connect_pads
			(clearance 0)
		)
		(min_thickness 0.25)
		(keepout
			(tracks not_allowed)
			(vias allowed)
			(pads allowed)
			(copperpour not_allowed)
			(footprints allowed)
		)
		(placement
			(enabled no)
			(sheetname "")
		)
		(fill yes
			(thermal_gap 0.5)
			(thermal_bridge_width 0.5)
			(island_removal_mode 0)
		)
		(polygon
			(pts
				(arc
					(start 207.397604 -212.616796)
					(mid 206.744824 -212.616796)
					(end 207.397604 -212.616796)
				)
			)
		)
	)
	(zone
		(layers "B.Cu" "In11.Cu" "In13.Cu" "In15.Cu")
		(hatch none 0.5)
		(connect_pads
			(clearance 0)
		)
		(min_thickness 0.25)
		(keepout
			(tracks not_allowed)
			(vias allowed)
			(pads allowed)
			(copperpour not_allowed)
			(footprints allowed)
		)
		(placement
			(enabled no)
			(sheetname "")
		)
		(fill yes
			(thermal_gap 0.5)
			(thermal_bridge_width 0.5)
			(island_removal_mode 0)
		)
		(polygon
			(pts
				(arc
					(start 32.203136 -243.216684)
					(mid 31.550356 -243.216684)
					(end 32.203136 -243.216684)
				)
			)
		)
	)
	(zone
		(layers "B.Cu" "In11.Cu" "In13.Cu" "In15.Cu")
		(hatch none 0.5)
		(connect_pads
			(clearance 0)
		)
		(min_thickness 0.25)
		(keepout
			(tracks not_allowed)
			(vias allowed)
			(pads allowed)
			(copperpour not_allowed)
			(footprints allowed)
		)
		(placement
			(enabled no)
			(sheetname "")
		)
		(fill yes
			(thermal_gap 0.5)
			(thermal_bridge_width 0.5)
			(island_removal_mode 0)
		)
		(polygon
			(pts
				(arc
					(start 110.556802 -215.436704)
					(mid 109.904022 -215.436704)
					(end 110.556802 -215.436704)
				)
			)
		)
	)
	(zone
		(layers "B.Cu" "In11.Cu" "In13.Cu" "In15.Cu")
		(hatch none 0.5)
		(connect_pads
			(clearance 0)
		)
		(min_thickness 0.25)
		(keepout
			(tracks not_allowed)
			(vias allowed)
			(pads allowed)
			(copperpour not_allowed)
			(footprints allowed)
		)
		(placement
			(enabled no)
			(sheetname "")
		)
		(fill yes
			(thermal_gap 0.5)
			(thermal_bridge_width 0.5)
			(island_removal_mode 0)
		)
		(polygon
			(pts
				(arc
					(start 96.460056 -213.732618)
					(mid 95.807276 -213.732618)
					(end 96.460056 -213.732618)
				)
			)
		)
	)
	(zone
		(layers "B.Cu" "In11.Cu" "In13.Cu" "In15.Cu")
		(hatch none 0.5)
		(connect_pads
			(clearance 0)
		)
		(min_thickness 0.25)
		(keepout
			(tracks not_allowed)
			(vias allowed)
			(pads allowed)
			(copperpour not_allowed)
			(footprints allowed)
		)
		(placement
			(enabled no)
			(sheetname "")
		)
		(fill yes
			(thermal_gap 0.5)
			(thermal_bridge_width 0.5)
			(island_removal_mode 0)
		)
		(polygon
			(pts
				(arc
					(start 355.207824 -227.64496)
					(mid 354.555044 -227.64496)
					(end 355.207824 -227.64496)
				)
			)
		)
	)
	(zone
		(layers "B.Cu" "In11.Cu" "In13.Cu" "In15.Cu")
		(hatch none 0.5)
		(connect_pads
			(clearance 0)
		)
		(min_thickness 0.25)
		(keepout
			(tracks not_allowed)
			(vias allowed)
			(pads allowed)
			(copperpour not_allowed)
			(footprints allowed)
		)
		(placement
			(enabled no)
			(sheetname "")
		)
		(fill yes
			(thermal_gap 0.5)
			(thermal_bridge_width 0.5)
			(island_removal_mode 0)
		)
		(polygon
			(pts
				(arc
					(start 229.54869 -56.506872)
					(mid 228.84511 -56.506872)
					(end 229.54869 -56.506872)
				)
			)
		)
	)
	(zone
		(layers "B.Cu" "In11.Cu" "In13.Cu" "In15.Cu")
		(hatch none 0.5)
		(connect_pads
			(clearance 0)
		)
		(min_thickness 0.25)
		(keepout
			(tracks not_allowed)
			(vias allowed)
			(pads allowed)
			(copperpour not_allowed)
			(footprints allowed)
		)
		(placement
			(enabled no)
			(sheetname "")
		)
		(fill yes
			(thermal_gap 0.5)
			(thermal_bridge_width 0.5)
			(island_removal_mode 0)
		)
		(polygon
			(pts
				(arc
					(start 96.100138 -265.314176)
					(mid 95.447358 -265.314176)
					(end 96.100138 -265.314176)
				)
			)
		)
	)
	(zone
		(layers "B.Cu" "In11.Cu" "In13.Cu" "In15.Cu")
		(hatch none 0.5)
		(connect_pads
			(clearance 0)
		)
		(min_thickness 0.25)
		(keepout
			(tracks not_allowed)
			(vias allowed)
			(pads allowed)
			(copperpour not_allowed)
			(footprints allowed)
		)
		(placement
			(enabled no)
			(sheetname "")
		)
		(fill yes
			(thermal_gap 0.5)
			(thermal_bridge_width 0.5)
			(island_removal_mode 0)
		)
		(polygon
			(pts
				(arc
					(start 280.143204 -204.116686)
					(mid 279.490424 -204.116686)
					(end 280.143204 -204.116686)
				)
			)
		)
	)
	(zone
		(layers "B.Cu" "In11.Cu" "In13.Cu" "In15.Cu")
		(hatch none 0.5)
		(connect_pads
			(clearance 0)
		)
		(min_thickness 0.25)
		(keepout
			(tracks not_allowed)
			(vias allowed)
			(pads allowed)
			(copperpour not_allowed)
			(footprints allowed)
		)
		(placement
			(enabled no)
			(sheetname "")
		)
		(fill yes
			(thermal_gap 0.5)
			(thermal_bridge_width 0.5)
			(island_removal_mode 0)
		)
		(polygon
			(pts
				(arc
					(start 36.303204 -273.816572)
					(mid 35.650424 -273.816572)
					(end 36.303204 -273.816572)
				)
			)
		)
	)
	(zone
		(layers "B.Cu" "In11.Cu" "In13.Cu" "In15.Cu")
		(hatch none 0.5)
		(connect_pads
			(clearance 0)
		)
		(min_thickness 0.25)
		(keepout
			(tracks not_allowed)
			(vias allowed)
			(pads allowed)
			(copperpour not_allowed)
			(footprints allowed)
		)
		(placement
			(enabled no)
			(sheetname "")
		)
		(fill yes
			(thermal_gap 0.5)
			(thermal_bridge_width 0.5)
			(island_removal_mode 0)
		)
		(polygon
			(pts
				(arc
					(start 314.385198 -403.883876)
					(mid 313.681618 -403.883876)
					(end 314.385198 -403.883876)
				)
			)
		)
	)
	(zone
		(layers "B.Cu" "In11.Cu" "In13.Cu" "In15.Cu")
		(hatch none 0.5)
		(connect_pads
			(clearance 0)
		)
		(min_thickness 0.25)
		(keepout
			(tracks not_allowed)
			(vias allowed)
			(pads allowed)
			(copperpour not_allowed)
			(footprints allowed)
		)
		(placement
			(enabled no)
			(sheetname "")
		)
		(fill yes
			(thermal_gap 0.5)
			(thermal_bridge_width 0.5)
			(island_removal_mode 0)
		)
		(polygon
			(pts
				(arc
					(start 32.203136 -303.566576)
					(mid 31.550356 -303.566576)
					(end 32.203136 -303.566576)
				)
			)
		)
	)
	(zone
		(layers "B.Cu" "In11.Cu" "In13.Cu" "In15.Cu")
		(hatch none 0.5)
		(connect_pads
			(clearance 0)
		)
		(min_thickness 0.25)
		(keepout
			(tracks not_allowed)
			(vias allowed)
			(pads allowed)
			(copperpour not_allowed)
			(footprints allowed)
		)
		(placement
			(enabled no)
			(sheetname "")
		)
		(fill yes
			(thermal_gap 0.5)
			(thermal_bridge_width 0.5)
			(island_removal_mode 0)
		)
		(polygon
			(pts
				(arc
					(start 269.155672 -307.816758)
					(mid 268.502892 -307.816758)
					(end 269.155672 -307.816758)
				)
			)
		)
	)
	(zone
		(layers "B.Cu" "In11.Cu" "In13.Cu" "In15.Cu")
		(hatch none 0.5)
		(connect_pads
			(clearance 0)
		)
		(min_thickness 0.25)
		(keepout
			(tracks not_allowed)
			(vias allowed)
			(pads allowed)
			(copperpour not_allowed)
			(footprints allowed)
		)
		(placement
			(enabled no)
			(sheetname "")
		)
		(fill yes
			(thermal_gap 0.5)
			(thermal_bridge_width 0.5)
			(island_removal_mode 0)
		)
		(polygon
			(pts
				(arc
					(start 116.195602 -215.436704)
					(mid 115.542822 -215.436704)
					(end 116.195602 -215.436704)
				)
			)
		)
	)
	(zone
		(layers "B.Cu" "In11.Cu" "In13.Cu" "In15.Cu")
		(hatch none 0.5)
		(connect_pads
			(clearance 0)
		)
		(min_thickness 0.25)
		(keepout
			(tracks not_allowed)
			(vias allowed)
			(pads allowed)
			(copperpour not_allowed)
			(footprints allowed)
		)
		(placement
			(enabled no)
			(sheetname "")
		)
		(fill yes
			(thermal_gap 0.5)
			(thermal_bridge_width 0.5)
			(island_removal_mode 0)
		)
		(polygon
			(pts
				(arc
					(start 436.150004 -288.266632)
					(mid 435.497224 -288.266632)
					(end 436.150004 -288.266632)
				)
			)
		)
	)
	(zone
		(layers "B.Cu" "In11.Cu" "In13.Cu" "In15.Cu")
		(hatch none 0.5)
		(connect_pads
			(clearance 0)
		)
		(min_thickness 0.25)
		(keepout
			(tracks not_allowed)
			(vias allowed)
			(pads allowed)
			(copperpour not_allowed)
			(footprints allowed)
		)
		(placement
			(enabled no)
			(sheetname "")
		)
		(fill yes
			(thermal_gap 0.5)
			(thermal_bridge_width 0.5)
			(island_removal_mode 0)
		)
		(polygon
			(pts
				(arc
					(start 32.203136 -274.66671)
					(mid 31.550356 -274.66671)
					(end 32.203136 -274.66671)
				)
			)
		)
	)
	(zone
		(layers "B.Cu" "In11.Cu" "In13.Cu" "In15.Cu")
		(hatch none 0.5)
		(connect_pads
			(clearance 0)
		)
		(min_thickness 0.25)
		(keepout
			(tracks not_allowed)
			(vias allowed)
			(pads allowed)
			(copperpour not_allowed)
			(footprints allowed)
		)
		(placement
			(enabled no)
			(sheetname "")
		)
		(fill yes
			(thermal_gap 0.5)
			(thermal_bridge_width 0.5)
			(island_removal_mode 0)
		)
		(polygon
			(pts
				(arc
					(start 32.203136 -202.416664)
					(mid 31.550356 -202.416664)
					(end 32.203136 -202.416664)
				)
			)
		)
	)
	(zone
		(layers "B.Cu" "In11.Cu" "In13.Cu" "In15.Cu")
		(hatch none 0.5)
		(connect_pads
			(clearance 0)
		)
		(min_thickness 0.25)
		(keepout
			(tracks not_allowed)
			(vias allowed)
			(pads allowed)
			(copperpour not_allowed)
			(footprints allowed)
		)
		(placement
			(enabled no)
			(sheetname "")
		)
		(fill yes
			(thermal_gap 0.5)
			(thermal_bridge_width 0.5)
			(island_removal_mode 0)
		)
		(polygon
			(pts
				(arc
					(start 323.574918 -403.883876)
					(mid 322.871338 -403.883876)
					(end 323.574918 -403.883876)
				)
			)
		)
	)
	(zone
		(layers "B.Cu" "In11.Cu" "In13.Cu" "In15.Cu")
		(hatch none 0.5)
		(connect_pads
			(clearance 0)
		)
		(min_thickness 0.25)
		(keepout
			(tracks not_allowed)
			(vias allowed)
			(pads allowed)
			(copperpour not_allowed)
			(footprints allowed)
		)
		(placement
			(enabled no)
			(sheetname "")
		)
		(fill yes
			(thermal_gap 0.5)
			(thermal_bridge_width 0.5)
			(island_removal_mode 0)
		)
		(polygon
			(pts
				(arc
					(start 127.583184 -272.639282)
					(mid 126.930404 -272.639282)
					(end 127.583184 -272.639282)
				)
			)
		)
	)
	(zone
		(layers "B.Cu" "In11.Cu" "In13.Cu" "In15.Cu")
		(hatch none 0.5)
		(connect_pads
			(clearance 0)
		)
		(min_thickness 0.25)
		(keepout
			(tracks not_allowed)
			(vias allowed)
			(pads allowed)
			(copperpour not_allowed)
			(footprints allowed)
		)
		(placement
			(enabled no)
			(sheetname "")
		)
		(fill yes
			(thermal_gap 0.5)
			(thermal_bridge_width 0.5)
			(island_removal_mode 0)
		)
		(polygon
			(pts
				(arc
					(start 126.643384 -267.755878)
					(mid 125.990604 -267.755878)
					(end 126.643384 -267.755878)
				)
			)
		)
	)
	(zone
		(layers "B.Cu" "In11.Cu" "In13.Cu" "In15.Cu")
		(hatch none 0.5)
		(connect_pads
			(clearance 0)
		)
		(min_thickness 0.25)
		(keepout
			(tracks not_allowed)
			(vias allowed)
			(pads allowed)
			(copperpour not_allowed)
			(footprints allowed)
		)
		(placement
			(enabled no)
			(sheetname "")
		)
		(fill yes
			(thermal_gap 0.5)
			(thermal_bridge_width 0.5)
			(island_removal_mode 0)
		)
		(polygon
			(pts
				(arc
					(start 127.113538 -253.919736)
					(mid 126.460758 -253.919736)
					(end 127.113538 -253.919736)
				)
			)
		)
	)
	(zone
		(layers "B.Cu" "In11.Cu" "In13.Cu" "In15.Cu")
		(hatch none 0.5)
		(connect_pads
			(clearance 0)
		)
		(min_thickness 0.25)
		(keepout
			(tracks not_allowed)
			(vias allowed)
			(pads allowed)
			(copperpour not_allowed)
			(footprints allowed)
		)
		(placement
			(enabled no)
			(sheetname "")
		)
		(fill yes
			(thermal_gap 0.5)
			(thermal_bridge_width 0.5)
			(island_removal_mode 0)
		)
		(polygon
			(pts
				(arc
					(start 403.154896 -438.089802)
					(mid 402.345144 -438.089802)
					(end 403.154896 -438.089802)
				)
			)
		)
	)
	(zone
		(layers "B.Cu" "In11.Cu" "In13.Cu" "In15.Cu")
		(hatch none 0.5)
		(connect_pads
			(clearance 0)
		)
		(min_thickness 0.25)
		(keepout
			(tracks not_allowed)
			(vias allowed)
			(pads allowed)
			(copperpour not_allowed)
			(footprints allowed)
		)
		(placement
			(enabled no)
			(sheetname "")
		)
		(fill yes
			(thermal_gap 0.5)
			(thermal_bridge_width 0.5)
			(island_removal_mode 0)
		)
		(polygon
			(pts
				(arc
					(start 32.203136 -204.116686)
					(mid 31.550356 -204.116686)
					(end 32.203136 -204.116686)
				)
			)
		)
	)
	(zone
		(layers "B.Cu" "In11.Cu" "In13.Cu" "In15.Cu")
		(hatch none 0.5)
		(connect_pads
			(clearance 0)
		)
		(min_thickness 0.25)
		(keepout
			(tracks not_allowed)
			(vias allowed)
			(pads allowed)
			(copperpour not_allowed)
			(footprints allowed)
		)
		(placement
			(enabled no)
			(sheetname "")
		)
		(fill yes
			(thermal_gap 0.5)
			(thermal_bridge_width 0.5)
			(island_removal_mode 0)
		)
		(polygon
			(pts
				(arc
					(start 16.306038 -104.827832)
					(mid 15.602458 -104.827832)
					(end 16.306038 -104.827832)
				)
			)
		)
	)
	(zone
		(layers "B.Cu" "In11.Cu" "In13.Cu" "In15.Cu")
		(hatch none 0.5)
		(connect_pads
			(clearance 0)
		)
		(min_thickness 0.25)
		(keepout
			(tracks not_allowed)
			(vias allowed)
			(pads allowed)
			(copperpour not_allowed)
			(footprints allowed)
		)
		(placement
			(enabled no)
			(sheetname "")
		)
		(fill yes
			(thermal_gap 0.5)
			(thermal_bridge_width 0.5)
			(island_removal_mode 0)
		)
		(polygon
			(pts
				(arc
					(start 350.441514 -173.128432)
					(mid 349.737934 -173.128432)
					(end 350.441514 -173.128432)
				)
			)
		)
	)
	(zone
		(layers "B.Cu" "In11.Cu" "In13.Cu" "In15.Cu")
		(hatch none 0.5)
		(connect_pads
			(clearance 0)
		)
		(min_thickness 0.25)
		(keepout
			(tracks not_allowed)
			(vias allowed)
			(pads allowed)
			(copperpour not_allowed)
			(footprints allowed)
		)
		(placement
			(enabled no)
			(sheetname "")
		)
		(fill yes
			(thermal_gap 0.5)
			(thermal_bridge_width 0.5)
			(island_removal_mode 0)
		)
		(polygon
			(pts
				(arc
					(start 127.583184 -275.8948)
					(mid 126.930404 -275.8948)
					(end 127.583184 -275.8948)
				)
			)
		)
	)
	(zone
		(layers "B.Cu" "In11.Cu" "In13.Cu" "In15.Cu")
		(hatch none 0.5)
		(connect_pads
			(clearance 0)
		)
		(min_thickness 0.25)
		(keepout
			(tracks not_allowed)
			(vias allowed)
			(pads allowed)
			(copperpour not_allowed)
			(footprints allowed)
		)
		(placement
			(enabled no)
			(sheetname "")
		)
		(fill yes
			(thermal_gap 0.5)
			(thermal_bridge_width 0.5)
			(island_removal_mode 0)
		)
		(polygon
			(pts
				(arc
					(start 376.823224 -239.0394)
					(mid 376.170444 -239.0394)
					(end 376.823224 -239.0394)
				)
			)
		)
	)
	(zone
		(layers "B.Cu" "In11.Cu" "In13.Cu" "In15.Cu")
		(hatch none 0.5)
		(connect_pads
			(clearance 0)
		)
		(min_thickness 0.25)
		(keepout
			(tracks not_allowed)
			(vias allowed)
			(pads allowed)
			(copperpour not_allowed)
			(footprints allowed)
		)
		(placement
			(enabled no)
			(sheetname "")
		)
		(fill yes
			(thermal_gap 0.5)
			(thermal_bridge_width 0.5)
			(island_removal_mode 0)
		)
		(polygon
			(pts
				(arc
					(start 95.626428 -410.030168)
					(mid 94.922848 -410.030168)
					(end 95.626428 -410.030168)
				)
			)
		)
	)
	(zone
		(layers "B.Cu" "In11.Cu" "In13.Cu" "In15.Cu")
		(hatch none 0.5)
		(connect_pads
			(clearance 0)
		)
		(min_thickness 0.25)
		(keepout
			(tracks not_allowed)
			(vias allowed)
			(pads allowed)
			(copperpour not_allowed)
			(footprints allowed)
		)
		(placement
			(enabled no)
			(sheetname "")
		)
		(fill yes
			(thermal_gap 0.5)
			(thermal_bridge_width 0.5)
			(island_removal_mode 0)
		)
		(polygon
			(pts
				(arc
					(start 413.80664 -410.030168)
					(mid 413.10306 -410.030168)
					(end 413.80664 -410.030168)
				)
			)
		)
	)
	(zone
		(layers "B.Cu" "In11.Cu" "In13.Cu" "In15.Cu")
		(hatch none 0.5)
		(connect_pads
			(clearance 0)
		)
		(min_thickness 0.25)
		(keepout
			(tracks not_allowed)
			(vias allowed)
			(pads allowed)
			(copperpour not_allowed)
			(footprints allowed)
		)
		(placement
			(enabled no)
			(sheetname "")
		)
		(fill yes
			(thermal_gap 0.5)
			(thermal_bridge_width 0.5)
			(island_removal_mode 0)
		)
		(polygon
			(pts
				(arc
					(start 345.449652 -256.361438)
					(mid 344.796872 -256.361438)
					(end 345.449652 -256.361438)
				)
			)
		)
	)
	(zone
		(layers "B.Cu" "In11.Cu" "In13.Cu" "In15.Cu")
		(hatch none 0.5)
		(connect_pads
			(clearance 0)
		)
		(min_thickness 0.25)
		(keepout
			(tracks not_allowed)
			(vias allowed)
			(pads allowed)
			(copperpour not_allowed)
			(footprints allowed)
		)
		(placement
			(enabled no)
			(sheetname "")
		)
		(fill yes
			(thermal_gap 0.5)
			(thermal_bridge_width 0.5)
			(island_removal_mode 0)
		)
		(polygon
			(pts
				(arc
					(start 97.509584 -254.733552)
					(mid 96.856804 -254.733552)
					(end 97.509584 -254.733552)
				)
			)
		)
	)
	(zone
		(layers "B.Cu" "In11.Cu" "In13.Cu" "In15.Cu")
		(hatch none 0.5)
		(connect_pads
			(clearance 0)
		)
		(min_thickness 0.25)
		(keepout
			(tracks not_allowed)
			(vias allowed)
			(pads allowed)
			(copperpour not_allowed)
			(footprints allowed)
		)
		(placement
			(enabled no)
			(sheetname "")
		)
		(fill yes
			(thermal_gap 0.5)
			(thermal_bridge_width 0.5)
			(island_removal_mode 0)
		)
		(polygon
			(pts
				(arc
					(start 436.150004 -216.866724)
					(mid 435.497224 -216.866724)
					(end 436.150004 -216.866724)
				)
			)
		)
	)
	(zone
		(layers "B.Cu" "In11.Cu" "In13.Cu" "In15.Cu")
		(hatch none 0.5)
		(connect_pads
			(clearance 0)
		)
		(min_thickness 0.25)
		(keepout
			(tracks not_allowed)
			(vias allowed)
			(pads allowed)
			(copperpour not_allowed)
			(footprints allowed)
		)
		(placement
			(enabled no)
			(sheetname "")
		)
		(fill yes
			(thermal_gap 0.5)
			(thermal_bridge_width 0.5)
			(island_removal_mode 0)
		)
		(polygon
			(pts
				(arc
					(start 203.297536 -308.666642)
					(mid 202.644756 -308.666642)
					(end 203.297536 -308.666642)
				)
			)
		)
	)
	(zone
		(layers "B.Cu" "In11.Cu" "In13.Cu" "In15.Cu")
		(hatch none 0.5)
		(connect_pads
			(clearance 0)
		)
		(min_thickness 0.25)
		(keepout
			(tracks not_allowed)
			(vias allowed)
			(pads allowed)
			(copperpour not_allowed)
			(footprints allowed)
		)
		(placement
			(enabled no)
			(sheetname "")
		)
		(fill yes
			(thermal_gap 0.5)
			(thermal_bridge_width 0.5)
			(island_removal_mode 0)
		)
		(polygon
			(pts
				(arc
					(start 280.143204 -224.516696)
					(mid 279.490424 -224.516696)
					(end 280.143204 -224.516696)
				)
			)
		)
	)
	(zone
		(layers "B.Cu" "In11.Cu" "In13.Cu" "In15.Cu")
		(hatch none 0.5)
		(connect_pads
			(clearance 0)
		)
		(min_thickness 0.25)
		(keepout
			(tracks not_allowed)
			(vias allowed)
			(pads allowed)
			(copperpour not_allowed)
			(footprints allowed)
		)
		(placement
			(enabled no)
			(sheetname "")
		)
		(fill yes
			(thermal_gap 0.5)
			(thermal_bridge_width 0.5)
			(island_removal_mode 0)
		)
		(polygon
			(pts
				(arc
					(start 436.150004 -282.316682)
					(mid 435.497224 -282.316682)
					(end 436.150004 -282.316682)
				)
			)
		)
	)
	(zone
		(layers "B.Cu" "In11.Cu" "In13.Cu" "In15.Cu")
		(hatch none 0.5)
		(connect_pads
			(clearance 0)
		)
		(min_thickness 0.25)
		(keepout
			(tracks not_allowed)
			(vias allowed)
			(pads allowed)
			(copperpour not_allowed)
			(footprints allowed)
		)
		(placement
			(enabled no)
			(sheetname "")
		)
		(fill yes
			(thermal_gap 0.5)
			(thermal_bridge_width 0.5)
			(island_removal_mode 0)
		)
		(polygon
			(pts
				(arc
					(start 399.154904 -430.889918)
					(mid 398.345152 -430.889918)
					(end 399.154904 -430.889918)
				)
			)
		)
	)
	(zone
		(layers "B.Cu" "In11.Cu" "In13.Cu" "In15.Cu")
		(hatch none 0.5)
		(connect_pads
			(clearance 0)
		)
		(min_thickness 0.25)
		(keepout
			(tracks not_allowed)
			(vias allowed)
			(pads allowed)
			(copperpour not_allowed)
			(footprints allowed)
		)
		(placement
			(enabled no)
			(sheetname "")
		)
		(fill yes
			(thermal_gap 0.5)
			(thermal_bridge_width 0.5)
			(island_removal_mode 0)
		)
		(polygon
			(pts
				(arc
					(start 32.203136 -196.466714)
					(mid 31.550356 -196.466714)
					(end 32.203136 -196.466714)
				)
			)
		)
	)
	(zone
		(layers "B.Cu" "In11.Cu" "In13.Cu" "In15.Cu")
		(hatch none 0.5)
		(connect_pads
			(clearance 0)
		)
		(min_thickness 0.25)
		(keepout
			(tracks not_allowed)
			(vias allowed)
			(pads allowed)
			(copperpour not_allowed)
			(footprints allowed)
		)
		(placement
			(enabled no)
			(sheetname "")
		)
		(fill yes
			(thermal_gap 0.5)
			(thermal_bridge_width 0.5)
			(island_removal_mode 0)
		)
		(polygon
			(pts
				(arc
					(start 128.993138 -268.569694)
					(mid 128.340358 -268.569694)
					(end 128.993138 -268.569694)
				)
			)
		)
	)
	(zone
		(layers "B.Cu" "In11.Cu" "In13.Cu" "In15.Cu")
		(hatch none 0.5)
		(connect_pads
			(clearance 0)
		)
		(min_thickness 0.25)
		(keepout
			(tracks not_allowed)
			(vias allowed)
			(pads allowed)
			(copperpour not_allowed)
			(footprints allowed)
		)
		(placement
			(enabled no)
			(sheetname "")
		)
		(fill yes
			(thermal_gap 0.5)
			(thermal_bridge_width 0.5)
			(island_removal_mode 0)
		)
		(polygon
			(pts
				(arc
					(start 284.243272 -301.866808)
					(mid 283.590492 -301.866808)
					(end 284.243272 -301.866808)
				)
			)
		)
	)
	(zone
		(layers "B.Cu" "In11.Cu" "In13.Cu" "In15.Cu")
		(hatch none 0.5)
		(connect_pads
			(clearance 0)
		)
		(min_thickness 0.25)
		(keepout
			(tracks not_allowed)
			(vias allowed)
			(pads allowed)
			(copperpour not_allowed)
			(footprints allowed)
		)
		(placement
			(enabled no)
			(sheetname "")
		)
		(fill yes
			(thermal_gap 0.5)
			(thermal_bridge_width 0.5)
			(island_removal_mode 0)
		)
		(polygon
			(pts
				(arc
					(start 188.209936 -215.166702)
					(mid 187.557156 -215.166702)
					(end 188.209936 -215.166702)
				)
			)
		)
	)
	(zone
		(layers "B.Cu" "In11.Cu" "In13.Cu" "In15.Cu")
		(hatch none 0.5)
		(connect_pads
			(clearance 0)
		)
		(min_thickness 0.25)
		(keepout
			(tracks not_allowed)
			(vias allowed)
			(pads allowed)
			(copperpour not_allowed)
			(footprints allowed)
		)
		(placement
			(enabled no)
			(sheetname "")
		)
		(fill yes
			(thermal_gap 0.5)
			(thermal_bridge_width 0.5)
			(island_removal_mode 0)
		)
		(polygon
			(pts
				(arc
					(start 32.203136 -227.91674)
					(mid 31.550356 -227.91674)
					(end 32.203136 -227.91674)
				)
			)
		)
	)
	(zone
		(layers "B.Cu" "In11.Cu" "In13.Cu" "In15.Cu")
		(hatch none 0.5)
		(connect_pads
			(clearance 0)
		)
		(min_thickness 0.25)
		(keepout
			(tracks not_allowed)
			(vias allowed)
			(pads allowed)
			(copperpour not_allowed)
			(footprints allowed)
		)
		(placement
			(enabled no)
			(sheetname "")
		)
		(fill yes
			(thermal_gap 0.5)
			(thermal_bridge_width 0.5)
			(island_removal_mode 0)
		)
		(polygon
			(pts
				(arc
					(start 96.929956 -232.528364)
					(mid 96.277176 -232.528364)
					(end 96.929956 -232.528364)
				)
			)
		)
	)
	(zone
		(layers "B.Cu" "In11.Cu" "In13.Cu" "In15.Cu")
		(hatch none 0.5)
		(connect_pads
			(clearance 0)
		)
		(min_thickness 0.25)
		(keepout
			(tracks not_allowed)
			(vias allowed)
			(pads allowed)
			(copperpour not_allowed)
			(footprints allowed)
		)
		(placement
			(enabled no)
			(sheetname "")
		)
		(fill yes
			(thermal_gap 0.5)
			(thermal_bridge_width 0.5)
			(island_removal_mode 0)
		)
		(polygon
			(pts
				(arc
					(start 95.160338 -275.08073)
					(mid 94.507558 -275.08073)
					(end 95.160338 -275.08073)
				)
			)
		)
	)
	(zone
		(layers "B.Cu" "In11.Cu" "In13.Cu" "In15.Cu")
		(hatch none 0.5)
		(connect_pads
			(clearance 0)
		)
		(min_thickness 0.25)
		(keepout
			(tracks not_allowed)
			(vias allowed)
			(pads allowed)
			(copperpour not_allowed)
			(footprints allowed)
		)
		(placement
			(enabled no)
			(sheetname "")
		)
		(fill yes
			(thermal_gap 0.5)
			(thermal_bridge_width 0.5)
			(island_removal_mode 0)
		)
		(polygon
			(pts
				(arc
					(start 96.100138 -271.825212)
					(mid 95.447358 -271.825212)
					(end 96.100138 -271.825212)
				)
			)
		)
	)
	(zone
		(layers "B.Cu" "In11.Cu" "In13.Cu" "In15.Cu")
		(hatch none 0.5)
		(connect_pads
			(clearance 0)
		)
		(min_thickness 0.25)
		(keepout
			(tracks not_allowed)
			(vias allowed)
			(pads allowed)
			(copperpour not_allowed)
			(footprints allowed)
		)
		(placement
			(enabled no)
			(sheetname "")
		)
		(fill yes
			(thermal_gap 0.5)
			(thermal_bridge_width 0.5)
			(island_removal_mode 0)
		)
		(polygon
			(pts
				(arc
					(start 99.748848 -214.622634)
					(mid 99.096068 -214.622634)
					(end 99.748848 -214.622634)
				)
			)
		)
	)
	(zone
		(layers "B.Cu" "In11.Cu" "In13.Cu" "In15.Cu")
		(hatch none 0.5)
		(connect_pads
			(clearance 0)
		)
		(min_thickness 0.25)
		(keepout
			(tracks not_allowed)
			(vias allowed)
			(pads allowed)
			(copperpour not_allowed)
			(footprints allowed)
		)
		(placement
			(enabled no)
			(sheetname "")
		)
		(fill yes
			(thermal_gap 0.5)
			(thermal_bridge_width 0.5)
			(island_removal_mode 0)
		)
		(polygon
			(pts
				(arc
					(start 370.474494 -179.067968)
					(mid 369.770914 -179.067968)
					(end 370.474494 -179.067968)
				)
			)
		)
	)
	(zone
		(layers "B.Cu" "In11.Cu" "In13.Cu" "In15.Cu")
		(hatch none 0.5)
		(connect_pads
			(clearance 0)
		)
		(min_thickness 0.25)
		(keepout
			(tracks not_allowed)
			(vias allowed)
			(pads allowed)
			(copperpour not_allowed)
			(footprints allowed)
		)
		(placement
			(enabled no)
			(sheetname "")
		)
		(fill yes
			(thermal_gap 0.5)
			(thermal_bridge_width 0.5)
			(island_removal_mode 0)
		)
		(polygon
			(pts
				(arc
					(start 73.054972 -435.489858)
					(mid 72.24522 -435.489858)
					(end 73.054972 -435.489858)
				)
			)
		)
	)
	(zone
		(layers "B.Cu" "In11.Cu" "In13.Cu" "In15.Cu")
		(hatch none 0.5)
		(connect_pads
			(clearance 0)
		)
		(min_thickness 0.25)
		(keepout
			(tracks not_allowed)
			(vias allowed)
			(pads allowed)
			(copperpour not_allowed)
			(footprints allowed)
		)
		(placement
			(enabled no)
			(sheetname "")
		)
		(fill yes
			(thermal_gap 0.5)
			(thermal_bridge_width 0.5)
			(island_removal_mode 0)
		)
		(polygon
			(pts
				(arc
					(start 451.237604 -213.46668)
					(mid 450.584824 -213.46668)
					(end 451.237604 -213.46668)
				)
			)
		)
	)
	(zone
		(layers "B.Cu" "In11.Cu" "In13.Cu" "In15.Cu")
		(hatch none 0.5)
		(connect_pads
			(clearance 0)
		)
		(min_thickness 0.25)
		(keepout
			(tracks not_allowed)
			(vias allowed)
			(pads allowed)
			(copperpour not_allowed)
			(footprints allowed)
		)
		(placement
			(enabled no)
			(sheetname "")
		)
		(fill yes
			(thermal_gap 0.5)
			(thermal_bridge_width 0.5)
			(island_removal_mode 0)
		)
		(polygon
			(pts
				(arc
					(start 320.511678 -403.883876)
					(mid 319.808098 -403.883876)
					(end 320.511678 -403.883876)
				)
			)
		)
	)
	(zone
		(layers "B.Cu" "In11.Cu" "In13.Cu" "In15.Cu")
		(hatch none 0.5)
		(connect_pads
			(clearance 0)
		)
		(min_thickness 0.25)
		(keepout
			(tracks not_allowed)
			(vias allowed)
			(pads allowed)
			(copperpour not_allowed)
			(footprints allowed)
		)
		(placement
			(enabled no)
			(sheetname "")
		)
		(fill yes
			(thermal_gap 0.5)
			(thermal_bridge_width 0.5)
			(island_removal_mode 0)
		)
		(polygon
			(pts
				(arc
					(start 389.30072 -410.030168)
					(mid 388.59714 -410.030168)
					(end 389.30072 -410.030168)
				)
			)
		)
	)
	(zone
		(layers "B.Cu" "In11.Cu" "In13.Cu" "In15.Cu")
		(hatch none 0.5)
		(connect_pads
			(clearance 0)
		)
		(min_thickness 0.25)
		(keepout
			(tracks not_allowed)
			(vias allowed)
			(pads allowed)
			(copperpour not_allowed)
			(footprints allowed)
		)
		(placement
			(enabled no)
			(sheetname "")
		)
		(fill yes
			(thermal_gap 0.5)
			(thermal_bridge_width 0.5)
			(island_removal_mode 0)
		)
		(polygon
			(pts
				(arc
					(start 145.154904 -439.0898)
					(mid 144.345152 -439.0898)
					(end 145.154904 -439.0898)
				)
			)
		)
	)
	(zone
		(layers "B.Cu" "In11.Cu" "In13.Cu" "In15.Cu")
		(hatch none 0.5)
		(connect_pads
			(clearance 0)
		)
		(min_thickness 0.25)
		(keepout
			(tracks not_allowed)
			(vias allowed)
			(pads allowed)
			(copperpour not_allowed)
			(footprints allowed)
		)
		(placement
			(enabled no)
			(sheetname "")
		)
		(fill yes
			(thermal_gap 0.5)
			(thermal_bridge_width 0.5)
			(island_removal_mode 0)
		)
		(polygon
			(pts
				(arc
					(start 195.753736 -243.216684)
					(mid 195.100956 -243.216684)
					(end 195.753736 -243.216684)
				)
			)
		)
	)
	(zone
		(layers "B.Cu" "In11.Cu" "In13.Cu" "In15.Cu")
		(hatch none 0.5)
		(connect_pads
			(clearance 0)
		)
		(min_thickness 0.25)
		(keepout
			(tracks not_allowed)
			(vias allowed)
			(pads allowed)
			(copperpour not_allowed)
			(footprints allowed)
		)
		(placement
			(enabled no)
			(sheetname "")
		)
		(fill yes
			(thermal_gap 0.5)
			(thermal_bridge_width 0.5)
			(island_removal_mode 0)
		)
		(polygon
			(pts
				(arc
					(start 280.143204 -215.166702)
					(mid 279.490424 -215.166702)
					(end 280.143204 -215.166702)
				)
			)
		)
	)
	(zone
		(layers "B.Cu" "In11.Cu" "In13.Cu" "In15.Cu")
		(hatch none 0.5)
		(connect_pads
			(clearance 0)
		)
		(min_thickness 0.25)
		(keepout
			(tracks not_allowed)
			(vias allowed)
			(pads allowed)
			(copperpour not_allowed)
			(footprints allowed)
		)
		(placement
			(enabled no)
			(sheetname "")
		)
		(fill yes
			(thermal_gap 0.5)
			(thermal_bridge_width 0.5)
			(island_removal_mode 0)
		)
		(polygon
			(pts
				(arc
					(start 131.702048 -214.622634)
					(mid 131.049268 -214.622634)
					(end 131.702048 -214.622634)
				)
			)
		)
	)
	(zone
		(layers "B.Cu" "In11.Cu" "In13.Cu" "In15.Cu")
		(hatch none 0.5)
		(connect_pads
			(clearance 0)
		)
		(min_thickness 0.25)
		(keepout
			(tracks not_allowed)
			(vias allowed)
			(pads allowed)
			(copperpour not_allowed)
			(footprints allowed)
		)
		(placement
			(enabled no)
			(sheetname "")
		)
		(fill yes
			(thermal_gap 0.5)
			(thermal_bridge_width 0.5)
			(island_removal_mode 0)
		)
		(polygon
			(pts
				(arc
					(start 188.209936 -219.41663)
					(mid 187.557156 -219.41663)
					(end 188.209936 -219.41663)
				)
			)
		)
	)
	(zone
		(layers "B.Cu" "In11.Cu" "In13.Cu" "In15.Cu")
		(hatch none 0.5)
		(connect_pads
			(clearance 0)
		)
		(min_thickness 0.25)
		(keepout
			(tracks not_allowed)
			(vias allowed)
			(pads allowed)
			(copperpour not_allowed)
			(footprints allowed)
		)
		(placement
			(enabled no)
			(sheetname "")
		)
		(fill yes
			(thermal_gap 0.5)
			(thermal_bridge_width 0.5)
			(island_removal_mode 0)
		)
		(polygon
			(pts
				(arc
					(start 334.641952 -286.475424)
					(mid 333.989172 -286.475424)
					(end 334.641952 -286.475424)
				)
			)
		)
	)
	(zone
		(layers "B.Cu" "In11.Cu" "In13.Cu" "In15.Cu")
		(hatch none 0.5)
		(connect_pads
			(clearance 0)
		)
		(min_thickness 0.25)
		(keepout
			(tracks not_allowed)
			(vias allowed)
			(pads allowed)
			(copperpour not_allowed)
			(footprints allowed)
		)
		(placement
			(enabled no)
			(sheetname "")
		)
		(fill yes
			(thermal_gap 0.5)
			(thermal_bridge_width 0.5)
			(island_removal_mode 0)
		)
		(polygon
			(pts
				(arc
					(start 90.054938 -428.28972)
					(mid 89.245186 -428.28972)
					(end 90.054938 -428.28972)
				)
			)
		)
	)
	(zone
		(layers "B.Cu" "In11.Cu" "In13.Cu" "In15.Cu")
		(hatch none 0.5)
		(connect_pads
			(clearance 0)
		)
		(min_thickness 0.25)
		(keepout
			(tracks not_allowed)
			(vias allowed)
			(pads allowed)
			(copperpour not_allowed)
			(footprints allowed)
		)
		(placement
			(enabled no)
			(sheetname "")
		)
		(fill yes
			(thermal_gap 0.5)
			(thermal_bridge_width 0.5)
			(island_removal_mode 0)
		)
		(polygon
			(pts
				(arc
					(start 188.209936 -275.516594)
					(mid 187.557156 -275.516594)
					(end 188.209936 -275.516594)
				)
			)
		)
	)
	(zone
		(layers "B.Cu" "In11.Cu" "In13.Cu" "In15.Cu")
		(hatch none 0.5)
		(connect_pads
			(clearance 0)
		)
		(min_thickness 0.25)
		(keepout
			(tracks not_allowed)
			(vias allowed)
			(pads allowed)
			(copperpour not_allowed)
			(footprints allowed)
		)
		(placement
			(enabled no)
			(sheetname "")
		)
		(fill yes
			(thermal_gap 0.5)
			(thermal_bridge_width 0.5)
			(island_removal_mode 0)
		)
		(polygon
			(pts
				(arc
					(start 95.050356 -237.411514)
					(mid 94.397576 -237.411514)
					(end 95.050356 -237.411514)
				)
			)
		)
	)
	(zone
		(layers "B.Cu" "In11.Cu" "In13.Cu" "In15.Cu")
		(hatch none 0.5)
		(connect_pads
			(clearance 0)
		)
		(min_thickness 0.25)
		(keepout
			(tracks not_allowed)
			(vias allowed)
			(pads allowed)
			(copperpour not_allowed)
			(footprints allowed)
		)
		(placement
			(enabled no)
			(sheetname "")
		)
		(fill yes
			(thermal_gap 0.5)
			(thermal_bridge_width 0.5)
			(island_removal_mode 0)
		)
		(polygon
			(pts
				(arc
					(start 21.215604 -209.216752)
					(mid 20.562824 -209.216752)
					(end 21.215604 -209.216752)
				)
			)
		)
	)
	(zone
		(layers "B.Cu" "In11.Cu" "In13.Cu" "In15.Cu")
		(hatch none 0.5)
		(connect_pads
			(clearance 0)
		)
		(min_thickness 0.25)
		(keepout
			(tracks not_allowed)
			(vias allowed)
			(pads allowed)
			(copperpour not_allowed)
			(footprints allowed)
		)
		(placement
			(enabled no)
			(sheetname "")
		)
		(fill yes
			(thermal_gap 0.5)
			(thermal_bridge_width 0.5)
			(island_removal_mode 0)
		)
		(polygon
			(pts
				(arc
					(start 375.523252 -271.011396)
					(mid 374.870472 -271.011396)
					(end 375.523252 -271.011396)
				)
			)
		)
	)
	(zone
		(layers "B.Cu" "In11.Cu" "In13.Cu" "In15.Cu")
		(hatch none 0.5)
		(connect_pads
			(clearance 0)
		)
		(min_thickness 0.25)
		(keepout
			(tracks not_allowed)
			(vias allowed)
			(pads allowed)
			(copperpour not_allowed)
			(footprints allowed)
		)
		(placement
			(enabled no)
			(sheetname "")
		)
		(fill yes
			(thermal_gap 0.5)
			(thermal_bridge_width 0.5)
			(island_removal_mode 0)
		)
		(polygon
			(pts
				(arc
					(start 440.250072 -201.56678)
					(mid 439.597292 -201.56678)
					(end 440.250072 -201.56678)
				)
			)
		)
	)
	(zone
		(layers "B.Cu" "In11.Cu" "In13.Cu" "In15.Cu")
		(hatch none 0.5)
		(connect_pads
			(clearance 0)
		)
		(min_thickness 0.25)
		(keepout
			(tracks not_allowed)
			(vias allowed)
			(pads allowed)
			(copperpour not_allowed)
			(footprints allowed)
		)
		(placement
			(enabled no)
			(sheetname "")
		)
		(fill yes
			(thermal_gap 0.5)
			(thermal_bridge_width 0.5)
			(island_removal_mode 0)
		)
		(polygon
			(pts
				(arc
					(start 345.809316 -214.622634)
					(mid 345.156536 -214.622634)
					(end 345.809316 -214.622634)
				)
			)
		)
	)
	(zone
		(layers "B.Cu" "In11.Cu" "In13.Cu" "In15.Cu")
		(hatch none 0.5)
		(connect_pads
			(clearance 0)
		)
		(min_thickness 0.25)
		(keepout
			(tracks not_allowed)
			(vias allowed)
			(pads allowed)
			(copperpour not_allowed)
			(footprints allowed)
		)
		(placement
			(enabled no)
			(sheetname "")
		)
		(fill yes
			(thermal_gap 0.5)
			(thermal_bridge_width 0.5)
			(island_removal_mode 0)
		)
		(polygon
			(pts
				(arc
					(start 455.337672 -315.46673)
					(mid 454.684892 -315.46673)
					(end 455.337672 -315.46673)
				)
			)
		)
	)
	(zone
		(layers "B.Cu" "In11.Cu" "In13.Cu" "In15.Cu")
		(hatch none 0.5)
		(connect_pads
			(clearance 0)
		)
		(min_thickness 0.25)
		(keepout
			(tracks not_allowed)
			(vias allowed)
			(pads allowed)
			(copperpour not_allowed)
			(footprints allowed)
		)
		(placement
			(enabled no)
			(sheetname "")
		)
		(fill yes
			(thermal_gap 0.5)
			(thermal_bridge_width 0.5)
			(island_removal_mode 0)
		)
		(polygon
			(pts
				(arc
					(start 403.154896 -436.889906)
					(mid 402.345144 -436.889906)
					(end 403.154896 -436.889906)
				)
			)
		)
	)
	(zone
		(layers "B.Cu" "In11.Cu" "In13.Cu" "In15.Cu")
		(hatch none 0.5)
		(connect_pads
			(clearance 0)
		)
		(min_thickness 0.25)
		(keepout
			(tracks not_allowed)
			(vias allowed)
			(pads allowed)
			(copperpour not_allowed)
			(footprints allowed)
		)
		(placement
			(enabled no)
			(sheetname "")
		)
		(fill yes
			(thermal_gap 0.5)
			(thermal_bridge_width 0.5)
			(island_removal_mode 0)
		)
		(polygon
			(pts
				(arc
					(start 32.203136 -286.56661)
					(mid 31.550356 -286.56661)
					(end 32.203136 -286.56661)
				)
			)
		)
	)
	(zone
		(layers "B.Cu" "In11.Cu" "In13.Cu" "In15.Cu")
		(hatch none 0.5)
		(connect_pads
			(clearance 0)
		)
		(min_thickness 0.25)
		(keepout
			(tracks not_allowed)
			(vias allowed)
			(pads allowed)
			(copperpour not_allowed)
			(footprints allowed)
		)
		(placement
			(enabled no)
			(sheetname "")
		)
		(fill yes
			(thermal_gap 0.5)
			(thermal_bridge_width 0.5)
			(island_removal_mode 0)
		)
		(polygon
			(pts
				(arc
					(start 24.659336 -243.216684)
					(mid 24.006556 -243.216684)
					(end 24.659336 -243.216684)
				)
			)
		)
	)
	(zone
		(layers "B.Cu" "In11.Cu" "In13.Cu" "In15.Cu")
		(hatch none 0.5)
		(connect_pads
			(clearance 0)
		)
		(min_thickness 0.25)
		(keepout
			(tracks not_allowed)
			(vias allowed)
			(pads allowed)
			(copperpour not_allowed)
			(footprints allowed)
		)
		(placement
			(enabled no)
			(sheetname "")
		)
		(fill yes
			(thermal_gap 0.5)
			(thermal_bridge_width 0.5)
			(island_removal_mode 0)
		)
		(polygon
			(pts
				(arc
					(start 436.150004 -306.96662)
					(mid 435.497224 -306.96662)
					(end 436.150004 -306.96662)
				)
			)
		)
	)
	(zone
		(layers "B.Cu" "In11.Cu" "In13.Cu" "In15.Cu")
		(hatch none 0.5)
		(connect_pads
			(clearance 0)
		)
		(min_thickness 0.25)
		(keepout
			(tracks not_allowed)
			(vias allowed)
			(pads allowed)
			(copperpour not_allowed)
			(footprints allowed)
		)
		(placement
			(enabled no)
			(sheetname "")
		)
		(fill yes
			(thermal_gap 0.5)
			(thermal_bridge_width 0.5)
			(island_removal_mode 0)
		)
		(polygon
			(pts
				(arc
					(start 97.399602 -241.481102)
					(mid 96.746822 -241.481102)
					(end 97.399602 -241.481102)
				)
			)
		)
	)
	(zone
		(layers "B.Cu" "In11.Cu" "In13.Cu" "In15.Cu")
		(hatch none 0.5)
		(connect_pads
			(clearance 0)
		)
		(min_thickness 0.25)
		(keepout
			(tracks not_allowed)
			(vias allowed)
			(pads allowed)
			(copperpour not_allowed)
			(footprints allowed)
		)
		(placement
			(enabled no)
			(sheetname "")
		)
		(fill yes
			(thermal_gap 0.5)
			(thermal_bridge_width 0.5)
			(island_removal_mode 0)
		)
		(polygon
			(pts
				(arc
					(start 9.571736 -245.76659)
					(mid 8.918956 -245.76659)
					(end 9.571736 -245.76659)
				)
			)
		)
	)
	(zone
		(layers "B.Cu" "In11.Cu" "In13.Cu" "In15.Cu")
		(hatch none 0.5)
		(connect_pads
			(clearance 0)
		)
		(min_thickness 0.25)
		(keepout
			(tracks not_allowed)
			(vias allowed)
			(pads allowed)
			(copperpour not_allowed)
			(footprints allowed)
		)
		(placement
			(enabled no)
			(sheetname "")
		)
		(fill yes
			(thermal_gap 0.5)
			(thermal_bridge_width 0.5)
			(island_removal_mode 0)
		)
		(polygon
			(pts
				(arc
					(start 78.054962 -434.289962)
					(mid 77.24521 -434.289962)
					(end 78.054962 -434.289962)
				)
			)
		)
	)
	(zone
		(layers "B.Cu" "In11.Cu" "In13.Cu" "In15.Cu")
		(hatch none 0.5)
		(connect_pads
			(clearance 0)
		)
		(min_thickness 0.25)
		(keepout
			(tracks not_allowed)
			(vias allowed)
			(pads allowed)
			(copperpour not_allowed)
			(footprints allowed)
		)
		(placement
			(enabled no)
			(sheetname "")
		)
		(fill yes
			(thermal_gap 0.5)
			(thermal_bridge_width 0.5)
			(island_removal_mode 0)
		)
		(polygon
			(pts
				(arc
					(start 133.581648 -214.622634)
					(mid 132.928868 -214.622634)
					(end 133.581648 -214.622634)
				)
			)
		)
	)
	(zone
		(layers "B.Cu" "In11.Cu" "In13.Cu" "In15.Cu")
		(hatch none 0.5)
		(connect_pads
			(clearance 0)
		)
		(min_thickness 0.25)
		(keepout
			(tracks not_allowed)
			(vias allowed)
			(pads allowed)
			(copperpour not_allowed)
			(footprints allowed)
		)
		(placement
			(enabled no)
			(sheetname "")
		)
		(fill yes
			(thermal_gap 0.5)
			(thermal_bridge_width 0.5)
			(island_removal_mode 0)
		)
		(polygon
			(pts
				(arc
					(start 284.243272 -274.66671)
					(mid 283.590492 -274.66671)
					(end 284.243272 -274.66671)
				)
			)
		)
	)
	(zone
		(layers "B.Cu" "In11.Cu" "In13.Cu" "In15.Cu")
		(hatch none 0.5)
		(connect_pads
			(clearance 0)
		)
		(min_thickness 0.25)
		(keepout
			(tracks not_allowed)
			(vias allowed)
			(pads allowed)
			(copperpour not_allowed)
			(footprints allowed)
		)
		(placement
			(enabled no)
			(sheetname "")
		)
		(fill yes
			(thermal_gap 0.5)
			(thermal_bridge_width 0.5)
			(island_removal_mode 0)
		)
		(polygon
			(pts
				(arc
					(start 269.155672 -311.216802)
					(mid 268.502892 -311.216802)
					(end 269.155672 -311.216802)
				)
			)
		)
	)
	(zone
		(layers "B.Cu" "In11.Cu" "In13.Cu" "In15.Cu")
		(hatch none 0.5)
		(connect_pads
			(clearance 0)
		)
		(min_thickness 0.25)
		(keepout
			(tracks not_allowed)
			(vias allowed)
			(pads allowed)
			(copperpour not_allowed)
			(footprints allowed)
		)
		(placement
			(enabled no)
			(sheetname "")
		)
		(fill yes
			(thermal_gap 0.5)
			(thermal_bridge_width 0.5)
			(island_removal_mode 0)
		)
		(polygon
			(pts
				(arc
					(start 65.054988 -427.089824)
					(mid 64.245236 -427.089824)
					(end 65.054988 -427.089824)
				)
			)
		)
	)
	(zone
		(layers "B.Cu" "In11.Cu" "In13.Cu" "In15.Cu")
		(hatch none 0.5)
		(connect_pads
			(clearance 0)
		)
		(min_thickness 0.25)
		(keepout
			(tracks not_allowed)
			(vias allowed)
			(pads allowed)
			(copperpour not_allowed)
			(footprints allowed)
		)
		(placement
			(enabled no)
			(sheetname "")
		)
		(fill yes
			(thermal_gap 0.5)
			(thermal_bridge_width 0.5)
			(island_removal_mode 0)
		)
		(polygon
			(pts
				(arc
					(start 104.088184 -277.522432)
					(mid 103.435404 -277.522432)
					(end 104.088184 -277.522432)
				)
			)
		)
	)
	(zone
		(layers "B.Cu" "In11.Cu" "In13.Cu" "In15.Cu")
		(hatch none 0.5)
		(connect_pads
			(clearance 0)
		)
		(min_thickness 0.25)
		(keepout
			(tracks not_allowed)
			(vias allowed)
			(pads allowed)
			(copperpour not_allowed)
			(footprints allowed)
		)
		(placement
			(enabled no)
			(sheetname "")
		)
		(fill yes
			(thermal_gap 0.5)
			(thermal_bridge_width 0.5)
			(island_removal_mode 0)
		)
		(polygon
			(pts
				(arc
					(start 164.738304 -410.030168)
					(mid 164.034724 -410.030168)
					(end 164.738304 -410.030168)
				)
			)
		)
	)
	(zone
		(layers "B.Cu" "In11.Cu" "In13.Cu" "In15.Cu")
		(hatch none 0.5)
		(connect_pads
			(clearance 0)
		)
		(min_thickness 0.25)
		(keepout
			(tracks not_allowed)
			(vias allowed)
			(pads allowed)
			(copperpour not_allowed)
			(footprints allowed)
		)
		(placement
			(enabled no)
			(sheetname "")
		)
		(fill yes
			(thermal_gap 0.5)
			(thermal_bridge_width 0.5)
			(island_removal_mode 0)
		)
		(polygon
			(pts
				(arc
					(start 127.583184 -262.872474)
					(mid 126.930404 -262.872474)
					(end 127.583184 -262.872474)
				)
			)
		)
	)
	(zone
		(layers "B.Cu" "In11.Cu" "In13.Cu" "In15.Cu")
		(hatch none 0.5)
		(connect_pads
			(clearance 0)
		)
		(min_thickness 0.25)
		(keepout
			(tracks not_allowed)
			(vias allowed)
			(pads allowed)
			(copperpour not_allowed)
			(footprints allowed)
		)
		(placement
			(enabled no)
			(sheetname "")
		)
		(fill yes
			(thermal_gap 0.5)
			(thermal_bridge_width 0.5)
			(island_removal_mode 0)
		)
		(polygon
			(pts
				(arc
					(start 140.154914 -430.689766)
					(mid 139.345162 -430.689766)
					(end 140.154914 -430.689766)
				)
			)
		)
	)
	(zone
		(layers "B.Cu" "In11.Cu" "In13.Cu" "In15.Cu")
		(hatch none 0.5)
		(connect_pads
			(clearance 0)
		)
		(min_thickness 0.25)
		(keepout
			(tracks not_allowed)
			(vias allowed)
			(pads allowed)
			(copperpour not_allowed)
			(footprints allowed)
		)
		(placement
			(enabled no)
			(sheetname "")
		)
		(fill yes
			(thermal_gap 0.5)
			(thermal_bridge_width 0.5)
			(island_removal_mode 0)
		)
		(polygon
			(pts
				(arc
					(start 284.243272 -270.416782)
					(mid 283.590492 -270.416782)
					(end 284.243272 -270.416782)
				)
			)
		)
	)
	(zone
		(layers "B.Cu" "In11.Cu" "In13.Cu" "In15.Cu")
		(hatch none 0.5)
		(connect_pads
			(clearance 0)
		)
		(min_thickness 0.25)
		(keepout
			(tracks not_allowed)
			(vias allowed)
			(pads allowed)
			(copperpour not_allowed)
			(footprints allowed)
		)
		(placement
			(enabled no)
			(sheetname "")
		)
		(fill yes
			(thermal_gap 0.5)
			(thermal_bridge_width 0.5)
			(island_removal_mode 0)
		)
		(polygon
			(pts
				(arc
					(start 97.509584 -264.50036)
					(mid 96.856804 -264.50036)
					(end 97.509584 -264.50036)
				)
			)
		)
	)
	(zone
		(layers "B.Cu" "In11.Cu" "In13.Cu" "In15.Cu")
		(hatch none 0.5)
		(connect_pads
			(clearance 0)
		)
		(min_thickness 0.25)
		(keepout
			(tracks not_allowed)
			(vias allowed)
			(pads allowed)
			(copperpour not_allowed)
			(footprints allowed)
		)
		(placement
			(enabled no)
			(sheetname "")
		)
		(fill yes
			(thermal_gap 0.5)
			(thermal_bridge_width 0.5)
			(island_removal_mode 0)
		)
		(polygon
			(pts
				(arc
					(start 284.243272 -203.266802)
					(mid 283.590492 -203.266802)
					(end 284.243272 -203.266802)
				)
			)
		)
	)
	(zone
		(layers "B.Cu" "In11.Cu" "In13.Cu" "In15.Cu")
		(hatch none 0.5)
		(connect_pads
			(clearance 0)
		)
		(min_thickness 0.25)
		(keepout
			(tracks not_allowed)
			(vias allowed)
			(pads allowed)
			(copperpour not_allowed)
			(footprints allowed)
		)
		(placement
			(enabled no)
			(sheetname "")
		)
		(fill yes
			(thermal_gap 0.5)
			(thermal_bridge_width 0.5)
			(island_removal_mode 0)
		)
		(polygon
			(pts
				(arc
					(start 383.401824 -219.506038)
					(mid 382.749044 -219.506038)
					(end 383.401824 -219.506038)
				)
			)
		)
	)
	(zone
		(layers "B.Cu" "In11.Cu" "In13.Cu" "In15.Cu")
		(hatch none 0.5)
		(connect_pads
			(clearance 0)
		)
		(min_thickness 0.25)
		(keepout
			(tracks not_allowed)
			(vias allowed)
			(pads allowed)
			(copperpour not_allowed)
			(footprints allowed)
		)
		(placement
			(enabled no)
			(sheetname "")
		)
		(fill yes
			(thermal_gap 0.5)
			(thermal_bridge_width 0.5)
			(island_removal_mode 0)
		)
		(polygon
			(pts
				(arc
					(start 143.295624 -410.030168)
					(mid 142.592044 -410.030168)
					(end 143.295624 -410.030168)
				)
			)
		)
	)
	(zone
		(layers "B.Cu" "In11.Cu" "In13.Cu" "In15.Cu")
		(hatch none 0.5)
		(connect_pads
			(clearance 0)
		)
		(min_thickness 0.25)
		(keepout
			(tracks not_allowed)
			(vias allowed)
			(pads allowed)
			(copperpour not_allowed)
			(footprints allowed)
		)
		(placement
			(enabled no)
			(sheetname "")
		)
		(fill yes
			(thermal_gap 0.5)
			(thermal_bridge_width 0.5)
			(island_removal_mode 0)
		)
		(polygon
			(pts
				(arc
					(start 36.303204 -197.316598)
					(mid 35.650424 -197.316598)
					(end 36.303204 -197.316598)
				)
			)
		)
	)
	(zone
		(layers "B.Cu" "In11.Cu" "In13.Cu" "In15.Cu")
		(hatch none 0.5)
		(connect_pads
			(clearance 0)
		)
		(min_thickness 0.25)
		(keepout
			(tracks not_allowed)
			(vias allowed)
			(pads allowed)
			(copperpour not_allowed)
			(footprints allowed)
		)
		(placement
			(enabled no)
			(sheetname "")
		)
		(fill yes
			(thermal_gap 0.5)
			(thermal_bridge_width 0.5)
			(island_removal_mode 0)
		)
		(polygon
			(pts
				(arc
					(start 101.628956 -247.178322)
					(mid 100.976176 -247.178322)
					(end 101.628956 -247.178322)
				)
			)
		)
	)
	(zone
		(layers "B.Cu" "In11.Cu" "In13.Cu" "In15.Cu")
		(hatch none 0.5)
		(connect_pads
			(clearance 0)
		)
		(min_thickness 0.25)
		(keepout
			(tracks not_allowed)
			(vias allowed)
			(pads allowed)
			(copperpour not_allowed)
			(footprints allowed)
		)
		(placement
			(enabled no)
			(sheetname "")
		)
		(fill yes
			(thermal_gap 0.5)
			(thermal_bridge_width 0.5)
			(island_removal_mode 0)
		)
		(polygon
			(pts
				(arc
					(start 102.098602 -247.992138)
					(mid 101.445822 -247.992138)
					(end 102.098602 -247.992138)
				)
			)
		)
	)
	(zone
		(layers "B.Cu" "In11.Cu" "In13.Cu" "In15.Cu")
		(hatch none 0.5)
		(connect_pads
			(clearance 0)
		)
		(min_thickness 0.25)
		(keepout
			(tracks not_allowed)
			(vias allowed)
			(pads allowed)
			(copperpour not_allowed)
			(footprints allowed)
		)
		(placement
			(enabled no)
			(sheetname "")
		)
		(fill yes
			(thermal_gap 0.5)
			(thermal_bridge_width 0.5)
			(island_removal_mode 0)
		)
		(polygon
			(pts
				(arc
					(start 353.300284 -183.034432)
					(mid 352.596704 -183.034432)
					(end 353.300284 -183.034432)
				)
			)
		)
	)
	(zone
		(layers "B.Cu" "In11.Cu" "In13.Cu" "In15.Cu")
		(hatch none 0.5)
		(connect_pads
			(clearance 0)
		)
		(min_thickness 0.25)
		(keepout
			(tracks not_allowed)
			(vias allowed)
			(pads allowed)
			(copperpour not_allowed)
			(footprints allowed)
		)
		(placement
			(enabled no)
			(sheetname "")
		)
		(fill yes
			(thermal_gap 0.5)
			(thermal_bridge_width 0.5)
			(island_removal_mode 0)
		)
		(polygon
			(pts
				(arc
					(start 332.054962 -427.289976)
					(mid 331.24521 -427.289976)
					(end 332.054962 -427.289976)
				)
			)
		)
	)
	(zone
		(layers "B.Cu" "In11.Cu" "In13.Cu" "In15.Cu")
		(hatch none 0.5)
		(connect_pads
			(clearance 0)
		)
		(min_thickness 0.25)
		(keepout
			(tracks not_allowed)
			(vias allowed)
			(pads allowed)
			(copperpour not_allowed)
			(footprints allowed)
		)
		(placement
			(enabled no)
			(sheetname "")
		)
		(fill yes
			(thermal_gap 0.5)
			(thermal_bridge_width 0.5)
			(island_removal_mode 0)
		)
		(polygon
			(pts
				(arc
					(start 385.751324 -217.064336)
					(mid 385.098544 -217.064336)
					(end 385.751324 -217.064336)
				)
			)
		)
	)
	(zone
		(layers "B.Cu" "In11.Cu" "In13.Cu" "In15.Cu")
		(hatch none 0.5)
		(connect_pads
			(clearance 0)
		)
		(min_thickness 0.25)
		(keepout
			(tracks not_allowed)
			(vias allowed)
			(pads allowed)
			(copperpour not_allowed)
			(footprints allowed)
		)
		(placement
			(enabled no)
			(sheetname "")
		)
		(fill yes
			(thermal_gap 0.5)
			(thermal_bridge_width 0.5)
			(island_removal_mode 0)
		)
		(polygon
			(pts
				(arc
					(start 127.113538 -262.058658)
					(mid 126.460758 -262.058658)
					(end 127.113538 -262.058658)
				)
			)
		)
	)
	(zone
		(layers "B.Cu" "In11.Cu" "In13.Cu" "In15.Cu")
		(hatch none 0.5)
		(connect_pads
			(clearance 0)
		)
		(min_thickness 0.25)
		(keepout
			(tracks not_allowed)
			(vias allowed)
			(pads allowed)
			(copperpour not_allowed)
			(footprints allowed)
		)
		(placement
			(enabled no)
			(sheetname "")
		)
		(fill yes
			(thermal_gap 0.5)
			(thermal_bridge_width 0.5)
			(island_removal_mode 0)
		)
		(polygon
			(pts
				(arc
					(start 385.281424 -216.25052)
					(mid 384.628644 -216.25052)
					(end 385.281424 -216.25052)
				)
			)
		)
	)
	(zone
		(layers "B.Cu" "In11.Cu" "In13.Cu" "In15.Cu")
		(hatch none 0.5)
		(connect_pads
			(clearance 0)
		)
		(min_thickness 0.25)
		(keepout
			(tracks not_allowed)
			(vias allowed)
			(pads allowed)
			(copperpour not_allowed)
			(footprints allowed)
		)
		(placement
			(enabled no)
			(sheetname "")
		)
		(fill yes
			(thermal_gap 0.5)
			(thermal_bridge_width 0.5)
			(island_removal_mode 0)
		)
		(polygon
			(pts
				(arc
					(start 109.72673 -275.8948)
					(mid 109.07395 -275.8948)
					(end 109.72673 -275.8948)
				)
			)
		)
	)
	(zone
		(layers "B.Cu" "In11.Cu" "In13.Cu" "In15.Cu")
		(hatch none 0.5)
		(connect_pads
			(clearance 0)
		)
		(min_thickness 0.25)
		(keepout
			(tracks not_allowed)
			(vias allowed)
			(pads allowed)
			(copperpour not_allowed)
			(footprints allowed)
		)
		(placement
			(enabled no)
			(sheetname "")
		)
		(fill yes
			(thermal_gap 0.5)
			(thermal_bridge_width 0.5)
			(island_removal_mode 0)
		)
		(polygon
			(pts
				(arc
					(start 207.397604 -244.916706)
					(mid 206.744824 -244.916706)
					(end 207.397604 -244.916706)
				)
			)
		)
	)
	(zone
		(layers "B.Cu" "In11.Cu" "In13.Cu" "In15.Cu")
		(hatch none 0.5)
		(connect_pads
			(clearance 0)
		)
		(min_thickness 0.25)
		(keepout
			(tracks not_allowed)
			(vias allowed)
			(pads allowed)
			(copperpour not_allowed)
			(footprints allowed)
		)
		(placement
			(enabled no)
			(sheetname "")
		)
		(fill yes
			(thermal_gap 0.5)
			(thermal_bridge_width 0.5)
			(island_removal_mode 0)
		)
		(polygon
			(pts
				(arc
					(start 440.250072 -229.616762)
					(mid 439.597292 -229.616762)
					(end 440.250072 -229.616762)
				)
			)
		)
	)
	(zone
		(layers "B.Cu" "In11.Cu" "In13.Cu" "In15.Cu")
		(hatch none 0.5)
		(connect_pads
			(clearance 0)
		)
		(min_thickness 0.25)
		(keepout
			(tracks not_allowed)
			(vias allowed)
			(pads allowed)
			(copperpour not_allowed)
			(footprints allowed)
		)
		(placement
			(enabled no)
			(sheetname "")
		)
		(fill yes
			(thermal_gap 0.5)
			(thermal_bridge_width 0.5)
			(island_removal_mode 0)
		)
		(polygon
			(pts
				(arc
					(start 188.209936 -216.866724)
					(mid 187.557156 -216.866724)
					(end 188.209936 -216.866724)
				)
			)
		)
	)
	(zone
		(layers "B.Cu" "In11.Cu" "In13.Cu" "In15.Cu")
		(hatch none 0.5)
		(connect_pads
			(clearance 0)
		)
		(min_thickness 0.25)
		(keepout
			(tracks not_allowed)
			(vias allowed)
			(pads allowed)
			(copperpour not_allowed)
			(footprints allowed)
		)
		(placement
			(enabled no)
			(sheetname "")
		)
		(fill yes
			(thermal_gap 0.5)
			(thermal_bridge_width 0.5)
			(island_removal_mode 0)
		)
		(polygon
			(pts
				(arc
					(start 341.220552 -281.59202)
					(mid 340.567772 -281.59202)
					(end 341.220552 -281.59202)
				)
			)
		)
	)
	(zone
		(layers "B.Cu" "In11.Cu" "In13.Cu" "In15.Cu")
		(hatch none 0.5)
		(connect_pads
			(clearance 0)
		)
		(min_thickness 0.25)
		(keepout
			(tracks not_allowed)
			(vias allowed)
			(pads allowed)
			(copperpour not_allowed)
			(footprints allowed)
		)
		(placement
			(enabled no)
			(sheetname "")
		)
		(fill yes
			(thermal_gap 0.5)
			(thermal_bridge_width 0.5)
			(island_removal_mode 0)
		)
		(polygon
			(pts
				(arc
					(start 347.956886 -71.816976)
					(mid 347.253306 -71.816976)
					(end 347.956886 -71.816976)
				)
			)
		)
	)
	(zone
		(layers "B.Cu" "In11.Cu" "In13.Cu" "In15.Cu")
		(hatch none 0.5)
		(connect_pads
			(clearance 0)
		)
		(min_thickness 0.25)
		(keepout
			(tracks not_allowed)
			(vias allowed)
			(pads allowed)
			(copperpour not_allowed)
			(footprints allowed)
		)
		(placement
			(enabled no)
			(sheetname "")
		)
		(fill yes
			(thermal_gap 0.5)
			(thermal_bridge_width 0.5)
			(island_removal_mode 0)
		)
		(polygon
			(pts
				(arc
					(start 65.054988 -428.28972)
					(mid 64.245236 -428.28972)
					(end 65.054988 -428.28972)
				)
			)
		)
	)
	(zone
		(layers "B.Cu" "In11.Cu" "In13.Cu" "In15.Cu")
		(hatch none 0.5)
		(connect_pads
			(clearance 0)
		)
		(min_thickness 0.25)
		(keepout
			(tracks not_allowed)
			(vias allowed)
			(pads allowed)
			(copperpour not_allowed)
			(footprints allowed)
		)
		(placement
			(enabled no)
			(sheetname "")
		)
		(fill yes
			(thermal_gap 0.5)
			(thermal_bridge_width 0.5)
			(island_removal_mode 0)
		)
		(polygon
			(pts
				(arc
					(start 374.943624 -235.783882)
					(mid 374.290844 -235.783882)
					(end 374.943624 -235.783882)
				)
			)
		)
	)
	(zone
		(layers "B.Cu" "In11.Cu" "In13.Cu" "In15.Cu")
		(hatch none 0.5)
		(connect_pads
			(clearance 0)
		)
		(min_thickness 0.25)
		(keepout
			(tracks not_allowed)
			(vias allowed)
			(pads allowed)
			(copperpour not_allowed)
			(footprints allowed)
		)
		(placement
			(enabled no)
			(sheetname "")
		)
		(fill yes
			(thermal_gap 0.5)
			(thermal_bridge_width 0.5)
			(island_removal_mode 0)
		)
		(polygon
			(pts
				(arc
					(start 188.209936 -230.466646)
					(mid 187.557156 -230.466646)
					(end 188.209936 -230.466646)
				)
			)
		)
	)
	(zone
		(layers "B.Cu" "In11.Cu" "In13.Cu" "In15.Cu")
		(hatch none 0.5)
		(connect_pads
			(clearance 0)
		)
		(min_thickness 0.25)
		(keepout
			(tracks not_allowed)
			(vias allowed)
			(pads allowed)
			(copperpour not_allowed)
			(footprints allowed)
		)
		(placement
			(enabled no)
			(sheetname "")
		)
		(fill yes
			(thermal_gap 0.5)
			(thermal_bridge_width 0.5)
			(island_removal_mode 0)
		)
		(polygon
			(pts
				(arc
					(start 354.73767 -215.436704)
					(mid 354.08489 -215.436704)
					(end 354.73767 -215.436704)
				)
			)
		)
	)
	(zone
		(layers "B.Cu" "In11.Cu" "In13.Cu" "In15.Cu")
		(hatch none 0.5)
		(connect_pads
			(clearance 0)
		)
		(min_thickness 0.25)
		(keepout
			(tracks not_allowed)
			(vias allowed)
			(pads allowed)
			(copperpour not_allowed)
			(footprints allowed)
		)
		(placement
			(enabled no)
			(sheetname "")
		)
		(fill yes
			(thermal_gap 0.5)
			(thermal_bridge_width 0.5)
			(island_removal_mode 0)
		)
		(polygon
			(pts
				(arc
					(start 413.154876 -430.689766)
					(mid 412.345124 -430.689766)
					(end 413.154876 -430.689766)
				)
			)
		)
	)
	(zone
		(layers "B.Cu" "In11.Cu" "In13.Cu" "In15.Cu")
		(hatch none 0.5)
		(connect_pads
			(clearance 0)
		)
		(min_thickness 0.25)
		(keepout
			(tracks not_allowed)
			(vias allowed)
			(pads allowed)
			(copperpour not_allowed)
			(footprints allowed)
		)
		(placement
			(enabled no)
			(sheetname "")
		)
		(fill yes
			(thermal_gap 0.5)
			(thermal_bridge_width 0.5)
			(island_removal_mode 0)
		)
		(polygon
			(pts
				(arc
					(start 106.327448 -214.622634)
					(mid 105.674668 -214.622634)
					(end 106.327448 -214.622634)
				)
			)
		)
	)
	(zone
		(layers "B.Cu" "In11.Cu" "In13.Cu" "In15.Cu")
		(hatch none 0.5)
		(connect_pads
			(clearance 0)
		)
		(min_thickness 0.25)
		(keepout
			(tracks not_allowed)
			(vias allowed)
			(pads allowed)
			(copperpour not_allowed)
			(footprints allowed)
		)
		(placement
			(enabled no)
			(sheetname "")
		)
		(fill yes
			(thermal_gap 0.5)
			(thermal_bridge_width 0.5)
			(island_removal_mode 0)
		)
		(polygon
			(pts
				(arc
					(start 360.846624 -227.64496)
					(mid 360.193844 -227.64496)
					(end 360.846624 -227.64496)
				)
			)
		)
	)
	(zone
		(layers "B.Cu" "In11.Cu" "In13.Cu" "In15.Cu")
		(hatch none 0.5)
		(connect_pads
			(clearance 0)
		)
		(min_thickness 0.25)
		(keepout
			(tracks not_allowed)
			(vias allowed)
			(pads allowed)
			(copperpour not_allowed)
			(footprints allowed)
		)
		(placement
			(enabled no)
			(sheetname "")
		)
		(fill yes
			(thermal_gap 0.5)
			(thermal_bridge_width 0.5)
			(island_removal_mode 0)
		)
		(polygon
			(pts
				(arc
					(start 419.06952 -410.030168)
					(mid 418.36594 -410.030168)
					(end 419.06952 -410.030168)
				)
			)
		)
	)
	(zone
		(layers "B.Cu" "In11.Cu" "In13.Cu" "In15.Cu")
		(hatch none 0.5)
		(connect_pads
			(clearance 0)
		)
		(min_thickness 0.25)
		(keepout
			(tracks not_allowed)
			(vias allowed)
			(pads allowed)
			(copperpour not_allowed)
			(footprints allowed)
		)
		(placement
			(enabled no)
			(sheetname "")
		)
		(fill yes
			(thermal_gap 0.5)
			(thermal_bridge_width 0.5)
			(island_removal_mode 0)
		)
		(polygon
			(pts
				(arc
					(start 375.41327 -243.108988)
					(mid 374.76049 -243.108988)
					(end 375.41327 -243.108988)
				)
			)
		)
	)
	(zone
		(layers "B.Cu" "In11.Cu" "In13.Cu" "In15.Cu")
		(hatch none 0.5)
		(connect_pads
			(clearance 0)
		)
		(min_thickness 0.25)
		(keepout
			(tracks not_allowed)
			(vias allowed)
			(pads allowed)
			(copperpour not_allowed)
			(footprints allowed)
		)
		(placement
			(enabled no)
			(sheetname "")
		)
		(fill yes
			(thermal_gap 0.5)
			(thermal_bridge_width 0.5)
			(island_removal_mode 0)
		)
		(polygon
			(pts
				(arc
					(start 127.583184 -261.244842)
					(mid 126.930404 -261.244842)
					(end 127.583184 -261.244842)
				)
			)
		)
	)
	(zone
		(layers "B.Cu" "In11.Cu" "In13.Cu" "In15.Cu")
		(hatch none 0.5)
		(connect_pads
			(clearance 0)
		)
		(min_thickness 0.25)
		(keepout
			(tracks not_allowed)
			(vias allowed)
			(pads allowed)
			(copperpour not_allowed)
			(footprints allowed)
		)
		(placement
			(enabled no)
			(sheetname "")
		)
		(fill yes
			(thermal_gap 0.5)
			(thermal_bridge_width 0.5)
			(island_removal_mode 0)
		)
		(polygon
			(pts
				(arc
					(start 153.348944 -410.030168)
					(mid 152.645364 -410.030168)
					(end 153.348944 -410.030168)
				)
			)
		)
	)
	(zone
		(layers "B.Cu" "In11.Cu" "In13.Cu" "In15.Cu")
		(hatch none 0.5)
		(connect_pads
			(clearance 0)
		)
		(min_thickness 0.25)
		(keepout
			(tracks not_allowed)
			(vias allowed)
			(pads allowed)
			(copperpour not_allowed)
			(footprints allowed)
		)
		(placement
			(enabled no)
			(sheetname "")
		)
		(fill yes
			(thermal_gap 0.5)
			(thermal_bridge_width 0.5)
			(island_removal_mode 0)
		)
		(polygon
			(pts
				(arc
					(start 280.143204 -274.66671)
					(mid 279.490424 -274.66671)
					(end 280.143204 -274.66671)
				)
			)
		)
	)
	(zone
		(layers "B.Cu" "In11.Cu" "In13.Cu" "In15.Cu")
		(hatch none 0.5)
		(connect_pads
			(clearance 0)
		)
		(min_thickness 0.25)
		(keepout
			(tracks not_allowed)
			(vias allowed)
			(pads allowed)
			(copperpour not_allowed)
			(footprints allowed)
		)
		(placement
			(enabled no)
			(sheetname "")
		)
		(fill yes
			(thermal_gap 0.5)
			(thermal_bridge_width 0.5)
			(island_removal_mode 0)
		)
		(polygon
			(pts
				(arc
					(start 342.990424 -232.528364)
					(mid 342.337644 -232.528364)
					(end 342.990424 -232.528364)
				)
			)
		)
	)
	(zone
		(layers "B.Cu" "In11.Cu" "In13.Cu" "In15.Cu")
		(hatch none 0.5)
		(connect_pads
			(clearance 0)
		)
		(min_thickness 0.25)
		(keepout
			(tracks not_allowed)
			(vias allowed)
			(pads allowed)
			(copperpour not_allowed)
			(footprints allowed)
		)
		(placement
			(enabled no)
			(sheetname "")
		)
		(fill yes
			(thermal_gap 0.5)
			(thermal_bridge_width 0.5)
			(island_removal_mode 0)
		)
		(polygon
			(pts
				(arc
					(start 106.907584 -277.522432)
					(mid 106.254804 -277.522432)
					(end 106.907584 -277.522432)
				)
			)
		)
	)
	(zone
		(layers "B.Cu" "In11.Cu" "In13.Cu" "In15.Cu")
		(hatch none 0.5)
		(connect_pads
			(clearance 0)
		)
		(min_thickness 0.25)
		(keepout
			(tracks not_allowed)
			(vias allowed)
			(pads allowed)
			(copperpour not_allowed)
			(footprints allowed)
		)
		(placement
			(enabled no)
			(sheetname "")
		)
		(fill yes
			(thermal_gap 0.5)
			(thermal_bridge_width 0.5)
			(island_removal_mode 0)
		)
		(polygon
			(pts
				(arc
					(start 436.150004 -303.566576)
					(mid 435.497224 -303.566576)
					(end 436.150004 -303.566576)
				)
			)
		)
	)
	(zone
		(layers "B.Cu" "In11.Cu" "In13.Cu" "In15.Cu")
		(hatch none 0.5)
		(connect_pads
			(clearance 0)
		)
		(min_thickness 0.25)
		(keepout
			(tracks not_allowed)
			(vias allowed)
			(pads allowed)
			(copperpour not_allowed)
			(footprints allowed)
		)
		(placement
			(enabled no)
			(sheetname "")
		)
		(fill yes
			(thermal_gap 0.5)
			(thermal_bridge_width 0.5)
			(island_removal_mode 0)
		)
		(polygon
			(pts
				(arc
					(start 335.581752 -284.847538)
					(mid 334.928972 -284.847538)
					(end 335.581752 -284.847538)
				)
			)
		)
	)
	(zone
		(layers "B.Cu" "In11.Cu" "In13.Cu" "In15.Cu")
		(hatch none 0.5)
		(connect_pads
			(clearance 0)
		)
		(min_thickness 0.25)
		(keepout
			(tracks not_allowed)
			(vias allowed)
			(pads allowed)
			(copperpour not_allowed)
			(footprints allowed)
		)
		(placement
			(enabled no)
			(sheetname "")
		)
		(fill yes
			(thermal_gap 0.5)
			(thermal_bridge_width 0.5)
			(island_removal_mode 0)
		)
		(polygon
			(pts
				(arc
					(start 192.310004 -227.91674)
					(mid 191.657224 -227.91674)
					(end 192.310004 -227.91674)
				)
			)
		)
	)
	(zone
		(layers "B.Cu" "In11.Cu" "In13.Cu" "In15.Cu")
		(hatch none 0.5)
		(connect_pads
			(clearance 0)
		)
		(min_thickness 0.25)
		(keepout
			(tracks not_allowed)
			(vias allowed)
			(pads allowed)
			(copperpour not_allowed)
			(footprints allowed)
		)
		(placement
			(enabled no)
			(sheetname "")
		)
		(fill yes
			(thermal_gap 0.5)
			(thermal_bridge_width 0.5)
			(island_removal_mode 0)
		)
		(polygon
			(pts
				(arc
					(start 455.337672 -209.216752)
					(mid 454.684892 -209.216752)
					(end 455.337672 -209.216752)
				)
			)
		)
	)
	(zone
		(layers "B.Cu" "In11.Cu" "In13.Cu" "In15.Cu")
		(hatch none 0.5)
		(connect_pads
			(clearance 0)
		)
		(min_thickness 0.25)
		(keepout
			(tracks not_allowed)
			(vias allowed)
			(pads allowed)
			(copperpour not_allowed)
			(footprints allowed)
		)
		(placement
			(enabled no)
			(sheetname "")
		)
		(fill yes
			(thermal_gap 0.5)
			(thermal_bridge_width 0.5)
			(island_removal_mode 0)
		)
		(polygon
			(pts
				(arc
					(start 151.154892 -430.889918)
					(mid 150.34514 -430.889918)
					(end 151.154892 -430.889918)
				)
			)
		)
	)
	(zone
		(layers "B.Cu" "In11.Cu" "In13.Cu" "In15.Cu")
		(hatch none 0.5)
		(connect_pads
			(clearance 0)
		)
		(min_thickness 0.25)
		(keepout
			(tracks not_allowed)
			(vias allowed)
			(pads allowed)
			(copperpour not_allowed)
			(footprints allowed)
		)
		(placement
			(enabled no)
			(sheetname "")
		)
		(fill yes
			(thermal_gap 0.5)
			(thermal_bridge_width 0.5)
			(island_removal_mode 0)
		)
		(polygon
			(pts
				(arc
					(start 128.413002 -234.970066)
					(mid 127.760222 -234.970066)
					(end 128.413002 -234.970066)
				)
			)
		)
	)
	(zone
		(layers "B.Cu" "In11.Cu" "In13.Cu" "In15.Cu")
		(hatch none 0.5)
		(connect_pads
			(clearance 0)
		)
		(min_thickness 0.25)
		(keepout
			(tracks not_allowed)
			(vias allowed)
			(pads allowed)
			(copperpour not_allowed)
			(footprints allowed)
		)
		(placement
			(enabled no)
			(sheetname "")
		)
		(fill yes
			(thermal_gap 0.5)
			(thermal_bridge_width 0.5)
			(island_removal_mode 0)
		)
		(polygon
			(pts
				(arc
					(start 97.399602 -243.108988)
					(mid 96.746822 -243.108988)
					(end 97.399602 -243.108988)
				)
			)
		)
	)
	(zone
		(layers "B.Cu" "In11.Cu" "In13.Cu" "In15.Cu")
		(hatch none 0.5)
		(connect_pads
			(clearance 0)
		)
		(min_thickness 0.25)
		(keepout
			(tracks not_allowed)
			(vias allowed)
			(pads allowed)
			(copperpour not_allowed)
			(footprints allowed)
		)
		(placement
			(enabled no)
			(sheetname "")
		)
		(fill yes
			(thermal_gap 0.5)
			(thermal_bridge_width 0.5)
			(island_removal_mode 0)
		)
		(polygon
			(pts
				(arc
					(start 36.303204 -278.066754)
					(mid 35.650424 -278.066754)
					(end 36.303204 -278.066754)
				)
			)
		)
	)
	(zone
		(layers "B.Cu" "In11.Cu" "In13.Cu" "In15.Cu")
		(hatch none 0.5)
		(connect_pads
			(clearance 0)
		)
		(min_thickness 0.25)
		(keepout
			(tracks not_allowed)
			(vias allowed)
			(pads allowed)
			(copperpour not_allowed)
			(footprints allowed)
		)
		(placement
			(enabled no)
			(sheetname "")
		)
		(fill yes
			(thermal_gap 0.5)
			(thermal_bridge_width 0.5)
			(island_removal_mode 0)
		)
		(polygon
			(pts
				(arc
					(start 82.054954 -427.089824)
					(mid 81.245202 -427.089824)
					(end 82.054954 -427.089824)
				)
			)
		)
	)
	(zone
		(layers "B.Cu" "In11.Cu" "In13.Cu" "In15.Cu")
		(hatch none 0.5)
		(connect_pads
			(clearance 0)
		)
		(min_thickness 0.25)
		(keepout
			(tracks not_allowed)
			(vias allowed)
			(pads allowed)
			(copperpour not_allowed)
			(footprints allowed)
		)
		(placement
			(enabled no)
			(sheetname "")
		)
		(fill yes
			(thermal_gap 0.5)
			(thermal_bridge_width 0.5)
			(island_removal_mode 0)
		)
		(polygon
			(pts
				(arc
					(start 334.054958 -434.289962)
					(mid 333.245206 -434.289962)
					(end 334.054958 -434.289962)
				)
			)
		)
	)
	(zone
		(layers "B.Cu" "In11.Cu" "In13.Cu" "In15.Cu")
		(hatch none 0.5)
		(connect_pads
			(clearance 0)
		)
		(min_thickness 0.25)
		(keepout
			(tracks not_allowed)
			(vias allowed)
			(pads allowed)
			(copperpour not_allowed)
			(footprints allowed)
		)
		(placement
			(enabled no)
			(sheetname "")
		)
		(fill yes
			(thermal_gap 0.5)
			(thermal_bridge_width 0.5)
			(island_removal_mode 0)
		)
		(polygon
			(pts
				(arc
					(start 116.665248 -214.622634)
					(mid 116.012468 -214.622634)
					(end 116.665248 -214.622634)
				)
			)
		)
	)
	(zone
		(layers "B.Cu" "In11.Cu" "In13.Cu" "In15.Cu")
		(hatch none 0.5)
		(connect_pads
			(clearance 0)
		)
		(min_thickness 0.25)
		(keepout
			(tracks not_allowed)
			(vias allowed)
			(pads allowed)
			(copperpour not_allowed)
			(footprints allowed)
		)
		(placement
			(enabled no)
			(sheetname "")
		)
		(fill yes
			(thermal_gap 0.5)
			(thermal_bridge_width 0.5)
			(island_removal_mode 0)
		)
		(polygon
			(pts
				(arc
					(start 374.943624 -240.667286)
					(mid 374.290844 -240.667286)
					(end 374.943624 -240.667286)
				)
			)
		)
	)
	(zone
		(layers "B.Cu" "In11.Cu" "In13.Cu" "In15.Cu")
		(hatch none 0.5)
		(connect_pads
			(clearance 0)
		)
		(min_thickness 0.25)
		(keepout
			(tracks not_allowed)
			(vias allowed)
			(pads allowed)
			(copperpour not_allowed)
			(footprints allowed)
		)
		(placement
			(enabled no)
			(sheetname "")
		)
		(fill yes
			(thermal_gap 0.5)
			(thermal_bridge_width 0.5)
			(island_removal_mode 0)
		)
		(polygon
			(pts
				(arc
					(start 342.160352 -283.219906)
					(mid 341.507572 -283.219906)
					(end 342.160352 -283.219906)
				)
			)
		)
	)
	(zone
		(layers "B.Cu" "In11.Cu" "In13.Cu" "In15.Cu")
		(hatch none 0.5)
		(connect_pads
			(clearance 0)
		)
		(min_thickness 0.25)
		(keepout
			(tracks not_allowed)
			(vias allowed)
			(pads allowed)
			(copperpour not_allowed)
			(footprints allowed)
		)
		(placement
			(enabled no)
			(sheetname "")
		)
		(fill yes
			(thermal_gap 0.5)
			(thermal_bridge_width 0.5)
			(island_removal_mode 0)
		)
		(polygon
			(pts
				(arc
					(start 411.15488 -429.689768)
					(mid 410.345128 -429.689768)
					(end 411.15488 -429.689768)
				)
			)
		)
	)
	(zone
		(layers "B.Cu" "In11.Cu" "In13.Cu" "In15.Cu")
		(hatch none 0.5)
		(connect_pads
			(clearance 0)
		)
		(min_thickness 0.25)
		(keepout
			(tracks not_allowed)
			(vias allowed)
			(pads allowed)
			(copperpour not_allowed)
			(footprints allowed)
		)
		(placement
			(enabled no)
			(sheetname "")
		)
		(fill yes
			(thermal_gap 0.5)
			(thermal_bridge_width 0.5)
			(island_removal_mode 0)
		)
		(polygon
			(pts
				(arc
					(start 36.303204 -281.466798)
					(mid 35.650424 -281.466798)
					(end 36.303204 -281.466798)
				)
			)
		)
	)
	(zone
		(layers "B.Cu" "In11.Cu" "In13.Cu" "In15.Cu")
		(hatch none 0.5)
		(connect_pads
			(clearance 0)
		)
		(min_thickness 0.25)
		(keepout
			(tracks not_allowed)
			(vias allowed)
			(pads allowed)
			(copperpour not_allowed)
			(footprints allowed)
		)
		(placement
			(enabled no)
			(sheetname "")
		)
		(fill yes
			(thermal_gap 0.5)
			(thermal_bridge_width 0.5)
			(island_removal_mode 0)
		)
		(polygon
			(pts
				(arc
					(start 354.086414 -50.207672)
					(mid 353.382834 -50.207672)
					(end 354.086414 -50.207672)
				)
			)
		)
	)
	(zone
		(layers "B.Cu" "In11.Cu" "In13.Cu" "In15.Cu")
		(hatch none 0.5)
		(connect_pads
			(clearance 0)
		)
		(min_thickness 0.25)
		(keepout
			(tracks not_allowed)
			(vias allowed)
			(pads allowed)
			(copperpour not_allowed)
			(footprints allowed)
		)
		(placement
			(enabled no)
			(sheetname "")
		)
		(fill yes
			(thermal_gap 0.5)
			(thermal_bridge_width 0.5)
			(island_removal_mode 0)
		)
		(polygon
			(pts
				(arc
					(start 342.520524 -213.732618)
					(mid 341.867744 -213.732618)
					(end 342.520524 -213.732618)
				)
			)
		)
	)
	(zone
		(layers "B.Cu" "In11.Cu" "In13.Cu" "In15.Cu")
		(hatch none 0.5)
		(connect_pads
			(clearance 0)
		)
		(min_thickness 0.25)
		(keepout
			(tracks not_allowed)
			(vias allowed)
			(pads allowed)
			(copperpour not_allowed)
			(footprints allowed)
		)
		(placement
			(enabled no)
			(sheetname "")
		)
		(fill yes
			(thermal_gap 0.5)
			(thermal_bridge_width 0.5)
			(island_removal_mode 0)
		)
		(polygon
			(pts
				(arc
					(start 104.558338 -276.708616)
					(mid 103.905558 -276.708616)
					(end 104.558338 -276.708616)
				)
			)
		)
	)
	(zone
		(layers "B.Cu" "In11.Cu" "In13.Cu" "In15.Cu")
		(hatch none 0.5)
		(connect_pads
			(clearance 0)
		)
		(min_thickness 0.25)
		(keepout
			(tracks not_allowed)
			(vias allowed)
			(pads allowed)
			(copperpour not_allowed)
			(footprints allowed)
		)
		(placement
			(enabled no)
			(sheetname "")
		)
		(fill yes
			(thermal_gap 0.5)
			(thermal_bridge_width 0.5)
			(island_removal_mode 0)
		)
		(polygon
			(pts
				(arc
					(start 128.413256 -213.732618)
					(mid 127.760476 -213.732618)
					(end 128.413256 -213.732618)
				)
			)
		)
	)
	(zone
		(layers "B.Cu" "In11.Cu" "In13.Cu" "In15.Cu")
		(hatch none 0.5)
		(connect_pads
			(clearance 0)
		)
		(min_thickness 0.25)
		(keepout
			(tracks not_allowed)
			(vias allowed)
			(pads allowed)
			(copperpour not_allowed)
			(footprints allowed)
		)
		(placement
			(enabled no)
			(sheetname "")
		)
		(fill yes
			(thermal_gap 0.5)
			(thermal_bridge_width 0.5)
			(island_removal_mode 0)
		)
		(polygon
			(pts
				(arc
					(start 88.054942 -427.289976)
					(mid 87.24519 -427.289976)
					(end 88.054942 -427.289976)
				)
			)
		)
	)
	(zone
		(layers "B.Cu" "In11.Cu" "In13.Cu" "In15.Cu")
		(hatch none 0.5)
		(connect_pads
			(clearance 0)
		)
		(min_thickness 0.25)
		(keepout
			(tracks not_allowed)
			(vias allowed)
			(pads allowed)
			(copperpour not_allowed)
			(footprints allowed)
		)
		(placement
			(enabled no)
			(sheetname "")
		)
		(fill yes
			(thermal_gap 0.5)
			(thermal_bridge_width 0.5)
			(island_removal_mode 0)
		)
		(polygon
			(pts
				(arc
					(start 203.297536 -210.066636)
					(mid 202.644756 -210.066636)
					(end 203.297536 -210.066636)
				)
			)
		)
	)
	(zone
		(layers "B.Cu" "In11.Cu" "In13.Cu" "In15.Cu")
		(hatch none 0.5)
		(connect_pads
			(clearance 0)
		)
		(min_thickness 0.25)
		(keepout
			(tracks not_allowed)
			(vias allowed)
			(pads allowed)
			(copperpour not_allowed)
			(footprints allowed)
		)
		(placement
			(enabled no)
			(sheetname "")
		)
		(fill yes
			(thermal_gap 0.5)
			(thermal_bridge_width 0.5)
			(island_removal_mode 0)
		)
		(polygon
			(pts
				(arc
					(start 343.930224 -242.294918)
					(mid 343.277444 -242.294918)
					(end 343.930224 -242.294918)
				)
			)
		)
	)
	(zone
		(layers "B.Cu" "In11.Cu" "In13.Cu" "In15.Cu")
		(hatch none 0.5)
		(connect_pads
			(clearance 0)
		)
		(min_thickness 0.25)
		(keepout
			(tracks not_allowed)
			(vias allowed)
			(pads allowed)
			(copperpour not_allowed)
			(footprints allowed)
		)
		(placement
			(enabled no)
			(sheetname "")
		)
		(fill yes
			(thermal_gap 0.5)
			(thermal_bridge_width 0.5)
			(island_removal_mode 0)
		)
		(polygon
			(pts
				(arc
					(start 130.762248 -214.622634)
					(mid 130.109468 -214.622634)
					(end 130.762248 -214.622634)
				)
			)
		)
	)
	(zone
		(layers "B.Cu" "In11.Cu" "In13.Cu" "In15.Cu")
		(hatch none 0.5)
		(connect_pads
			(clearance 0)
		)
		(min_thickness 0.25)
		(keepout
			(tracks not_allowed)
			(vias allowed)
			(pads allowed)
			(copperpour not_allowed)
			(footprints allowed)
		)
		(placement
			(enabled no)
			(sheetname "")
		)
		(fill yes
			(thermal_gap 0.5)
			(thermal_bridge_width 0.5)
			(island_removal_mode 0)
		)
		(polygon
			(pts
				(arc
					(start 354.224336 -183.567832)
					(mid 353.520756 -183.567832)
					(end 354.224336 -183.567832)
				)
			)
		)
	)
	(zone
		(layers "B.Cu" "In11.Cu" "In13.Cu" "In15.Cu")
		(hatch none 0.5)
		(connect_pads
			(clearance 0)
		)
		(min_thickness 0.25)
		(keepout
			(tracks not_allowed)
			(vias allowed)
			(pads allowed)
			(copperpour not_allowed)
			(footprints allowed)
		)
		(placement
			(enabled no)
			(sheetname "")
		)
		(fill yes
			(thermal_gap 0.5)
			(thermal_bridge_width 0.5)
			(island_removal_mode 0)
		)
		(polygon
			(pts
				(arc
					(start 32.203136 -244.066568)
					(mid 31.550356 -244.066568)
					(end 32.203136 -244.066568)
				)
			)
		)
	)
	(zone
		(layers "B.Cu" "In11.Cu" "In13.Cu" "In15.Cu")
		(hatch none 0.5)
		(connect_pads
			(clearance 0)
		)
		(min_thickness 0.25)
		(keepout
			(tracks not_allowed)
			(vias allowed)
			(pads allowed)
			(copperpour not_allowed)
			(footprints allowed)
		)
		(placement
			(enabled no)
			(sheetname "")
		)
		(fill yes
			(thermal_gap 0.5)
			(thermal_bridge_width 0.5)
			(island_removal_mode 0)
		)
		(polygon
			(pts
				(arc
					(start 36.303204 -287.416748)
					(mid 35.650424 -287.416748)
					(end 36.303204 -287.416748)
				)
			)
		)
	)
	(zone
		(layers "B.Cu" "In11.Cu" "In13.Cu" "In15.Cu")
		(hatch none 0.5)
		(connect_pads
			(clearance 0)
		)
		(min_thickness 0.25)
		(keepout
			(tracks not_allowed)
			(vias allowed)
			(pads allowed)
			(copperpour not_allowed)
			(footprints allowed)
		)
		(placement
			(enabled no)
			(sheetname "")
		)
		(fill yes
			(thermal_gap 0.5)
			(thermal_bridge_width 0.5)
			(island_removal_mode 0)
		)
		(polygon
			(pts
				(arc
					(start 376.463052 -266.128246)
					(mid 375.810272 -266.128246)
					(end 376.463052 -266.128246)
				)
			)
		)
	)
	(zone
		(layers "B.Cu" "In11.Cu" "In13.Cu" "In15.Cu")
		(hatch none 0.5)
		(connect_pads
			(clearance 0)
		)
		(min_thickness 0.25)
		(keepout
			(tracks not_allowed)
			(vias allowed)
			(pads allowed)
			(copperpour not_allowed)
			(footprints allowed)
		)
		(placement
			(enabled no)
			(sheetname "")
		)
		(fill yes
			(thermal_gap 0.5)
			(thermal_bridge_width 0.5)
			(island_removal_mode 0)
		)
		(polygon
			(pts
				(arc
					(start 374.583452 -277.522432)
					(mid 373.930672 -277.522432)
					(end 374.583452 -277.522432)
				)
			)
		)
	)
	(zone
		(layers "B.Cu" "In11.Cu" "In13.Cu" "In15.Cu")
		(hatch none 0.5)
		(connect_pads
			(clearance 0)
		)
		(min_thickness 0.25)
		(keepout
			(tracks not_allowed)
			(vias allowed)
			(pads allowed)
			(copperpour not_allowed)
			(footprints allowed)
		)
		(placement
			(enabled no)
			(sheetname "")
		)
		(fill yes
			(thermal_gap 0.5)
			(thermal_bridge_width 0.5)
			(island_removal_mode 0)
		)
		(polygon
			(pts
				(arc
					(start 93.170248 -214.622634)
					(mid 92.517468 -214.622634)
					(end 93.170248 -214.622634)
				)
			)
		)
	)
	(zone
		(layers "B.Cu" "In11.Cu" "In13.Cu" "In15.Cu")
		(hatch none 0.5)
		(connect_pads
			(clearance 0)
		)
		(min_thickness 0.25)
		(keepout
			(tracks not_allowed)
			(vias allowed)
			(pads allowed)
			(copperpour not_allowed)
			(footprints allowed)
		)
		(placement
			(enabled no)
			(sheetname "")
		)
		(fill yes
			(thermal_gap 0.5)
			(thermal_bridge_width 0.5)
			(island_removal_mode 0)
		)
		(polygon
			(pts
				(arc
					(start 364.605824 -227.64496)
					(mid 363.953044 -227.64496)
					(end 364.605824 -227.64496)
				)
			)
		)
	)
	(zone
		(layers "B.Cu" "In11.Cu" "In13.Cu" "In15.Cu")
		(hatch none 0.5)
		(connect_pads
			(clearance 0)
		)
		(min_thickness 0.25)
		(keepout
			(tracks not_allowed)
			(vias allowed)
			(pads allowed)
			(copperpour not_allowed)
			(footprints allowed)
		)
		(placement
			(enabled no)
			(sheetname "")
		)
		(fill yes
			(thermal_gap 0.5)
			(thermal_bridge_width 0.5)
			(island_removal_mode 0)
		)
		(polygon
			(pts
				(arc
					(start 380.22276 -254.733552)
					(mid 379.56998 -254.733552)
					(end 380.22276 -254.733552)
				)
			)
		)
	)
	(zone
		(layers "B.Cu" "In11.Cu" "In13.Cu" "In15.Cu")
		(hatch none 0.5)
		(connect_pads
			(clearance 0)
		)
		(min_thickness 0.25)
		(keepout
			(tracks not_allowed)
			(vias allowed)
			(pads allowed)
			(copperpour not_allowed)
			(footprints allowed)
		)
		(placement
			(enabled no)
			(sheetname "")
		)
		(fill yes
			(thermal_gap 0.5)
			(thermal_bridge_width 0.5)
			(island_removal_mode 0)
		)
		(polygon
			(pts
				(arc
					(start 21.215604 -208.366614)
					(mid 20.562824 -208.366614)
					(end 21.215604 -208.366614)
				)
			)
		)
	)
	(zone
		(layers "B.Cu" "In11.Cu" "In13.Cu" "In15.Cu")
		(hatch none 0.5)
		(connect_pads
			(clearance 0)
		)
		(min_thickness 0.25)
		(keepout
			(tracks not_allowed)
			(vias allowed)
			(pads allowed)
			(copperpour not_allowed)
			(footprints allowed)
		)
		(placement
			(enabled no)
			(sheetname "")
		)
		(fill yes
			(thermal_gap 0.5)
			(thermal_bridge_width 0.5)
			(island_removal_mode 0)
		)
		(polygon
			(pts
				(arc
					(start 356.61727 -215.436704)
					(mid 355.96449 -215.436704)
					(end 356.61727 -215.436704)
				)
			)
		)
	)
	(zone
		(layers "B.Cu" "In11.Cu" "In13.Cu" "In15.Cu")
		(hatch none 0.5)
		(connect_pads
			(clearance 0)
		)
		(min_thickness 0.25)
		(keepout
			(tracks not_allowed)
			(vias allowed)
			(pads allowed)
			(copperpour not_allowed)
			(footprints allowed)
		)
		(placement
			(enabled no)
			(sheetname "")
		)
		(fill yes
			(thermal_gap 0.5)
			(thermal_bridge_width 0.5)
			(island_removal_mode 0)
		)
		(polygon
			(pts
				(arc
					(start 395.4272 -410.030168)
					(mid 394.72362 -410.030168)
					(end 395.4272 -410.030168)
				)
			)
		)
	)
	(zone
		(layers "B.Cu" "In11.Cu" "In13.Cu" "In15.Cu")
		(hatch none 0.5)
		(connect_pads
			(clearance 0)
		)
		(min_thickness 0.25)
		(keepout
			(tracks not_allowed)
			(vias allowed)
			(pads allowed)
			(copperpour not_allowed)
			(footprints allowed)
		)
		(placement
			(enabled no)
			(sheetname "")
		)
		(fill yes
			(thermal_gap 0.5)
			(thermal_bridge_width 0.5)
			(island_removal_mode 0)
		)
		(polygon
			(pts
				(arc
					(start 376.35307 -236.597952)
					(mid 375.70029 -236.597952)
					(end 376.35307 -236.597952)
				)
			)
		)
	)
	(zone
		(layers "B.Cu" "In11.Cu" "In13.Cu" "In15.Cu")
		(hatch none 0.5)
		(connect_pads
			(clearance 0)
		)
		(min_thickness 0.25)
		(keepout
			(tracks not_allowed)
			(vias allowed)
			(pads allowed)
			(copperpour not_allowed)
			(footprints allowed)
		)
		(placement
			(enabled no)
			(sheetname "")
		)
		(fill yes
			(thermal_gap 0.5)
			(thermal_bridge_width 0.5)
			(island_removal_mode 0)
		)
		(polygon
			(pts
				(arc
					(start 17.115536 -213.46668)
					(mid 16.462756 -213.46668)
					(end 17.115536 -213.46668)
				)
			)
		)
	)
	(zone
		(layers "B.Cu" "In11.Cu" "In13.Cu" "In15.Cu")
		(hatch none 0.5)
		(connect_pads
			(clearance 0)
		)
		(min_thickness 0.25)
		(keepout
			(tracks not_allowed)
			(vias allowed)
			(pads allowed)
			(copperpour not_allowed)
			(footprints allowed)
		)
		(placement
			(enabled no)
			(sheetname "")
		)
		(fill yes
			(thermal_gap 0.5)
			(thermal_bridge_width 0.5)
			(island_removal_mode 0)
		)
		(polygon
			(pts
				(arc
					(start 128.993138 -273.453098)
					(mid 128.340358 -273.453098)
					(end 128.993138 -273.453098)
				)
			)
		)
	)
	(zone
		(layers "B.Cu" "In11.Cu" "In13.Cu" "In15.Cu")
		(hatch none 0.5)
		(connect_pads
			(clearance 0)
		)
		(min_thickness 0.25)
		(keepout
			(tracks not_allowed)
			(vias allowed)
			(pads allowed)
			(copperpour not_allowed)
			(footprints allowed)
		)
		(placement
			(enabled no)
			(sheetname "")
		)
		(fill yes
			(thermal_gap 0.5)
			(thermal_bridge_width 0.5)
			(island_removal_mode 0)
		)
		(polygon
			(pts
				(arc
					(start 129.352802 -230.086662)
					(mid 128.700022 -230.086662)
					(end 129.352802 -230.086662)
				)
			)
		)
	)
	(zone
		(layers "B.Cu" "In11.Cu" "In13.Cu" "In15.Cu")
		(hatch none 0.5)
		(connect_pads
			(clearance 0)
		)
		(min_thickness 0.25)
		(keepout
			(tracks not_allowed)
			(vias allowed)
			(pads allowed)
			(copperpour not_allowed)
			(footprints allowed)
		)
		(placement
			(enabled no)
			(sheetname "")
		)
		(fill yes
			(thermal_gap 0.5)
			(thermal_bridge_width 0.5)
			(island_removal_mode 0)
		)
		(polygon
			(pts
				(arc
					(start 304.331878 -403.883876)
					(mid 303.628298 -403.883876)
					(end 304.331878 -403.883876)
				)
			)
		)
	)
	(zone
		(layers "B.Cu" "In11.Cu" "In13.Cu" "In15.Cu")
		(hatch none 0.5)
		(connect_pads
			(clearance 0)
		)
		(min_thickness 0.25)
		(keepout
			(tracks not_allowed)
			(vias allowed)
			(pads allowed)
			(copperpour not_allowed)
			(footprints allowed)
		)
		(placement
			(enabled no)
			(sheetname "")
		)
		(fill yes
			(thermal_gap 0.5)
			(thermal_bridge_width 0.5)
			(island_removal_mode 0)
		)
		(polygon
			(pts
				(arc
					(start 344.870024 -239.0394)
					(mid 344.217244 -239.0394)
					(end 344.870024 -239.0394)
				)
			)
		)
	)
	(zone
		(layers "B.Cu" "In11.Cu" "In13.Cu" "In15.Cu")
		(hatch none 0.5)
		(connect_pads
			(clearance 0)
		)
		(min_thickness 0.25)
		(keepout
			(tracks not_allowed)
			(vias allowed)
			(pads allowed)
			(copperpour not_allowed)
			(footprints allowed)
		)
		(placement
			(enabled no)
			(sheetname "")
		)
		(fill yes
			(thermal_gap 0.5)
			(thermal_bridge_width 0.5)
			(island_removal_mode 0)
		)
		(polygon
			(pts
				(arc
					(start 451.237604 -310.366664)
					(mid 450.584824 -310.366664)
					(end 451.237604 -310.366664)
				)
			)
		)
	)
	(zone
		(layers "B.Cu" "In11.Cu" "In13.Cu" "In15.Cu")
		(hatch none 0.5)
		(connect_pads
			(clearance 0)
		)
		(min_thickness 0.25)
		(keepout
			(tracks not_allowed)
			(vias allowed)
			(pads allowed)
			(copperpour not_allowed)
			(footprints allowed)
		)
		(placement
			(enabled no)
			(sheetname "")
		)
		(fill yes
			(thermal_gap 0.5)
			(thermal_bridge_width 0.5)
			(island_removal_mode 0)
		)
		(polygon
			(pts
				(arc
					(start 336.88147 -215.436704)
					(mid 336.22869 -215.436704)
					(end 336.88147 -215.436704)
				)
			)
		)
	)
	(zone
		(layers "B.Cu" "In11.Cu" "In13.Cu" "In15.Cu")
		(hatch none 0.5)
		(connect_pads
			(clearance 0)
		)
		(min_thickness 0.25)
		(keepout
			(tracks not_allowed)
			(vias allowed)
			(pads allowed)
			(copperpour not_allowed)
			(footprints allowed)
		)
		(placement
			(enabled no)
			(sheetname "")
		)
		(fill yes
			(thermal_gap 0.5)
			(thermal_bridge_width 0.5)
			(island_removal_mode 0)
		)
		(polygon
			(pts
				(arc
					(start 36.303204 -195.616576)
					(mid 35.650424 -195.616576)
					(end 36.303204 -195.616576)
				)
			)
		)
	)
	(zone
		(layers "B.Cu" "In11.Cu" "In13.Cu" "In15.Cu")
		(hatch none 0.5)
		(connect_pads
			(clearance 0)
		)
		(min_thickness 0.25)
		(keepout
			(tracks not_allowed)
			(vias allowed)
			(pads allowed)
			(copperpour not_allowed)
			(footprints allowed)
		)
		(placement
			(enabled no)
			(sheetname "")
		)
		(fill yes
			(thermal_gap 0.5)
			(thermal_bridge_width 0.5)
			(island_removal_mode 0)
		)
		(polygon
			(pts
				(arc
					(start 115.256056 -213.732618)
					(mid 114.603276 -213.732618)
					(end 115.256056 -213.732618)
				)
			)
		)
	)
	(zone
		(layers "B.Cu" "In11.Cu" "In13.Cu" "In15.Cu")
		(hatch none 0.5)
		(connect_pads
			(clearance 0)
		)
		(min_thickness 0.25)
		(keepout
			(tracks not_allowed)
			(vias allowed)
			(pads allowed)
			(copperpour not_allowed)
			(footprints allowed)
		)
		(placement
			(enabled no)
			(sheetname "")
		)
		(fill yes
			(thermal_gap 0.5)
			(thermal_bridge_width 0.5)
			(island_removal_mode 0)
		)
		(polygon
			(pts
				(arc
					(start 346.054934 -435.489858)
					(mid 345.245182 -435.489858)
					(end 346.054934 -435.489858)
				)
			)
		)
	)
	(zone
		(layers "B.Cu" "In11.Cu" "In13.Cu" "In15.Cu")
		(hatch none 0.5)
		(connect_pads
			(clearance 0)
		)
		(min_thickness 0.25)
		(keepout
			(tracks not_allowed)
			(vias allowed)
			(pads allowed)
			(copperpour not_allowed)
			(footprints allowed)
		)
		(placement
			(enabled no)
			(sheetname "")
		)
		(fill yes
			(thermal_gap 0.5)
			(thermal_bridge_width 0.5)
			(island_removal_mode 0)
		)
		(polygon
			(pts
				(arc
					(start 17.115536 -316.316614)
					(mid 16.462756 -316.316614)
					(end 17.115536 -316.316614)
				)
			)
		)
	)
	(zone
		(layers "B.Cu" "In11.Cu" "In13.Cu" "In15.Cu")
		(hatch none 0.5)
		(connect_pads
			(clearance 0)
		)
		(min_thickness 0.25)
		(keepout
			(tracks not_allowed)
			(vias allowed)
			(pads allowed)
			(copperpour not_allowed)
			(footprints allowed)
		)
		(placement
			(enabled no)
			(sheetname "")
		)
		(fill yes
			(thermal_gap 0.5)
			(thermal_bridge_width 0.5)
			(island_removal_mode 0)
		)
		(polygon
			(pts
				(arc
					(start 188.209936 -271.266666)
					(mid 187.557156 -271.266666)
					(end 188.209936 -271.266666)
				)
			)
		)
	)
	(zone
		(layers "B.Cu" "In11.Cu" "In13.Cu" "In15.Cu")
		(hatch none 0.5)
		(connect_pads
			(clearance 0)
		)
		(min_thickness 0.25)
		(keepout
			(tracks not_allowed)
			(vias allowed)
			(pads allowed)
			(copperpour not_allowed)
			(footprints allowed)
		)
		(placement
			(enabled no)
			(sheetname "")
		)
		(fill yes
			(thermal_gap 0.5)
			(thermal_bridge_width 0.5)
			(island_removal_mode 0)
		)
		(polygon
			(pts
				(arc
					(start 342.52027 -226.831144)
					(mid 341.86749 -226.831144)
					(end 342.52027 -226.831144)
				)
			)
		)
	)
	(zone
		(layers "B.Cu" "In11.Cu" "In13.Cu" "In15.Cu")
		(hatch none 0.5)
		(connect_pads
			(clearance 0)
		)
		(min_thickness 0.25)
		(keepout
			(tracks not_allowed)
			(vias allowed)
			(pads allowed)
			(copperpour not_allowed)
			(footprints allowed)
		)
		(placement
			(enabled no)
			(sheetname "")
		)
		(fill yes
			(thermal_gap 0.5)
			(thermal_bridge_width 0.5)
			(island_removal_mode 0)
		)
		(polygon
			(pts
				(arc
					(start 188.209936 -301.01667)
					(mid 187.557156 -301.01667)
					(end 188.209936 -301.01667)
				)
			)
		)
	)
	(zone
		(layers "B.Cu" "In11.Cu" "In13.Cu" "In15.Cu")
		(hatch none 0.5)
		(connect_pads
			(clearance 0)
		)
		(min_thickness 0.25)
		(keepout
			(tracks not_allowed)
			(vias allowed)
			(pads allowed)
			(copperpour not_allowed)
			(footprints allowed)
		)
		(placement
			(enabled no)
			(sheetname "")
		)
		(fill yes
			(thermal_gap 0.5)
			(thermal_bridge_width 0.5)
			(island_removal_mode 0)
		)
		(polygon
			(pts
				(arc
					(start 36.303204 -220.266768)
					(mid 35.650424 -220.266768)
					(end 36.303204 -220.266768)
				)
			)
		)
	)
	(zone
		(layers "B.Cu" "In11.Cu" "In13.Cu" "In15.Cu")
		(hatch none 0.5)
		(connect_pads
			(clearance 0)
		)
		(min_thickness 0.25)
		(keepout
			(tracks not_allowed)
			(vias allowed)
			(pads allowed)
			(copperpour not_allowed)
			(footprints allowed)
		)
		(placement
			(enabled no)
			(sheetname "")
		)
		(fill yes
			(thermal_gap 0.5)
			(thermal_bridge_width 0.5)
			(island_removal_mode 0)
		)
		(polygon
			(pts
				(arc
					(start 269.155672 -312.066686)
					(mid 268.502892 -312.066686)
					(end 269.155672 -312.066686)
				)
			)
		)
	)
	(zone
		(layers "B.Cu" "In11.Cu" "In13.Cu" "In15.Cu")
		(hatch none 0.5)
		(connect_pads
			(clearance 0)
		)
		(min_thickness 0.25)
		(keepout
			(tracks not_allowed)
			(vias allowed)
			(pads allowed)
			(copperpour not_allowed)
			(footprints allowed)
		)
		(placement
			(enabled no)
			(sheetname "")
		)
		(fill yes
			(thermal_gap 0.5)
			(thermal_bridge_width 0.5)
			(island_removal_mode 0)
		)
		(polygon
			(pts
				(arc
					(start 184.004204 2.4892)
					(mid 183.300624 2.4892)
					(end 184.004204 2.4892)
				)
			)
		)
	)
	(zone
		(layers "B.Cu" "In11.Cu" "In13.Cu" "In15.Cu")
		(hatch none 0.5)
		(connect_pads
			(clearance 0)
		)
		(min_thickness 0.25)
		(keepout
			(tracks not_allowed)
			(vias allowed)
			(pads allowed)
			(copperpour not_allowed)
			(footprints allowed)
		)
		(placement
			(enabled no)
			(sheetname "")
		)
		(fill yes
			(thermal_gap 0.5)
			(thermal_bridge_width 0.5)
			(island_removal_mode 0)
		)
		(polygon
			(pts
				(arc
					(start 81.173828 -410.030168)
					(mid 80.470248 -410.030168)
					(end 81.173828 -410.030168)
				)
			)
		)
	)
	(zone
		(layers "B.Cu" "In11.Cu" "In13.Cu" "In15.Cu")
		(hatch none 0.5)
		(connect_pads
			(clearance 0)
		)
		(min_thickness 0.25)
		(keepout
			(tracks not_allowed)
			(vias allowed)
			(pads allowed)
			(copperpour not_allowed)
			(footprints allowed)
		)
		(placement
			(enabled no)
			(sheetname "")
		)
		(fill yes
			(thermal_gap 0.5)
			(thermal_bridge_width 0.5)
			(island_removal_mode 0)
		)
		(polygon
			(pts
				(arc
					(start 101.158802 -215.436704)
					(mid 100.506022 -215.436704)
					(end 101.158802 -215.436704)
				)
			)
		)
	)
	(zone
		(layers "B.Cu" "In11.Cu" "In13.Cu" "In15.Cu")
		(hatch none 0.5)
		(connect_pads
			(clearance 0)
		)
		(min_thickness 0.25)
		(keepout
			(tracks not_allowed)
			(vias allowed)
			(pads allowed)
			(copperpour not_allowed)
			(footprints allowed)
		)
		(placement
			(enabled no)
			(sheetname "")
		)
		(fill yes
			(thermal_gap 0.5)
			(thermal_bridge_width 0.5)
			(island_removal_mode 0)
		)
		(polygon
			(pts
				(arc
					(start 128.883156 -229.272846)
					(mid 128.230376 -229.272846)
					(end 128.883156 -229.272846)
				)
			)
		)
	)
	(zone
		(layers "B.Cu" "In11.Cu" "In13.Cu" "In15.Cu")
		(hatch none 0.5)
		(connect_pads
			(clearance 0)
		)
		(min_thickness 0.25)
		(keepout
			(tracks not_allowed)
			(vias allowed)
			(pads allowed)
			(copperpour not_allowed)
			(footprints allowed)
		)
		(placement
			(enabled no)
			(sheetname "")
		)
		(fill yes
			(thermal_gap 0.5)
			(thermal_bridge_width 0.5)
			(island_removal_mode 0)
		)
		(polygon
			(pts
				(arc
					(start 376.933206 -271.825212)
					(mid 376.280426 -271.825212)
					(end 376.933206 -271.825212)
				)
			)
		)
	)
	(zone
		(layers "B.Cu" "In11.Cu" "In13.Cu" "In15.Cu")
		(hatch none 0.5)
		(connect_pads
			(clearance 0)
		)
		(min_thickness 0.25)
		(keepout
			(tracks not_allowed)
			(vias allowed)
			(pads allowed)
			(copperpour not_allowed)
			(footprints allowed)
		)
		(placement
			(enabled no)
			(sheetname "")
		)
		(fill yes
			(thermal_gap 0.5)
			(thermal_bridge_width 0.5)
			(island_removal_mode 0)
		)
		(polygon
			(pts
				(arc
					(start 173.122336 -244.066568)
					(mid 172.469556 -244.066568)
					(end 173.122336 -244.066568)
				)
			)
		)
	)
	(zone
		(layers "B.Cu" "In11.Cu" "In13.Cu" "In15.Cu")
		(hatch none 0.5)
		(connect_pads
			(clearance 0)
		)
		(min_thickness 0.25)
		(keepout
			(tracks not_allowed)
			(vias allowed)
			(pads allowed)
			(copperpour not_allowed)
			(footprints allowed)
		)
		(placement
			(enabled no)
			(sheetname "")
		)
		(fill yes
			(thermal_gap 0.5)
			(thermal_bridge_width 0.5)
			(island_removal_mode 0)
		)
		(polygon
			(pts
				(arc
					(start 140.232384 -410.030168)
					(mid 139.528804 -410.030168)
					(end 140.232384 -410.030168)
				)
			)
		)
	)
	(zone
		(layers "B.Cu" "In11.Cu" "In13.Cu" "In15.Cu")
		(hatch none 0.5)
		(connect_pads
			(clearance 0)
		)
		(min_thickness 0.25)
		(keepout
			(tracks not_allowed)
			(vias allowed)
			(pads allowed)
			(copperpour not_allowed)
			(footprints allowed)
		)
		(placement
			(enabled no)
			(sheetname "")
		)
		(fill yes
			(thermal_gap 0.5)
			(thermal_bridge_width 0.5)
			(island_removal_mode 0)
		)
		(polygon
			(pts
				(arc
					(start 401.1549 -439.0898)
					(mid 400.345148 -439.0898)
					(end 401.1549 -439.0898)
				)
			)
		)
	)
	(zone
		(layers "B.Cu" "In11.Cu" "In13.Cu" "In15.Cu")
		(hatch none 0.5)
		(connect_pads
			(clearance 0)
		)
		(min_thickness 0.25)
		(keepout
			(tracks not_allowed)
			(vias allowed)
			(pads allowed)
			(copperpour not_allowed)
			(footprints allowed)
		)
		(placement
			(enabled no)
			(sheetname "")
		)
		(fill yes
			(thermal_gap 0.5)
			(thermal_bridge_width 0.5)
			(island_removal_mode 0)
		)
		(polygon
			(pts
				(arc
					(start 436.150004 -301.01667)
					(mid 435.497224 -301.01667)
					(end 436.150004 -301.01667)
				)
			)
		)
	)
	(zone
		(layers "B.Cu" "In11.Cu" "In13.Cu" "In15.Cu")
		(hatch none 0.5)
		(connect_pads
			(clearance 0)
		)
		(min_thickness 0.25)
		(keepout
			(tracks not_allowed)
			(vias allowed)
			(pads allowed)
			(copperpour not_allowed)
			(footprints allowed)
		)
		(placement
			(enabled no)
			(sheetname "")
		)
		(fill yes
			(thermal_gap 0.5)
			(thermal_bridge_width 0.5)
			(island_removal_mode 0)
		)
		(polygon
			(pts
				(arc
					(start 98.339402 -226.831144)
					(mid 97.686622 -226.831144)
					(end 98.339402 -226.831144)
				)
			)
		)
	)
	(zone
		(layers "B.Cu" "In11.Cu" "In13.Cu" "In15.Cu")
		(hatch none 0.5)
		(connect_pads
			(clearance 0)
		)
		(min_thickness 0.25)
		(keepout
			(tracks not_allowed)
			(vias allowed)
			(pads allowed)
			(copperpour not_allowed)
			(footprints allowed)
		)
		(placement
			(enabled no)
			(sheetname "")
		)
		(fill yes
			(thermal_gap 0.5)
			(thermal_bridge_width 0.5)
			(island_removal_mode 0)
		)
		(polygon
			(pts
				(arc
					(start 401.55368 -410.030168)
					(mid 400.8501 -410.030168)
					(end 401.55368 -410.030168)
				)
			)
		)
	)
	(zone
		(layers "B.Cu" "In11.Cu" "In13.Cu" "In15.Cu")
		(hatch none 0.5)
		(connect_pads
			(clearance 0)
		)
		(min_thickness 0.25)
		(keepout
			(tracks not_allowed)
			(vias allowed)
			(pads allowed)
			(copperpour not_allowed)
			(footprints allowed)
		)
		(placement
			(enabled no)
			(sheetname "")
		)
		(fill yes
			(thermal_gap 0.5)
			(thermal_bridge_width 0.5)
			(island_removal_mode 0)
		)
		(polygon
			(pts
				(arc
					(start 363.196124 -226.831144)
					(mid 362.543344 -226.831144)
					(end 363.196124 -226.831144)
				)
			)
		)
	)
	(zone
		(layers "B.Cu" "In11.Cu" "In13.Cu" "In15.Cu")
		(hatch none 0.5)
		(connect_pads
			(clearance 0)
		)
		(min_thickness 0.25)
		(keepout
			(tracks not_allowed)
			(vias allowed)
			(pads allowed)
			(copperpour not_allowed)
			(footprints allowed)
		)
		(placement
			(enabled no)
			(sheetname "")
		)
		(fill yes
			(thermal_gap 0.5)
			(thermal_bridge_width 0.5)
			(island_removal_mode 0)
		)
		(polygon
			(pts
				(arc
					(start 394.154914 -429.689768)
					(mid 393.345162 -429.689768)
					(end 394.154914 -429.689768)
				)
			)
		)
	)
	(zone
		(layers "B.Cu" "In11.Cu" "In13.Cu" "In15.Cu")
		(hatch none 0.5)
		(connect_pads
			(clearance 0)
		)
		(min_thickness 0.25)
		(keepout
			(tracks not_allowed)
			(vias allowed)
			(pads allowed)
			(copperpour not_allowed)
			(footprints allowed)
		)
		(placement
			(enabled no)
			(sheetname "")
		)
		(fill yes
			(thermal_gap 0.5)
			(thermal_bridge_width 0.5)
			(island_removal_mode 0)
		)
		(polygon
			(pts
				(arc
					(start 32.203136 -221.116652)
					(mid 31.550356 -221.116652)
					(end 32.203136 -221.116652)
				)
			)
		)
	)
	(zone
		(layers "B.Cu" "In11.Cu" "In13.Cu" "In15.Cu")
		(hatch none 0.5)
		(connect_pads
			(clearance 0)
		)
		(min_thickness 0.25)
		(keepout
			(tracks not_allowed)
			(vias allowed)
			(pads allowed)
			(copperpour not_allowed)
			(footprints allowed)
		)
		(placement
			(enabled no)
			(sheetname "")
		)
		(fill yes
			(thermal_gap 0.5)
			(thermal_bridge_width 0.5)
			(island_removal_mode 0)
		)
		(polygon
			(pts
				(arc
					(start 97.039938 -263.686544)
					(mid 96.387158 -263.686544)
					(end 97.039938 -263.686544)
				)
			)
		)
	)
	(zone
		(layers "B.Cu" "In11.Cu" "In13.Cu" "In15.Cu")
		(hatch none 0.5)
		(connect_pads
			(clearance 0)
		)
		(min_thickness 0.25)
		(keepout
			(tracks not_allowed)
			(vias allowed)
			(pads allowed)
			(copperpour not_allowed)
			(footprints allowed)
		)
		(placement
			(enabled no)
			(sheetname "")
		)
		(fill yes
			(thermal_gap 0.5)
			(thermal_bridge_width 0.5)
			(island_removal_mode 0)
		)
		(polygon
			(pts
				(arc
					(start 436.150004 -302.716692)
					(mid 435.497224 -302.716692)
					(end 436.150004 -302.716692)
				)
			)
		)
	)
	(zone
		(layers "B.Cu" "In11.Cu" "In13.Cu" "In15.Cu")
		(hatch none 0.5)
		(connect_pads
			(clearance 0)
		)
		(min_thickness 0.25)
		(keepout
			(tracks not_allowed)
			(vias allowed)
			(pads allowed)
			(copperpour not_allowed)
			(footprints allowed)
		)
		(placement
			(enabled no)
			(sheetname "")
		)
		(fill yes
			(thermal_gap 0.5)
			(thermal_bridge_width 0.5)
			(island_removal_mode 0)
		)
		(polygon
			(pts
				(arc
					(start 375.41327 -231.714548)
					(mid 374.76049 -231.714548)
					(end 375.41327 -231.714548)
				)
			)
		)
	)
	(zone
		(layers "B.Cu" "In11.Cu" "In13.Cu" "In15.Cu")
		(hatch none 0.5)
		(connect_pads
			(clearance 0)
		)
		(min_thickness 0.25)
		(keepout
			(tracks not_allowed)
			(vias allowed)
			(pads allowed)
			(copperpour not_allowed)
			(footprints allowed)
		)
		(placement
			(enabled no)
			(sheetname "")
		)
		(fill yes
			(thermal_gap 0.5)
			(thermal_bridge_width 0.5)
			(island_removal_mode 0)
		)
		(polygon
			(pts
				(arc
					(start 133.112002 -215.436704)
					(mid 132.459222 -215.436704)
					(end 133.112002 -215.436704)
				)
			)
		)
	)
	(zone
		(layers "B.Cu" "In11.Cu" "In13.Cu" "In15.Cu")
		(hatch none 0.5)
		(connect_pads
			(clearance 0)
		)
		(min_thickness 0.25)
		(keepout
			(tracks not_allowed)
			(vias allowed)
			(pads allowed)
			(copperpour not_allowed)
			(footprints allowed)
		)
		(placement
			(enabled no)
			(sheetname "")
		)
		(fill yes
			(thermal_gap 0.5)
			(thermal_bridge_width 0.5)
			(island_removal_mode 0)
		)
		(polygon
			(pts
				(arc
					(start 376.823224 -240.667286)
					(mid 376.170444 -240.667286)
					(end 376.823224 -240.667286)
				)
			)
		)
	)
	(zone
		(layers "B.Cu" "In11.Cu" "In13.Cu" "In15.Cu")
		(hatch none 0.5)
		(connect_pads
			(clearance 0)
		)
		(min_thickness 0.25)
		(keepout
			(tracks not_allowed)
			(vias allowed)
			(pads allowed)
			(copperpour not_allowed)
			(footprints allowed)
		)
		(placement
			(enabled no)
			(sheetname "")
		)
		(fill yes
			(thermal_gap 0.5)
			(thermal_bridge_width 0.5)
			(island_removal_mode 0)
		)
		(polygon
			(pts
				(arc
					(start 138.154918 -430.889918)
					(mid 137.345166 -430.889918)
					(end 138.154918 -430.889918)
				)
			)
		)
	)
	(zone
		(layers "B.Cu" "In11.Cu" "In13.Cu" "In15.Cu")
		(hatch none 0.5)
		(connect_pads
			(clearance 0)
		)
		(min_thickness 0.25)
		(keepout
			(tracks not_allowed)
			(vias allowed)
			(pads allowed)
			(copperpour not_allowed)
			(footprints allowed)
		)
		(placement
			(enabled no)
			(sheetname "")
		)
		(fill yes
			(thermal_gap 0.5)
			(thermal_bridge_width 0.5)
			(island_removal_mode 0)
		)
		(polygon
			(pts
				(arc
					(start 340.170516 -214.622634)
					(mid 339.517736 -214.622634)
					(end 340.170516 -214.622634)
				)
			)
		)
	)
	(zone
		(layers "B.Cu" "In11.Cu" "In13.Cu" "In15.Cu")
		(hatch none 0.5)
		(connect_pads
			(clearance 0)
		)
		(min_thickness 0.25)
		(keepout
			(tracks not_allowed)
			(vias allowed)
			(pads allowed)
			(copperpour not_allowed)
			(footprints allowed)
		)
		(placement
			(enabled no)
			(sheetname "")
		)
		(fill yes
			(thermal_gap 0.5)
			(thermal_bridge_width 0.5)
			(island_removal_mode 0)
		)
		(polygon
			(pts
				(arc
					(start 107.377738 -276.708616)
					(mid 106.724958 -276.708616)
					(end 107.377738 -276.708616)
				)
			)
		)
	)
	(zone
		(layers "B.Cu" "In11.Cu" "In13.Cu" "In15.Cu")
		(hatch none 0.5)
		(connect_pads
			(clearance 0)
		)
		(min_thickness 0.25)
		(keepout
			(tracks not_allowed)
			(vias allowed)
			(pads allowed)
			(copperpour not_allowed)
			(footprints allowed)
		)
		(placement
			(enabled no)
			(sheetname "")
		)
		(fill yes
			(thermal_gap 0.5)
			(thermal_bridge_width 0.5)
			(island_removal_mode 0)
		)
		(polygon
			(pts
				(arc
					(start 63.054992 -433.289964)
					(mid 62.24524 -433.289964)
					(end 63.054992 -433.289964)
				)
			)
		)
	)
	(zone
		(layers "B.Cu" "In11.Cu" "In13.Cu" "In15.Cu")
		(hatch none 0.5)
		(connect_pads
			(clearance 0)
		)
		(min_thickness 0.25)
		(keepout
			(tracks not_allowed)
			(vias allowed)
			(pads allowed)
			(copperpour not_allowed)
			(footprints allowed)
		)
		(placement
			(enabled no)
			(sheetname "")
		)
		(fill yes
			(thermal_gap 0.5)
			(thermal_bridge_width 0.5)
			(island_removal_mode 0)
		)
		(polygon
			(pts
				(arc
					(start 374.370346 -185.544968)
					(mid 373.666766 -185.544968)
					(end 374.370346 -185.544968)
				)
			)
		)
	)
	(zone
		(layers "B.Cu" "In11.Cu" "In13.Cu" "In15.Cu")
		(hatch none 0.5)
		(connect_pads
			(clearance 0)
		)
		(min_thickness 0.25)
		(keepout
			(tracks not_allowed)
			(vias allowed)
			(pads allowed)
			(copperpour not_allowed)
			(footprints allowed)
		)
		(placement
			(enabled no)
			(sheetname "")
		)
		(fill yes
			(thermal_gap 0.5)
			(thermal_bridge_width 0.5)
			(island_removal_mode 0)
		)
		(polygon
			(pts
				(arc
					(start 346.27947 -226.831144)
					(mid 345.62669 -226.831144)
					(end 346.27947 -226.831144)
				)
			)
		)
	)
	(zone
		(layers "B.Cu" "In11.Cu" "In13.Cu" "In15.Cu")
		(hatch none 0.5)
		(connect_pads
			(clearance 0)
		)
		(min_thickness 0.25)
		(keepout
			(tracks not_allowed)
			(vias allowed)
			(pads allowed)
			(copperpour not_allowed)
			(footprints allowed)
		)
		(placement
			(enabled no)
			(sheetname "")
		)
		(fill yes
			(thermal_gap 0.5)
			(thermal_bridge_width 0.5)
			(island_removal_mode 0)
		)
		(polygon
			(pts
				(arc
					(start 95.990156 -245.55069)
					(mid 95.337376 -245.55069)
					(end 95.990156 -245.55069)
				)
			)
		)
	)
	(zone
		(layers "B.Cu" "In11.Cu" "In13.Cu" "In15.Cu")
		(hatch none 0.5)
		(connect_pads
			(clearance 0)
		)
		(min_thickness 0.25)
		(keepout
			(tracks not_allowed)
			(vias allowed)
			(pads allowed)
			(copperpour not_allowed)
			(footprints allowed)
		)
		(placement
			(enabled no)
			(sheetname "")
		)
		(fill yes
			(thermal_gap 0.5)
			(thermal_bridge_width 0.5)
			(island_removal_mode 0)
		)
		(polygon
			(pts
				(arc
					(start 207.397604 -206.666592)
					(mid 206.744824 -206.666592)
					(end 207.397604 -206.666592)
				)
			)
		)
	)
	(zone
		(layers "B.Cu" "In11.Cu" "In13.Cu" "In15.Cu")
		(hatch none 0.5)
		(connect_pads
			(clearance 0)
		)
		(min_thickness 0.25)
		(keepout
			(tracks not_allowed)
			(vias allowed)
			(pads allowed)
			(copperpour not_allowed)
			(footprints allowed)
		)
		(placement
			(enabled no)
			(sheetname "")
		)
		(fill yes
			(thermal_gap 0.5)
			(thermal_bridge_width 0.5)
			(island_removal_mode 0)
		)
		(polygon
			(pts
				(arc
					(start 96.100138 -281.59202)
					(mid 95.447358 -281.59202)
					(end 96.100138 -281.59202)
				)
			)
		)
	)
	(zone
		(layers "B.Cu" "In11.Cu" "In13.Cu" "In15.Cu")
		(hatch none 0.5)
		(connect_pads
			(clearance 0)
		)
		(min_thickness 0.25)
		(keepout
			(tracks not_allowed)
			(vias allowed)
			(pads allowed)
			(copperpour not_allowed)
			(footprints allowed)
		)
		(placement
			(enabled no)
			(sheetname "")
		)
		(fill yes
			(thermal_gap 0.5)
			(thermal_bridge_width 0.5)
			(island_removal_mode 0)
		)
		(polygon
			(pts
				(arc
					(start 98.449384 -282.405836)
					(mid 97.796604 -282.405836)
					(end 98.449384 -282.405836)
				)
			)
		)
	)
	(zone
		(layers "B.Cu" "In11.Cu" "In13.Cu" "In15.Cu")
		(hatch none 0.5)
		(connect_pads
			(clearance 0)
		)
		(min_thickness 0.25)
		(keepout
			(tracks not_allowed)
			(vias allowed)
			(pads allowed)
			(copperpour not_allowed)
			(footprints allowed)
		)
		(placement
			(enabled no)
			(sheetname "")
		)
		(fill yes
			(thermal_gap 0.5)
			(thermal_bridge_width 0.5)
			(island_removal_mode 0)
		)
		(polygon
			(pts
				(arc
					(start 345.33967 -236.597952)
					(mid 344.68689 -236.597952)
					(end 345.33967 -236.597952)
				)
			)
		)
	)
	(zone
		(layers "B.Cu" "In11.Cu" "In13.Cu" "In15.Cu")
		(hatch none 0.5)
		(connect_pads
			(clearance 0)
		)
		(min_thickness 0.25)
		(keepout
			(tracks not_allowed)
			(vias allowed)
			(pads allowed)
			(copperpour not_allowed)
			(footprints allowed)
		)
		(placement
			(enabled no)
			(sheetname "")
		)
		(fill yes
			(thermal_gap 0.5)
			(thermal_bridge_width 0.5)
			(island_removal_mode 0)
		)
		(polygon
			(pts
				(arc
					(start 203.297536 -245.76659)
					(mid 202.644756 -245.76659)
					(end 203.297536 -245.76659)
				)
			)
		)
	)
	(zone
		(layers "B.Cu" "In11.Cu" "In13.Cu" "In15.Cu")
		(hatch none 0.5)
		(connect_pads
			(clearance 0)
		)
		(min_thickness 0.25)
		(keepout
			(tracks not_allowed)
			(vias allowed)
			(pads allowed)
			(copperpour not_allowed)
			(footprints allowed)
		)
		(placement
			(enabled no)
			(sheetname "")
		)
		(fill yes
			(thermal_gap 0.5)
			(thermal_bridge_width 0.5)
			(island_removal_mode 0)
		)
		(polygon
			(pts
				(arc
					(start 358.49687 -215.436704)
					(mid 357.84409 -215.436704)
					(end 358.49687 -215.436704)
				)
			)
		)
	)
	(zone
		(layers "B.Cu" "In11.Cu" "In13.Cu" "In15.Cu")
		(hatch none 0.5)
		(connect_pads
			(clearance 0)
		)
		(min_thickness 0.25)
		(keepout
			(tracks not_allowed)
			(vias allowed)
			(pads allowed)
			(copperpour not_allowed)
			(footprints allowed)
		)
		(placement
			(enabled no)
			(sheetname "")
		)
		(fill yes
			(thermal_gap 0.5)
			(thermal_bridge_width 0.5)
			(island_removal_mode 0)
		)
		(polygon
			(pts
				(arc
					(start 344.040206 -257.175254)
					(mid 343.387426 -257.175254)
					(end 344.040206 -257.175254)
				)
			)
		)
	)
	(zone
		(layers "B.Cu" "In11.Cu" "In13.Cu" "In15.Cu")
		(hatch none 0.5)
		(connect_pads
			(clearance 0)
		)
		(min_thickness 0.25)
		(keepout
			(tracks not_allowed)
			(vias allowed)
			(pads allowed)
			(copperpour not_allowed)
			(footprints allowed)
		)
		(placement
			(enabled no)
			(sheetname "")
		)
		(fill yes
			(thermal_gap 0.5)
			(thermal_bridge_width 0.5)
			(island_removal_mode 0)
		)
		(polygon
			(pts
				(arc
					(start 376.463052 -271.011396)
					(mid 375.810272 -271.011396)
					(end 376.463052 -271.011396)
				)
			)
		)
	)
	(zone
		(layers "B.Cu" "In11.Cu" "In13.Cu" "In15.Cu")
		(hatch none 0.5)
		(connect_pads
			(clearance 0)
		)
		(min_thickness 0.25)
		(keepout
			(tracks not_allowed)
			(vias allowed)
			(pads allowed)
			(copperpour not_allowed)
			(footprints allowed)
		)
		(placement
			(enabled no)
			(sheetname "")
		)
		(fill yes
			(thermal_gap 0.5)
			(thermal_bridge_width 0.5)
			(island_removal_mode 0)
		)
		(polygon
			(pts
				(arc
					(start 310.318404 -243.216684)
					(mid 309.665624 -243.216684)
					(end 310.318404 -243.216684)
				)
			)
		)
	)
	(zone
		(layers "B.Cu" "In11.Cu" "In13.Cu" "In15.Cu")
		(hatch none 0.5)
		(connect_pads
			(clearance 0)
		)
		(min_thickness 0.25)
		(keepout
			(tracks not_allowed)
			(vias allowed)
			(pads allowed)
			(copperpour not_allowed)
			(footprints allowed)
		)
		(placement
			(enabled no)
			(sheetname "")
		)
		(fill yes
			(thermal_gap 0.5)
			(thermal_bridge_width 0.5)
			(island_removal_mode 0)
		)
		(polygon
			(pts
				(arc
					(start 95.629984 -275.8948)
					(mid 94.977204 -275.8948)
					(end 95.629984 -275.8948)
				)
			)
		)
	)
	(zone
		(layers "B.Cu" "In11.Cu" "In13.Cu" "In15.Cu")
		(hatch none 0.5)
		(connect_pads
			(clearance 0)
		)
		(min_thickness 0.25)
		(keepout
			(tracks not_allowed)
			(vias allowed)
			(pads allowed)
			(copperpour not_allowed)
			(footprints allowed)
		)
		(placement
			(enabled no)
			(sheetname "")
		)
		(fill yes
			(thermal_gap 0.5)
			(thermal_bridge_width 0.5)
			(island_removal_mode 0)
		)
		(polygon
			(pts
				(arc
					(start 269.155672 -210.916774)
					(mid 268.502892 -210.916774)
					(end 269.155672 -210.916774)
				)
			)
		)
	)
	(zone
		(layers "B.Cu" "In11.Cu" "In13.Cu" "In15.Cu")
		(hatch none 0.5)
		(connect_pads
			(clearance 0)
		)
		(min_thickness 0.25)
		(keepout
			(tracks not_allowed)
			(vias allowed)
			(pads allowed)
			(copperpour not_allowed)
			(footprints allowed)
		)
		(placement
			(enabled no)
			(sheetname "")
		)
		(fill yes
			(thermal_gap 0.5)
			(thermal_bridge_width 0.5)
			(island_removal_mode 0)
		)
		(polygon
			(pts
				(arc
					(start 344.980006 -275.08073)
					(mid 344.327226 -275.08073)
					(end 344.980006 -275.08073)
				)
			)
		)
	)
	(zone
		(layers "B.Cu" "In11.Cu" "In13.Cu" "In15.Cu")
		(hatch none 0.5)
		(connect_pads
			(clearance 0)
		)
		(min_thickness 0.25)
		(keepout
			(tracks not_allowed)
			(vias allowed)
			(pads allowed)
			(copperpour not_allowed)
			(footprints allowed)
		)
		(placement
			(enabled no)
			(sheetname "")
		)
		(fill yes
			(thermal_gap 0.5)
			(thermal_bridge_width 0.5)
			(island_removal_mode 0)
		)
		(polygon
			(pts
				(arc
					(start 97.509584 -269.38351)
					(mid 96.856804 -269.38351)
					(end 97.509584 -269.38351)
				)
			)
		)
	)
	(zone
		(layers "B.Cu" "In11.Cu" "In13.Cu" "In15.Cu")
		(hatch none 0.5)
		(connect_pads
			(clearance 0)
		)
		(min_thickness 0.25)
		(keepout
			(tracks not_allowed)
			(vias allowed)
			(pads allowed)
			(copperpour not_allowed)
			(footprints allowed)
		)
		(placement
			(enabled no)
			(sheetname "")
		)
		(fill yes
			(thermal_gap 0.5)
			(thermal_bridge_width 0.5)
			(island_removal_mode 0)
		)
		(polygon
			(pts
				(arc
					(start 341.901526 -71.185786)
					(mid 341.197946 -71.185786)
					(end 341.901526 -71.185786)
				)
			)
		)
	)
	(zone
		(layers "B.Cu" "In11.Cu" "In13.Cu" "In15.Cu")
		(hatch none 0.5)
		(connect_pads
			(clearance 0)
		)
		(min_thickness 0.25)
		(keepout
			(tracks not_allowed)
			(vias allowed)
			(pads allowed)
			(copperpour not_allowed)
			(footprints allowed)
		)
		(placement
			(enabled no)
			(sheetname "")
		)
		(fill yes
			(thermal_gap 0.5)
			(thermal_bridge_width 0.5)
			(island_removal_mode 0)
		)
		(polygon
			(pts
				(arc
					(start 375.41327 -230.086662)
					(mid 374.76049 -230.086662)
					(end 375.41327 -230.086662)
				)
			)
		)
	)
	(zone
		(layers "B.Cu" "In11.Cu" "In13.Cu" "In15.Cu")
		(hatch none 0.5)
		(connect_pads
			(clearance 0)
		)
		(min_thickness 0.25)
		(keepout
			(tracks not_allowed)
			(vias allowed)
			(pads allowed)
			(copperpour not_allowed)
			(footprints allowed)
		)
		(placement
			(enabled no)
			(sheetname "")
		)
		(fill yes
			(thermal_gap 0.5)
			(thermal_bridge_width 0.5)
			(island_removal_mode 0)
		)
		(polygon
			(pts
				(arc
					(start 343.100406 -275.08073)
					(mid 342.447626 -275.08073)
					(end 343.100406 -275.08073)
				)
			)
		)
	)
	(zone
		(layers "B.Cu" "In11.Cu" "In13.Cu" "In15.Cu")
		(hatch none 0.5)
		(connect_pads
			(clearance 0)
		)
		(min_thickness 0.25)
		(keepout
			(tracks not_allowed)
			(vias allowed)
			(pads allowed)
			(copperpour not_allowed)
			(footprints allowed)
		)
		(placement
			(enabled no)
			(sheetname "")
		)
		(fill yes
			(thermal_gap 0.5)
			(thermal_bridge_width 0.5)
			(island_removal_mode 0)
		)
		(polygon
			(pts
				(arc
					(start 344.054938 -433.289964)
					(mid 343.245186 -433.289964)
					(end 344.054938 -433.289964)
				)
			)
		)
	)
	(zone
		(layers "B.Cu" "In11.Cu" "In13.Cu" "In15.Cu")
		(hatch none 0.5)
		(connect_pads
			(clearance 0)
		)
		(min_thickness 0.25)
		(keepout
			(tracks not_allowed)
			(vias allowed)
			(pads allowed)
			(copperpour not_allowed)
			(footprints allowed)
		)
		(placement
			(enabled no)
			(sheetname "")
		)
		(fill yes
			(thermal_gap 0.5)
			(thermal_bridge_width 0.5)
			(island_removal_mode 0)
		)
		(polygon
			(pts
				(arc
					(start 125.593602 -247.992138)
					(mid 124.940822 -247.992138)
					(end 125.593602 -247.992138)
				)
			)
		)
	)
	(zone
		(layers "B.Cu" "In11.Cu" "In13.Cu" "In15.Cu")
		(hatch none 0.5)
		(connect_pads
			(clearance 0)
		)
		(min_thickness 0.25)
		(keepout
			(tracks not_allowed)
			(vias allowed)
			(pads allowed)
			(copperpour not_allowed)
			(footprints allowed)
		)
		(placement
			(enabled no)
			(sheetname "")
		)
		(fill yes
			(thermal_gap 0.5)
			(thermal_bridge_width 0.5)
			(island_removal_mode 0)
		)
		(polygon
			(pts
				(arc
					(start 32.203136 -228.766624)
					(mid 31.550356 -228.766624)
					(end 32.203136 -228.766624)
				)
			)
		)
	)
	(zone
		(layers "B.Cu" "In11.Cu" "In13.Cu" "In15.Cu")
		(hatch none 0.5)
		(connect_pads
			(clearance 0)
		)
		(min_thickness 0.25)
		(keepout
			(tracks not_allowed)
			(vias allowed)
			(pads allowed)
			(copperpour not_allowed)
			(footprints allowed)
		)
		(placement
			(enabled no)
			(sheetname "")
		)
		(fill yes
			(thermal_gap 0.5)
			(thermal_bridge_width 0.5)
			(island_removal_mode 0)
		)
		(polygon
			(pts
				(arc
					(start 95.160338 -270.19758)
					(mid 94.507558 -270.19758)
					(end 95.160338 -270.19758)
				)
			)
		)
	)
	(zone
		(layers "B.Cu" "In11.Cu" "In13.Cu" "In15.Cu")
		(hatch none 0.5)
		(connect_pads
			(clearance 0)
		)
		(min_thickness 0.25)
		(keepout
			(tracks not_allowed)
			(vias allowed)
			(pads allowed)
			(copperpour not_allowed)
			(footprints allowed)
		)
		(placement
			(enabled no)
			(sheetname "")
		)
		(fill yes
			(thermal_gap 0.5)
			(thermal_bridge_width 0.5)
			(island_removal_mode 0)
		)
		(polygon
			(pts
				(arc
					(start 349.517462 -176.709832)
					(mid 348.813882 -176.709832)
					(end 349.517462 -176.709832)
				)
			)
		)
	)
	(zone
		(layers "B.Cu" "In11.Cu" "In13.Cu" "In15.Cu")
		(hatch none 0.5)
		(connect_pads
			(clearance 0)
		)
		(min_thickness 0.25)
		(keepout
			(tracks not_allowed)
			(vias allowed)
			(pads allowed)
			(copperpour not_allowed)
			(footprints allowed)
		)
		(placement
			(enabled no)
			(sheetname "")
		)
		(fill yes
			(thermal_gap 0.5)
			(thermal_bridge_width 0.5)
			(island_removal_mode 0)
		)
		(polygon
			(pts
				(arc
					(start 349.679006 -281.59202)
					(mid 349.026226 -281.59202)
					(end 349.679006 -281.59202)
				)
			)
		)
	)
	(zone
		(layers "B.Cu" "In11.Cu" "In13.Cu" "In15.Cu")
		(hatch none 0.5)
		(connect_pads
			(clearance 0)
		)
		(min_thickness 0.25)
		(keepout
			(tracks not_allowed)
			(vias allowed)
			(pads allowed)
			(copperpour not_allowed)
			(footprints allowed)
		)
		(placement
			(enabled no)
			(sheetname "")
		)
		(fill yes
			(thermal_gap 0.5)
			(thermal_bridge_width 0.5)
			(island_removal_mode 0)
		)
		(polygon
			(pts
				(arc
					(start 345.449652 -269.38351)
					(mid 344.796872 -269.38351)
					(end 345.449652 -269.38351)
				)
			)
		)
	)
	(zone
		(layers "B.Cu" "In11.Cu" "In13.Cu" "In15.Cu")
		(hatch none 0.5)
		(connect_pads
			(clearance 0)
		)
		(min_thickness 0.25)
		(keepout
			(tracks not_allowed)
			(vias allowed)
			(pads allowed)
			(copperpour not_allowed)
			(footprints allowed)
		)
		(placement
			(enabled no)
			(sheetname "")
		)
		(fill yes
			(thermal_gap 0.5)
			(thermal_bridge_width 0.5)
			(island_removal_mode 0)
		)
		(polygon
			(pts
				(arc
					(start 349.569024 -247.178322)
					(mid 348.916244 -247.178322)
					(end 349.569024 -247.178322)
				)
			)
		)
	)
	(zone
		(layers "B.Cu" "In11.Cu" "In13.Cu" "In15.Cu")
		(hatch none 0.5)
		(connect_pads
			(clearance 0)
		)
		(min_thickness 0.25)
		(keepout
			(tracks not_allowed)
			(vias allowed)
			(pads allowed)
			(copperpour not_allowed)
			(footprints allowed)
		)
		(placement
			(enabled no)
			(sheetname "")
		)
		(fill yes
			(thermal_gap 0.5)
			(thermal_bridge_width 0.5)
			(island_removal_mode 0)
		)
		(polygon
			(pts
				(arc
					(start 127.583184 -271.011396)
					(mid 126.930404 -271.011396)
					(end 127.583184 -271.011396)
				)
			)
		)
	)
	(zone
		(layers "B.Cu" "In11.Cu" "In13.Cu" "In15.Cu")
		(hatch none 0.5)
		(connect_pads
			(clearance 0)
		)
		(min_thickness 0.25)
		(keepout
			(tracks not_allowed)
			(vias allowed)
			(pads allowed)
			(copperpour not_allowed)
			(footprints allowed)
		)
		(placement
			(enabled no)
			(sheetname "")
		)
		(fill yes
			(thermal_gap 0.5)
			(thermal_bridge_width 0.5)
			(island_removal_mode 0)
		)
		(polygon
			(pts
				(arc
					(start 128.883156 -234.15625)
					(mid 128.230376 -234.15625)
					(end 128.883156 -234.15625)
				)
			)
		)
	)
	(zone
		(layers "B.Cu" "In11.Cu" "In13.Cu" "In15.Cu")
		(hatch none 0.5)
		(connect_pads
			(clearance 0)
		)
		(min_thickness 0.25)
		(keepout
			(tracks not_allowed)
			(vias allowed)
			(pads allowed)
			(copperpour not_allowed)
			(footprints allowed)
		)
		(placement
			(enabled no)
			(sheetname "")
		)
		(fill yes
			(thermal_gap 0.5)
			(thermal_bridge_width 0.5)
			(island_removal_mode 0)
		)
		(polygon
			(pts
				(arc
					(start 128.154938 -439.0898)
					(mid 127.345186 -439.0898)
					(end 128.154938 -439.0898)
				)
			)
		)
	)
	(zone
		(layers "B.Cu" "In11.Cu" "In13.Cu" "In15.Cu")
		(hatch none 0.5)
		(connect_pads
			(clearance 0)
		)
		(min_thickness 0.25)
		(keepout
			(tracks not_allowed)
			(vias allowed)
			(pads allowed)
			(copperpour not_allowed)
			(footprints allowed)
		)
		(placement
			(enabled no)
			(sheetname "")
		)
		(fill yes
			(thermal_gap 0.5)
			(thermal_bridge_width 0.5)
			(island_removal_mode 0)
		)
		(polygon
			(pts
				(arc
					(start 280.143204 -272.966688)
					(mid 279.490424 -272.966688)
					(end 280.143204 -272.966688)
				)
			)
		)
	)
	(zone
		(layers "B.Cu" "In11.Cu" "In13.Cu" "In15.Cu")
		(hatch none 0.5)
		(connect_pads
			(clearance 0)
		)
		(min_thickness 0.25)
		(keepout
			(tracks not_allowed)
			(vias allowed)
			(pads allowed)
			(copperpour not_allowed)
			(footprints allowed)
		)
		(placement
			(enabled no)
			(sheetname "")
		)
		(fill yes
			(thermal_gap 0.5)
			(thermal_bridge_width 0.5)
			(island_removal_mode 0)
		)
		(polygon
			(pts
				(arc
					(start 325.054976 -434.289962)
					(mid 324.245224 -434.289962)
					(end 325.054976 -434.289962)
				)
			)
		)
	)
	(zone
		(layers "B.Cu" "In11.Cu" "In13.Cu" "In15.Cu")
		(hatch none 0.5)
		(connect_pads
			(clearance 0)
		)
		(min_thickness 0.25)
		(keepout
			(tracks not_allowed)
			(vias allowed)
			(pads allowed)
			(copperpour not_allowed)
			(footprints allowed)
		)
		(placement
			(enabled no)
			(sheetname "")
		)
		(fill yes
			(thermal_gap 0.5)
			(thermal_bridge_width 0.5)
			(island_removal_mode 0)
		)
		(polygon
			(pts
				(arc
					(start 436.150004 -277.216616)
					(mid 435.497224 -277.216616)
					(end 436.150004 -277.216616)
				)
			)
		)
	)
	(zone
		(layers "B.Cu" "In11.Cu" "In13.Cu" "In15.Cu")
		(hatch none 0.5)
		(connect_pads
			(clearance 0)
		)
		(min_thickness 0.25)
		(keepout
			(tracks not_allowed)
			(vias allowed)
			(pads allowed)
			(copperpour not_allowed)
			(footprints allowed)
		)
		(placement
			(enabled no)
			(sheetname "")
		)
		(fill yes
			(thermal_gap 0.5)
			(thermal_bridge_width 0.5)
			(island_removal_mode 0)
		)
		(polygon
			(pts
				(arc
					(start 366.485424 -227.64496)
					(mid 365.832644 -227.64496)
					(end 366.485424 -227.64496)
				)
			)
		)
	)
	(zone
		(layers "B.Cu" "In11.Cu" "In13.Cu" "In15.Cu")
		(hatch none 0.5)
		(connect_pads
			(clearance 0)
		)
		(min_thickness 0.25)
		(keepout
			(tracks not_allowed)
			(vias allowed)
			(pads allowed)
			(copperpour not_allowed)
			(footprints allowed)
		)
		(placement
			(enabled no)
			(sheetname "")
		)
		(fill yes
			(thermal_gap 0.5)
			(thermal_bridge_width 0.5)
			(island_removal_mode 0)
		)
		(polygon
			(pts
				(arc
					(start 280.143204 -198.166736)
					(mid 279.490424 -198.166736)
					(end 280.143204 -198.166736)
				)
			)
		)
	)
	(zone
		(layers "B.Cu" "In11.Cu" "In13.Cu" "In15.Cu")
		(hatch none 0.5)
		(connect_pads
			(clearance 0)
		)
		(min_thickness 0.25)
		(keepout
			(tracks not_allowed)
			(vias allowed)
			(pads allowed)
			(copperpour not_allowed)
			(footprints allowed)
		)
		(placement
			(enabled no)
			(sheetname "")
		)
		(fill yes
			(thermal_gap 0.5)
			(thermal_bridge_width 0.5)
			(island_removal_mode 0)
		)
		(polygon
			(pts
				(arc
					(start 375.053606 -273.453098)
					(mid 374.400826 -273.453098)
					(end 375.053606 -273.453098)
				)
			)
		)
	)
	(zone
		(layers "B.Cu" "In11.Cu" "In13.Cu" "In15.Cu")
		(hatch none 0.5)
		(connect_pads
			(clearance 0)
		)
		(min_thickness 0.25)
		(keepout
			(tracks not_allowed)
			(vias allowed)
			(pads allowed)
			(copperpour not_allowed)
			(footprints allowed)
		)
		(placement
			(enabled no)
			(sheetname "")
		)
		(fill yes
			(thermal_gap 0.5)
			(thermal_bridge_width 0.5)
			(island_removal_mode 0)
		)
		(polygon
			(pts
				(arc
					(start 421.062404 -243.216684)
					(mid 420.409624 -243.216684)
					(end 421.062404 -243.216684)
				)
			)
		)
	)
	(zone
		(layers "B.Cu" "In11.Cu" "In13.Cu" "In15.Cu")
		(hatch none 0.5)
		(connect_pads
			(clearance 0)
		)
		(min_thickness 0.25)
		(keepout
			(tracks not_allowed)
			(vias allowed)
			(pads allowed)
			(copperpour not_allowed)
			(footprints allowed)
		)
		(placement
			(enabled no)
			(sheetname "")
		)
		(fill yes
			(thermal_gap 0.5)
			(thermal_bridge_width 0.5)
			(island_removal_mode 0)
		)
		(polygon
			(pts
				(arc
					(start 67.054984 -434.48986)
					(mid 66.245232 -434.48986)
					(end 67.054984 -434.48986)
				)
			)
		)
	)
	(zone
		(layers "B.Cu" "In11.Cu" "In13.Cu" "In15.Cu")
		(hatch none 0.5)
		(connect_pads
			(clearance 0)
		)
		(min_thickness 0.25)
		(keepout
			(tracks not_allowed)
			(vias allowed)
			(pads allowed)
			(copperpour not_allowed)
			(footprints allowed)
		)
		(placement
			(enabled no)
			(sheetname "")
		)
		(fill yes
			(thermal_gap 0.5)
			(thermal_bridge_width 0.5)
			(island_removal_mode 0)
		)
		(polygon
			(pts
				(arc
					(start 128.522984 -269.38351)
					(mid 127.870204 -269.38351)
					(end 128.522984 -269.38351)
				)
			)
		)
	)
	(zone
		(layers "B.Cu" "In11.Cu" "In13.Cu" "In15.Cu")
		(hatch none 0.5)
		(connect_pads
			(clearance 0)
		)
		(min_thickness 0.25)
		(keepout
			(tracks not_allowed)
			(vias allowed)
			(pads allowed)
			(copperpour not_allowed)
			(footprints allowed)
		)
		(placement
			(enabled no)
			(sheetname "")
		)
		(fill yes
			(thermal_gap 0.5)
			(thermal_bridge_width 0.5)
			(island_removal_mode 0)
		)
		(polygon
			(pts
				(arc
					(start 192.310004 -199.01662)
					(mid 191.657224 -199.01662)
					(end 192.310004 -199.01662)
				)
			)
		)
	)
	(zone
		(layers "B.Cu" "In11.Cu" "In13.Cu" "In15.Cu")
		(hatch none 0.5)
		(connect_pads
			(clearance 0)
		)
		(min_thickness 0.25)
		(keepout
			(tracks not_allowed)
			(vias allowed)
			(pads allowed)
			(copperpour not_allowed)
			(footprints allowed)
		)
		(placement
			(enabled no)
			(sheetname "")
		)
		(fill yes
			(thermal_gap 0.5)
			(thermal_bridge_width 0.5)
			(island_removal_mode 0)
		)
		(polygon
			(pts
				(arc
					(start 157.15488 -430.689766)
					(mid 156.345128 -430.689766)
					(end 157.15488 -430.689766)
				)
			)
		)
	)
	(zone
		(layers "B.Cu" "In11.Cu" "In13.Cu" "In15.Cu")
		(hatch none 0.5)
		(connect_pads
			(clearance 0)
		)
		(min_thickness 0.25)
		(keepout
			(tracks not_allowed)
			(vias allowed)
			(pads allowed)
			(copperpour not_allowed)
			(footprints allowed)
		)
		(placement
			(enabled no)
			(sheetname "")
		)
		(fill yes
			(thermal_gap 0.5)
			(thermal_bridge_width 0.5)
			(island_removal_mode 0)
		)
		(polygon
			(pts
				(arc
					(start 71.054976 -426.089826)
					(mid 70.245224 -426.089826)
					(end 71.054976 -426.089826)
				)
			)
		)
	)
	(zone
		(layers "B.Cu" "In11.Cu" "In13.Cu" "In15.Cu")
		(hatch none 0.5)
		(connect_pads
			(clearance 0)
		)
		(min_thickness 0.25)
		(keepout
			(tracks not_allowed)
			(vias allowed)
			(pads allowed)
			(copperpour not_allowed)
			(footprints allowed)
		)
		(placement
			(enabled no)
			(sheetname "")
		)
		(fill yes
			(thermal_gap 0.5)
			(thermal_bridge_width 0.5)
			(island_removal_mode 0)
		)
		(polygon
			(pts
				(arc
					(start 127.473202 -233.34218)
					(mid 126.820422 -233.34218)
					(end 127.473202 -233.34218)
				)
			)
		)
	)
	(zone
		(layers "B.Cu" "In11.Cu" "In13.Cu" "In15.Cu")
		(hatch none 0.5)
		(connect_pads
			(clearance 0)
		)
		(min_thickness 0.25)
		(keepout
			(tracks not_allowed)
			(vias allowed)
			(pads allowed)
			(copperpour not_allowed)
			(footprints allowed)
		)
		(placement
			(enabled no)
			(sheetname "")
		)
		(fill yes
			(thermal_gap 0.5)
			(thermal_bridge_width 0.5)
			(island_removal_mode 0)
		)
		(polygon
			(pts
				(arc
					(start 343.46007 -231.714548)
					(mid 342.80729 -231.714548)
					(end 343.46007 -231.714548)
				)
			)
		)
	)
	(zone
		(layers "B.Cu" "In11.Cu" "In13.Cu" "In15.Cu")
		(hatch none 0.5)
		(connect_pads
			(clearance 0)
		)
		(min_thickness 0.25)
		(keepout
			(tracks not_allowed)
			(vias allowed)
			(pads allowed)
			(copperpour not_allowed)
			(footprints allowed)
		)
		(placement
			(enabled no)
			(sheetname "")
		)
		(fill yes
			(thermal_gap 0.5)
			(thermal_bridge_width 0.5)
			(island_removal_mode 0)
		)
		(polygon
			(pts
				(arc
					(start 336.051652 -285.661354)
					(mid 335.398872 -285.661354)
					(end 336.051652 -285.661354)
				)
			)
		)
	)
	(zone
		(layers "B.Cu" "In11.Cu" "In13.Cu" "In15.Cu")
		(hatch none 0.5)
		(connect_pads
			(clearance 0)
		)
		(min_thickness 0.25)
		(keepout
			(tracks not_allowed)
			(vias allowed)
			(pads allowed)
			(copperpour not_allowed)
			(footprints allowed)
		)
		(placement
			(enabled no)
			(sheetname "")
		)
		(fill yes
			(thermal_gap 0.5)
			(thermal_bridge_width 0.5)
			(island_removal_mode 0)
		)
		(polygon
			(pts
				(arc
					(start 337.351116 -216.25052)
					(mid 336.698336 -216.25052)
					(end 337.351116 -216.25052)
				)
			)
		)
	)
	(zone
		(layers "B.Cu" "In11.Cu" "In13.Cu" "In15.Cu")
		(hatch none 0.5)
		(connect_pads
			(clearance 0)
		)
		(min_thickness 0.25)
		(keepout
			(tracks not_allowed)
			(vias allowed)
			(pads allowed)
			(copperpour not_allowed)
			(footprints allowed)
		)
		(placement
			(enabled no)
			(sheetname "")
		)
		(fill yes
			(thermal_gap 0.5)
			(thermal_bridge_width 0.5)
			(island_removal_mode 0)
		)
		(polygon
			(pts
				(arc
					(start 24.659336 -244.066568)
					(mid 24.006556 -244.066568)
					(end 24.659336 -244.066568)
				)
			)
		)
	)
	(zone
		(layers "B.Cu" "In11.Cu" "In13.Cu" "In15.Cu")
		(hatch none 0.5)
		(connect_pads
			(clearance 0)
		)
		(min_thickness 0.25)
		(keepout
			(tracks not_allowed)
			(vias allowed)
			(pads allowed)
			(copperpour not_allowed)
			(footprints allowed)
		)
		(placement
			(enabled no)
			(sheetname "")
		)
		(fill yes
			(thermal_gap 0.5)
			(thermal_bridge_width 0.5)
			(island_removal_mode 0)
		)
		(polygon
			(pts
				(arc
					(start 89.991184 -280.778204)
					(mid 89.338404 -280.778204)
					(end 89.991184 -280.778204)
				)
			)
		)
	)
	(zone
		(layers "B.Cu" "In11.Cu" "In13.Cu" "In15.Cu")
		(hatch none 0.5)
		(connect_pads
			(clearance 0)
		)
		(min_thickness 0.25)
		(keepout
			(tracks not_allowed)
			(vias allowed)
			(pads allowed)
			(copperpour not_allowed)
			(footprints allowed)
		)
		(placement
			(enabled no)
			(sheetname "")
		)
		(fill yes
			(thermal_gap 0.5)
			(thermal_bridge_width 0.5)
			(island_removal_mode 0)
		)
		(polygon
			(pts
				(arc
					(start 97.509584 -266.128246)
					(mid 96.856804 -266.128246)
					(end 97.509584 -266.128246)
				)
			)
		)
	)
	(zone
		(layers "B.Cu" "In11.Cu" "In13.Cu" "In15.Cu")
		(hatch none 0.5)
		(connect_pads
			(clearance 0)
		)
		(min_thickness 0.25)
		(keepout
			(tracks not_allowed)
			(vias allowed)
			(pads allowed)
			(copperpour not_allowed)
			(footprints allowed)
		)
		(placement
			(enabled no)
			(sheetname "")
		)
		(fill yes
			(thermal_gap 0.5)
			(thermal_bridge_width 0.5)
			(island_removal_mode 0)
		)
		(polygon
			(pts
				(arc
					(start 386.15493 -429.689768)
					(mid 385.345178 -429.689768)
					(end 386.15493 -429.689768)
				)
			)
		)
	)
	(zone
		(layers "B.Cu" "In11.Cu" "In13.Cu" "In15.Cu")
		(hatch none 0.5)
		(connect_pads
			(clearance 0)
		)
		(min_thickness 0.25)
		(keepout
			(tracks not_allowed)
			(vias allowed)
			(pads allowed)
			(copperpour not_allowed)
			(footprints allowed)
		)
		(placement
			(enabled no)
			(sheetname "")
		)
		(fill yes
			(thermal_gap 0.5)
			(thermal_bridge_width 0.5)
			(island_removal_mode 0)
		)
		(polygon
			(pts
				(arc
					(start 95.990156 -230.900478)
					(mid 95.337376 -230.900478)
					(end 95.990156 -230.900478)
				)
			)
		)
	)
	(zone
		(layers "B.Cu" "In11.Cu" "In13.Cu" "In15.Cu")
		(hatch none 0.5)
		(connect_pads
			(clearance 0)
		)
		(min_thickness 0.25)
		(keepout
			(tracks not_allowed)
			(vias allowed)
			(pads allowed)
			(copperpour not_allowed)
			(footprints allowed)
		)
		(placement
			(enabled no)
			(sheetname "")
		)
		(fill yes
			(thermal_gap 0.5)
			(thermal_bridge_width 0.5)
			(island_removal_mode 0)
		)
		(polygon
			(pts
				(arc
					(start 350.441514 -176.176432)
					(mid 349.737934 -176.176432)
					(end 350.441514 -176.176432)
				)
			)
		)
	)
	(zone
		(layers "B.Cu" "In11.Cu" "In13.Cu" "In15.Cu")
		(hatch none 0.5)
		(connect_pads
			(clearance 0)
		)
		(min_thickness 0.25)
		(keepout
			(tracks not_allowed)
			(vias allowed)
			(pads allowed)
			(copperpour not_allowed)
			(footprints allowed)
		)
		(placement
			(enabled no)
			(sheetname "")
		)
		(fill yes
			(thermal_gap 0.5)
			(thermal_bridge_width 0.5)
			(island_removal_mode 0)
		)
		(polygon
			(pts
				(arc
					(start 173.122336 -243.216684)
					(mid 172.469556 -243.216684)
					(end 173.122336 -243.216684)
				)
			)
		)
	)
	(zone
		(layers "B.Cu" "In11.Cu" "In13.Cu" "In15.Cu")
		(hatch none 0.5)
		(connect_pads
			(clearance 0)
		)
		(min_thickness 0.25)
		(keepout
			(tracks not_allowed)
			(vias allowed)
			(pads allowed)
			(copperpour not_allowed)
			(footprints allowed)
		)
		(placement
			(enabled no)
			(sheetname "")
		)
		(fill yes
			(thermal_gap 0.5)
			(thermal_bridge_width 0.5)
			(island_removal_mode 0)
		)
		(polygon
			(pts
				(arc
					(start 192.310004 -220.266768)
					(mid 191.657224 -220.266768)
					(end 192.310004 -220.266768)
				)
			)
		)
	)
	(zone
		(layers "B.Cu" "In11.Cu" "In13.Cu" "In15.Cu")
		(hatch none 0.5)
		(connect_pads
			(clearance 0)
		)
		(min_thickness 0.25)
		(keepout
			(tracks not_allowed)
			(vias allowed)
			(pads allowed)
			(copperpour not_allowed)
			(footprints allowed)
		)
		(placement
			(enabled no)
			(sheetname "")
		)
		(fill yes
			(thermal_gap 0.5)
			(thermal_bridge_width 0.5)
			(island_removal_mode 0)
		)
		(polygon
			(pts
				(arc
					(start 192.268094 -281.466798)
					(mid 191.615314 -281.466798)
					(end 192.268094 -281.466798)
				)
			)
		)
	)
	(zone
		(layers "B.Cu" "In11.Cu" "In13.Cu" "In15.Cu")
		(hatch none 0.5)
		(connect_pads
			(clearance 0)
		)
		(min_thickness 0.25)
		(keepout
			(tracks not_allowed)
			(vias allowed)
			(pads allowed)
			(copperpour not_allowed)
			(footprints allowed)
		)
		(placement
			(enabled no)
			(sheetname "")
		)
		(fill yes
			(thermal_gap 0.5)
			(thermal_bridge_width 0.5)
			(island_removal_mode 0)
		)
		(polygon
			(pts
				(arc
					(start 440.224672 -270.416782)
					(mid 439.571892 -270.416782)
					(end 440.224672 -270.416782)
				)
			)
		)
	)
	(zone
		(layers "B.Cu" "In11.Cu" "In13.Cu" "In15.Cu")
		(hatch none 0.5)
		(connect_pads
			(clearance 0)
		)
		(min_thickness 0.25)
		(keepout
			(tracks not_allowed)
			(vias allowed)
			(pads allowed)
			(copperpour not_allowed)
			(footprints allowed)
		)
		(placement
			(enabled no)
			(sheetname "")
		)
		(fill yes
			(thermal_gap 0.5)
			(thermal_bridge_width 0.5)
			(island_removal_mode 0)
		)
		(polygon
			(pts
				(arc
					(start 375.183146 -171.193968)
					(mid 374.479566 -171.193968)
					(end 375.183146 -171.193968)
				)
			)
		)
	)
	(zone
		(layers "B.Cu" "In11.Cu" "In13.Cu" "In15.Cu")
		(hatch none 0.5)
		(connect_pads
			(clearance 0)
		)
		(min_thickness 0.25)
		(keepout
			(tracks not_allowed)
			(vias allowed)
			(pads allowed)
			(copperpour not_allowed)
			(footprints allowed)
		)
		(placement
			(enabled no)
			(sheetname "")
		)
		(fill yes
			(thermal_gap 0.5)
			(thermal_bridge_width 0.5)
			(island_removal_mode 0)
		)
		(polygon
			(pts
				(arc
					(start 103.618538 -275.08073)
					(mid 102.965758 -275.08073)
					(end 103.618538 -275.08073)
				)
			)
		)
	)
	(zone
		(layers "B.Cu" "In11.Cu" "In13.Cu" "In15.Cu")
		(hatch none 0.5)
		(connect_pads
			(clearance 0)
		)
		(min_thickness 0.25)
		(keepout
			(tracks not_allowed)
			(vias allowed)
			(pads allowed)
			(copperpour not_allowed)
			(footprints allowed)
		)
		(placement
			(enabled no)
			(sheetname "")
		)
		(fill yes
			(thermal_gap 0.5)
			(thermal_bridge_width 0.5)
			(island_removal_mode 0)
		)
		(polygon
			(pts
				(arc
					(start 86.054946 -428.28972)
					(mid 85.245194 -428.28972)
					(end 86.054946 -428.28972)
				)
			)
		)
	)
	(zone
		(layers "B.Cu" "In11.Cu" "In13.Cu" "In15.Cu")
		(hatch none 0.5)
		(connect_pads
			(clearance 0)
		)
		(min_thickness 0.25)
		(keepout
			(tracks not_allowed)
			(vias allowed)
			(pads allowed)
			(copperpour not_allowed)
			(footprints allowed)
		)
		(placement
			(enabled no)
			(sheetname "")
		)
		(fill yes
			(thermal_gap 0.5)
			(thermal_bridge_width 0.5)
			(island_removal_mode 0)
		)
		(polygon
			(pts
				(arc
					(start 386.23748 -410.030168)
					(mid 385.5339 -410.030168)
					(end 386.23748 -410.030168)
				)
			)
		)
	)
	(zone
		(layers "B.Cu" "In11.Cu" "In13.Cu" "In15.Cu")
		(hatch none 0.5)
		(connect_pads
			(clearance 0)
		)
		(min_thickness 0.25)
		(keepout
			(tracks not_allowed)
			(vias allowed)
			(pads allowed)
			(copperpour not_allowed)
			(footprints allowed)
		)
		(placement
			(enabled no)
			(sheetname "")
		)
		(fill yes
			(thermal_gap 0.5)
			(thermal_bridge_width 0.5)
			(island_removal_mode 0)
		)
		(polygon
			(pts
				(arc
					(start 97.399602 -238.225584)
					(mid 96.746822 -238.225584)
					(end 97.399602 -238.225584)
				)
			)
		)
	)
	(zone
		(layers "B.Cu" "In11.Cu" "In13.Cu" "In15.Cu")
		(hatch none 0.5)
		(connect_pads
			(clearance 0)
		)
		(min_thickness 0.25)
		(keepout
			(tracks not_allowed)
			(vias allowed)
			(pads allowed)
			(copperpour not_allowed)
			(footprints allowed)
		)
		(placement
			(enabled no)
			(sheetname "")
		)
		(fill yes
			(thermal_gap 0.5)
			(thermal_bridge_width 0.5)
			(island_removal_mode 0)
		)
		(polygon
			(pts
				(arc
					(start 280.143204 -218.566746)
					(mid 279.490424 -218.566746)
					(end 280.143204 -218.566746)
				)
			)
		)
	)
	(zone
		(layers "B.Cu" "In11.Cu" "In13.Cu" "In15.Cu")
		(hatch none 0.5)
		(connect_pads
			(clearance 0)
		)
		(min_thickness 0.25)
		(keepout
			(tracks not_allowed)
			(vias allowed)
			(pads allowed)
			(copperpour not_allowed)
			(footprints allowed)
		)
		(placement
			(enabled no)
			(sheetname "")
		)
		(fill yes
			(thermal_gap 0.5)
			(thermal_bridge_width 0.5)
			(island_removal_mode 0)
		)
		(polygon
			(pts
				(arc
					(start 127.003556 -230.900478)
					(mid 126.350776 -230.900478)
					(end 127.003556 -230.900478)
				)
			)
		)
	)
	(zone
		(layers "B.Cu" "In11.Cu" "In13.Cu" "In15.Cu")
		(hatch none 0.5)
		(connect_pads
			(clearance 0)
		)
		(min_thickness 0.25)
		(keepout
			(tracks not_allowed)
			(vias allowed)
			(pads allowed)
			(copperpour not_allowed)
			(footprints allowed)
		)
		(placement
			(enabled no)
			(sheetname "")
		)
		(fill yes
			(thermal_gap 0.5)
			(thermal_bridge_width 0.5)
			(island_removal_mode 0)
		)
		(polygon
			(pts
				(arc
					(start 134.105904 -410.030168)
					(mid 133.402324 -410.030168)
					(end 134.105904 -410.030168)
				)
			)
		)
	)
	(zone
		(layers "B.Cu" "In11.Cu" "In13.Cu" "In15.Cu")
		(hatch none 0.5)
		(connect_pads
			(clearance 0)
		)
		(min_thickness 0.25)
		(keepout
			(tracks not_allowed)
			(vias allowed)
			(pads allowed)
			(copperpour not_allowed)
			(footprints allowed)
		)
		(placement
			(enabled no)
			(sheetname "")
		)
		(fill yes
			(thermal_gap 0.5)
			(thermal_bridge_width 0.5)
			(island_removal_mode 0)
		)
		(polygon
			(pts
				(arc
					(start 345.017598 -403.883876)
					(mid 344.314018 -403.883876)
					(end 345.017598 -403.883876)
				)
			)
		)
	)
	(zone
		(layers "B.Cu" "In11.Cu" "In13.Cu" "In15.Cu")
		(hatch none 0.5)
		(connect_pads
			(clearance 0)
		)
		(min_thickness 0.25)
		(keepout
			(tracks not_allowed)
			(vias allowed)
			(pads allowed)
			(copperpour not_allowed)
			(footprints allowed)
		)
		(placement
			(enabled no)
			(sheetname "")
		)
		(fill yes
			(thermal_gap 0.5)
			(thermal_bridge_width 0.5)
			(island_removal_mode 0)
		)
		(polygon
			(pts
				(arc
					(start 462.881472 -244.916706)
					(mid 462.228692 -244.916706)
					(end 462.881472 -244.916706)
				)
			)
		)
	)
	(zone
		(layers "B.Cu" "In11.Cu" "In13.Cu" "In15.Cu")
		(hatch none 0.5)
		(connect_pads
			(clearance 0)
		)
		(min_thickness 0.25)
		(keepout
			(tracks not_allowed)
			(vias allowed)
			(pads allowed)
			(copperpour not_allowed)
			(footprints allowed)
		)
		(placement
			(enabled no)
			(sheetname "")
		)
		(fill yes
			(thermal_gap 0.5)
			(thermal_bridge_width 0.5)
			(island_removal_mode 0)
		)
		(polygon
			(pts
				(arc
					(start 343.570052 -259.616956)
					(mid 342.917272 -259.616956)
					(end 343.570052 -259.616956)
				)
			)
		)
	)
	(zone
		(layers "B.Cu" "In11.Cu" "In13.Cu" "In15.Cu")
		(hatch none 0.5)
		(connect_pads
			(clearance 0)
		)
		(min_thickness 0.25)
		(keepout
			(tracks not_allowed)
			(vias allowed)
			(pads allowed)
			(copperpour not_allowed)
			(footprints allowed)
		)
		(placement
			(enabled no)
			(sheetname "")
		)
		(fill yes
			(thermal_gap 0.5)
			(thermal_bridge_width 0.5)
			(island_removal_mode 0)
		)
		(polygon
			(pts
				(arc
					(start 188.209936 -198.166736)
					(mid 187.557156 -198.166736)
					(end 188.209936 -198.166736)
				)
			)
		)
	)
	(zone
		(layers "B.Cu" "In11.Cu" "In13.Cu" "In15.Cu")
		(hatch none 0.5)
		(connect_pads
			(clearance 0)
		)
		(min_thickness 0.25)
		(keepout
			(tracks not_allowed)
			(vias allowed)
			(pads allowed)
			(copperpour not_allowed)
			(footprints allowed)
		)
		(placement
			(enabled no)
			(sheetname "")
		)
		(fill yes
			(thermal_gap 0.5)
			(thermal_bridge_width 0.5)
			(island_removal_mode 0)
		)
		(polygon
			(pts
				(arc
					(start 313.521598 -403.883876)
					(mid 312.818018 -403.883876)
					(end 313.521598 -403.883876)
				)
			)
		)
	)
	(zone
		(layers "B.Cu" "In11.Cu" "In13.Cu" "In15.Cu")
		(hatch none 0.5)
		(connect_pads
			(clearance 0)
		)
		(min_thickness 0.25)
		(keepout
			(tracks not_allowed)
			(vias allowed)
			(pads allowed)
			(copperpour not_allowed)
			(footprints allowed)
		)
		(placement
			(enabled no)
			(sheetname "")
		)
		(fill yes
			(thermal_gap 0.5)
			(thermal_bridge_width 0.5)
			(island_removal_mode 0)
		)
		(polygon
			(pts
				(arc
					(start 124.653802 -213.732618)
					(mid 124.001022 -213.732618)
					(end 124.653802 -213.732618)
				)
			)
		)
	)
	(zone
		(layers "B.Cu" "In11.Cu" "In13.Cu" "In15.Cu")
		(hatch none 0.5)
		(connect_pads
			(clearance 0)
		)
		(min_thickness 0.25)
		(keepout
			(tracks not_allowed)
			(vias allowed)
			(pads allowed)
			(copperpour not_allowed)
			(footprints allowed)
		)
		(placement
			(enabled no)
			(sheetname "")
		)
		(fill yes
			(thermal_gap 0.5)
			(thermal_bridge_width 0.5)
			(island_removal_mode 0)
		)
		(polygon
			(pts
				(arc
					(start 92.230448 -214.622634)
					(mid 91.577668 -214.622634)
					(end 92.230448 -214.622634)
				)
			)
		)
	)
	(zone
		(layers "B.Cu" "In11.Cu" "In13.Cu" "In15.Cu")
		(hatch none 0.5)
		(connect_pads
			(clearance 0)
		)
		(min_thickness 0.25)
		(keepout
			(tracks not_allowed)
			(vias allowed)
			(pads allowed)
			(copperpour not_allowed)
			(footprints allowed)
		)
		(placement
			(enabled no)
			(sheetname "")
		)
		(fill yes
			(thermal_gap 0.5)
			(thermal_bridge_width 0.5)
			(island_removal_mode 0)
		)
		(polygon
			(pts
				(arc
					(start 115.725448 -214.622634)
					(mid 115.072668 -214.622634)
					(end 115.725448 -214.622634)
				)
			)
		)
	)
	(zone
		(layers "B.Cu" "In11.Cu" "In13.Cu" "In15.Cu")
		(hatch none 0.5)
		(connect_pads
			(clearance 0)
		)
		(min_thickness 0.25)
		(keepout
			(tracks not_allowed)
			(vias allowed)
			(pads allowed)
			(copperpour not_allowed)
			(footprints allowed)
		)
		(placement
			(enabled no)
			(sheetname "")
		)
		(fill yes
			(thermal_gap 0.5)
			(thermal_bridge_width 0.5)
			(island_removal_mode 0)
		)
		(polygon
			(pts
				(arc
					(start 340.054946 -434.48986)
					(mid 339.245194 -434.48986)
					(end 340.054946 -434.48986)
				)
			)
		)
	)
	(zone
		(layers "B.Cu" "In11.Cu" "In13.Cu" "In15.Cu")
		(hatch none 0.5)
		(connect_pads
			(clearance 0)
		)
		(min_thickness 0.25)
		(keepout
			(tracks not_allowed)
			(vias allowed)
			(pads allowed)
			(copperpour not_allowed)
			(footprints allowed)
		)
		(placement
			(enabled no)
			(sheetname "")
		)
		(fill yes
			(thermal_gap 0.5)
			(thermal_bridge_width 0.5)
			(island_removal_mode 0)
		)
		(polygon
			(pts
				(arc
					(start 370.474494 -182.115968)
					(mid 369.770914 -182.115968)
					(end 370.474494 -182.115968)
				)
			)
		)
	)
	(zone
		(layers "B.Cu" "In11.Cu" "In13.Cu" "In15.Cu")
		(hatch none 0.5)
		(connect_pads
			(clearance 0)
		)
		(min_thickness 0.25)
		(keepout
			(tracks not_allowed)
			(vias allowed)
			(pads allowed)
			(copperpour not_allowed)
			(footprints allowed)
		)
		(placement
			(enabled no)
			(sheetname "")
		)
		(fill yes
			(thermal_gap 0.5)
			(thermal_bridge_width 0.5)
			(island_removal_mode 0)
		)
		(polygon
			(pts
				(arc
					(start 73.054972 -434.289962)
					(mid 72.24522 -434.289962)
					(end 73.054972 -434.289962)
				)
			)
		)
	)
	(zone
		(layers "B.Cu" "In11.Cu" "In13.Cu" "In15.Cu")
		(hatch none 0.5)
		(connect_pads
			(clearance 0)
		)
		(min_thickness 0.25)
		(keepout
			(tracks not_allowed)
			(vias allowed)
			(pads allowed)
			(copperpour not_allowed)
			(footprints allowed)
		)
		(placement
			(enabled no)
			(sheetname "")
		)
		(fill yes
			(thermal_gap 0.5)
			(thermal_bridge_width 0.5)
			(island_removal_mode 0)
		)
		(polygon
			(pts
				(arc
					(start 137.341356 -216.25052)
					(mid 136.688576 -216.25052)
					(end 137.341356 -216.25052)
				)
			)
		)
	)
	(zone
		(layers "B.Cu" "In11.Cu" "In13.Cu" "In15.Cu")
		(hatch none 0.5)
		(connect_pads
			(clearance 0)
		)
		(min_thickness 0.25)
		(keepout
			(tracks not_allowed)
			(vias allowed)
			(pads allowed)
			(copperpour not_allowed)
			(footprints allowed)
		)
		(placement
			(enabled no)
			(sheetname "")
		)
		(fill yes
			(thermal_gap 0.5)
			(thermal_bridge_width 0.5)
			(island_removal_mode 0)
		)
		(polygon
			(pts
				(arc
					(start 161.675064 -410.030168)
					(mid 160.971484 -410.030168)
					(end 161.675064 -410.030168)
				)
			)
		)
	)
	(zone
		(layers "B.Cu" "In11.Cu" "In13.Cu" "In15.Cu")
		(hatch none 0.5)
		(connect_pads
			(clearance 0)
		)
		(min_thickness 0.25)
		(keepout
			(tracks not_allowed)
			(vias allowed)
			(pads allowed)
			(copperpour not_allowed)
			(footprints allowed)
		)
		(placement
			(enabled no)
			(sheetname "")
		)
		(fill yes
			(thermal_gap 0.5)
			(thermal_bridge_width 0.5)
			(island_removal_mode 0)
		)
		(polygon
			(pts
				(arc
					(start 343.930224 -227.64496)
					(mid 343.277444 -227.64496)
					(end 343.930224 -227.64496)
				)
			)
		)
	)
	(zone
		(layers "B.Cu" "In11.Cu" "In13.Cu" "In15.Cu")
		(hatch none 0.5)
		(connect_pads
			(clearance 0)
		)
		(min_thickness 0.25)
		(keepout
			(tracks not_allowed)
			(vias allowed)
			(pads allowed)
			(copperpour not_allowed)
			(footprints allowed)
		)
		(placement
			(enabled no)
			(sheetname "")
		)
		(fill yes
			(thermal_gap 0.5)
			(thermal_bridge_width 0.5)
			(island_removal_mode 0)
		)
		(polygon
			(pts
				(arc
					(start 188.209936 -282.316682)
					(mid 187.557156 -282.316682)
					(end 188.209936 -282.316682)
				)
			)
		)
	)
	(zone
		(layers "B.Cu" "In11.Cu" "In13.Cu" "In15.Cu")
		(hatch none 0.5)
		(connect_pads
			(clearance 0)
		)
		(min_thickness 0.25)
		(keepout
			(tracks not_allowed)
			(vias allowed)
			(pads allowed)
			(copperpour not_allowed)
			(footprints allowed)
		)
		(placement
			(enabled no)
			(sheetname "")
		)
		(fill yes
			(thermal_gap 0.5)
			(thermal_bridge_width 0.5)
			(island_removal_mode 0)
		)
		(polygon
			(pts
				(arc
					(start 65.054988 -435.489858)
					(mid 64.245236 -435.489858)
					(end 65.054988 -435.489858)
				)
			)
		)
	)
	(zone
		(layers "B.Cu" "In11.Cu" "In13.Cu" "In15.Cu")
		(hatch none 0.5)
		(connect_pads
			(clearance 0)
		)
		(min_thickness 0.25)
		(keepout
			(tracks not_allowed)
			(vias allowed)
			(pads allowed)
			(copperpour not_allowed)
			(footprints allowed)
		)
		(placement
			(enabled no)
			(sheetname "")
		)
		(fill yes
			(thermal_gap 0.5)
			(thermal_bridge_width 0.5)
			(island_removal_mode 0)
		)
		(polygon
			(pts
				(arc
					(start 143.154908 -429.689768)
					(mid 142.345156 -429.689768)
					(end 143.154908 -429.689768)
				)
			)
		)
	)
	(zone
		(layers "B.Cu" "In11.Cu" "In13.Cu" "In15.Cu")
		(hatch none 0.5)
		(connect_pads
			(clearance 0)
		)
		(min_thickness 0.25)
		(keepout
			(tracks not_allowed)
			(vias allowed)
			(pads allowed)
			(copperpour not_allowed)
			(footprints allowed)
		)
		(placement
			(enabled no)
			(sheetname "")
		)
		(fill yes
			(thermal_gap 0.5)
			(thermal_bridge_width 0.5)
			(island_removal_mode 0)
		)
		(polygon
			(pts
				(arc
					(start 361.31627 -228.45903)
					(mid 360.66349 -228.45903)
					(end 361.31627 -228.45903)
				)
			)
		)
	)
	(zone
		(layers "B.Cu" "In11.Cu" "In13.Cu" "In15.Cu")
		(hatch none 0.5)
		(connect_pads
			(clearance 0)
		)
		(min_thickness 0.25)
		(keepout
			(tracks not_allowed)
			(vias allowed)
			(pads allowed)
			(copperpour not_allowed)
			(footprints allowed)
		)
		(placement
			(enabled no)
			(sheetname "")
		)
		(fill yes
			(thermal_gap 0.5)
			(thermal_bridge_width 0.5)
			(island_removal_mode 0)
		)
		(polygon
			(pts
				(arc
					(start 17.115536 -207.51673)
					(mid 16.462756 -207.51673)
					(end 17.115536 -207.51673)
				)
			)
		)
	)
	(zone
		(layers "B.Cu" "In11.Cu" "In13.Cu" "In15.Cu")
		(hatch none 0.5)
		(connect_pads
			(clearance 0)
		)
		(min_thickness 0.25)
		(keepout
			(tracks not_allowed)
			(vias allowed)
			(pads allowed)
			(copperpour not_allowed)
			(footprints allowed)
		)
		(placement
			(enabled no)
			(sheetname "")
		)
		(fill yes
			(thermal_gap 0.5)
			(thermal_bridge_width 0.5)
			(island_removal_mode 0)
		)
		(polygon
			(pts
				(arc
					(start 413.493204 -244.066568)
					(mid 412.840424 -244.066568)
					(end 413.493204 -244.066568)
				)
			)
		)
	)
	(zone
		(layers "B.Cu" "In11.Cu" "In13.Cu" "In15.Cu")
		(hatch none 0.5)
		(connect_pads
			(clearance 0)
		)
		(min_thickness 0.25)
		(keepout
			(tracks not_allowed)
			(vias allowed)
			(pads allowed)
			(copperpour not_allowed)
			(footprints allowed)
		)
		(placement
			(enabled no)
			(sheetname "")
		)
		(fill yes
			(thermal_gap 0.5)
			(thermal_bridge_width 0.5)
			(island_removal_mode 0)
		)
		(polygon
			(pts
				(arc
					(start 344.870024 -232.528364)
					(mid 344.217244 -232.528364)
					(end 344.870024 -232.528364)
				)
			)
		)
	)
	(zone
		(layers "B.Cu" "In11.Cu" "In13.Cu" "In15.Cu")
		(hatch none 0.5)
		(connect_pads
			(clearance 0)
		)
		(min_thickness 0.25)
		(keepout
			(tracks not_allowed)
			(vias allowed)
			(pads allowed)
			(copperpour not_allowed)
			(footprints allowed)
		)
		(placement
			(enabled no)
			(sheetname "")
		)
		(fill yes
			(thermal_gap 0.5)
			(thermal_bridge_width 0.5)
			(island_removal_mode 0)
		)
		(polygon
			(pts
				(arc
					(start 36.303204 -284.016704)
					(mid 35.650424 -284.016704)
					(end 36.303204 -284.016704)
				)
			)
		)
	)
	(zone
		(layers "B.Cu" "In11.Cu" "In13.Cu" "In15.Cu")
		(hatch none 0.5)
		(connect_pads
			(clearance 0)
		)
		(min_thickness 0.25)
		(keepout
			(tracks not_allowed)
			(vias allowed)
			(pads allowed)
			(copperpour not_allowed)
			(footprints allowed)
		)
		(placement
			(enabled no)
			(sheetname "")
		)
		(fill yes
			(thermal_gap 0.5)
			(thermal_bridge_width 0.5)
			(island_removal_mode 0)
		)
		(polygon
			(pts
				(arc
					(start 345.33967 -228.45903)
					(mid 344.68689 -228.45903)
					(end 345.33967 -228.45903)
				)
			)
		)
	)
	(zone
		(layers "B.Cu" "In11.Cu" "In13.Cu" "In15.Cu")
		(hatch none 0.5)
		(connect_pads
			(clearance 0)
		)
		(min_thickness 0.25)
		(keepout
			(tracks not_allowed)
			(vias allowed)
			(pads allowed)
			(copperpour not_allowed)
			(footprints allowed)
		)
		(placement
			(enabled no)
			(sheetname "")
		)
		(fill yes
			(thermal_gap 0.5)
			(thermal_bridge_width 0.5)
			(island_removal_mode 0)
		)
		(polygon
			(pts
				(arc
					(start 436.150004 -232.166668)
					(mid 435.497224 -232.166668)
					(end 436.150004 -232.166668)
				)
			)
		)
	)
	(zone
		(layers "B.Cu" "In11.Cu" "In13.Cu" "In15.Cu")
		(hatch none 0.5)
		(connect_pads
			(clearance 0)
		)
		(min_thickness 0.25)
		(keepout
			(tracks not_allowed)
			(vias allowed)
			(pads allowed)
			(copperpour not_allowed)
			(footprints allowed)
		)
		(placement
			(enabled no)
			(sheetname "")
		)
		(fill yes
			(thermal_gap 0.5)
			(thermal_bridge_width 0.5)
			(island_removal_mode 0)
		)
		(polygon
			(pts
				(arc
					(start 436.150004 -227.91674)
					(mid 435.497224 -227.91674)
					(end 436.150004 -227.91674)
				)
			)
		)
	)
	(zone
		(layers "B.Cu" "In11.Cu" "In13.Cu" "In15.Cu")
		(hatch none 0.5)
		(connect_pads
			(clearance 0)
		)
		(min_thickness 0.25)
		(keepout
			(tracks not_allowed)
			(vias allowed)
			(pads allowed)
			(copperpour not_allowed)
			(footprints allowed)
		)
		(placement
			(enabled no)
			(sheetname "")
		)
		(fill yes
			(thermal_gap 0.5)
			(thermal_bridge_width 0.5)
			(island_removal_mode 0)
		)
		(polygon
			(pts
				(arc
					(start 409.154884 -437.889904)
					(mid 408.345132 -437.889904)
					(end 409.154884 -437.889904)
				)
			)
		)
	)
	(zone
		(layers "B.Cu" "In11.Cu" "In13.Cu" "In15.Cu")
		(hatch none 0.5)
		(connect_pads
			(clearance 0)
		)
		(min_thickness 0.25)
		(keepout
			(tracks not_allowed)
			(vias allowed)
			(pads allowed)
			(copperpour not_allowed)
			(footprints allowed)
		)
		(placement
			(enabled no)
			(sheetname "")
		)
		(fill yes
			(thermal_gap 0.5)
			(thermal_bridge_width 0.5)
			(island_removal_mode 0)
		)
		(polygon
			(pts
				(arc
					(start 127.003556 -239.0394)
					(mid 126.350776 -239.0394)
					(end 127.003556 -239.0394)
				)
			)
		)
	)
	(zone
		(layers "B.Cu" "In11.Cu" "In13.Cu" "In15.Cu")
		(hatch none 0.5)
		(connect_pads
			(clearance 0)
		)
		(min_thickness 0.25)
		(keepout
			(tracks not_allowed)
			(vias allowed)
			(pads allowed)
			(copperpour not_allowed)
			(footprints allowed)
		)
		(placement
			(enabled no)
			(sheetname "")
		)
		(fill yes
			(thermal_gap 0.5)
			(thermal_bridge_width 0.5)
			(island_removal_mode 0)
		)
		(polygon
			(pts
				(arc
					(start 165.601904 -410.030168)
					(mid 164.898324 -410.030168)
					(end 165.601904 -410.030168)
				)
			)
		)
	)
	(zone
		(layers "B.Cu" "In11.Cu" "In13.Cu" "In15.Cu")
		(hatch none 0.5)
		(connect_pads
			(clearance 0)
		)
		(min_thickness 0.25)
		(keepout
			(tracks not_allowed)
			(vias allowed)
			(pads allowed)
			(copperpour not_allowed)
			(footprints allowed)
		)
		(placement
			(enabled no)
			(sheetname "")
		)
		(fill yes
			(thermal_gap 0.5)
			(thermal_bridge_width 0.5)
			(island_removal_mode 0)
		)
		(polygon
			(pts
				(arc
					(start 346.859606 -253.919736)
					(mid 346.206826 -253.919736)
					(end 346.859606 -253.919736)
				)
			)
		)
	)
	(zone
		(layers "B.Cu" "In11.Cu" "In13.Cu" "In15.Cu")
		(hatch none 0.5)
		(connect_pads
			(clearance 0)
		)
		(min_thickness 0.25)
		(keepout
			(tracks not_allowed)
			(vias allowed)
			(pads allowed)
			(copperpour not_allowed)
			(footprints allowed)
		)
		(placement
			(enabled no)
			(sheetname "")
		)
		(fill yes
			(thermal_gap 0.5)
			(thermal_bridge_width 0.5)
			(island_removal_mode 0)
		)
		(polygon
			(pts
				(arc
					(start 344.980006 -263.686544)
					(mid 344.327226 -263.686544)
					(end 344.980006 -263.686544)
				)
			)
		)
	)
	(zone
		(layers "B.Cu" "In11.Cu" "In13.Cu" "In15.Cu")
		(hatch none 0.5)
		(connect_pads
			(clearance 0)
		)
		(min_thickness 0.25)
		(keepout
			(tracks not_allowed)
			(vias allowed)
			(pads allowed)
			(copperpour not_allowed)
			(footprints allowed)
		)
		(placement
			(enabled no)
			(sheetname "")
		)
		(fill yes
			(thermal_gap 0.5)
			(thermal_bridge_width 0.5)
			(island_removal_mode 0)
		)
		(polygon
			(pts
				(arc
					(start 280.143204 -227.91674)
					(mid 279.490424 -227.91674)
					(end 280.143204 -227.91674)
				)
			)
		)
	)
	(zone
		(layers "B.Cu" "In11.Cu" "In13.Cu" "In15.Cu")
		(hatch none 0.5)
		(connect_pads
			(clearance 0)
		)
		(min_thickness 0.25)
		(keepout
			(tracks not_allowed)
			(vias allowed)
			(pads allowed)
			(copperpour not_allowed)
			(footprints allowed)
		)
		(placement
			(enabled no)
			(sheetname "")
		)
		(fill yes
			(thermal_gap 0.5)
			(thermal_bridge_width 0.5)
			(island_removal_mode 0)
		)
		(polygon
			(pts
				(arc
					(start 344.040206 -263.686544)
					(mid 343.387426 -263.686544)
					(end 344.040206 -263.686544)
				)
			)
		)
	)
	(zone
		(layers "B.Cu" "In11.Cu" "In13.Cu" "In15.Cu")
		(hatch none 0.5)
		(connect_pads
			(clearance 0)
		)
		(min_thickness 0.25)
		(keepout
			(tracks not_allowed)
			(vias allowed)
			(pads allowed)
			(copperpour not_allowed)
			(footprints allowed)
		)
		(placement
			(enabled no)
			(sheetname "")
		)
		(fill yes
			(thermal_gap 0.5)
			(thermal_bridge_width 0.5)
			(island_removal_mode 0)
		)
		(polygon
			(pts
				(arc
					(start 126.643384 -262.872474)
					(mid 125.990604 -262.872474)
					(end 126.643384 -262.872474)
				)
			)
		)
	)
	(zone
		(layers "B.Cu" "In11.Cu" "In13.Cu" "In15.Cu")
		(hatch none 0.5)
		(connect_pads
			(clearance 0)
		)
		(min_thickness 0.25)
		(keepout
			(tracks not_allowed)
			(vias allowed)
			(pads allowed)
			(copperpour not_allowed)
			(footprints allowed)
		)
		(placement
			(enabled no)
			(sheetname "")
		)
		(fill yes
			(thermal_gap 0.5)
			(thermal_bridge_width 0.5)
			(island_removal_mode 0)
		)
		(polygon
			(pts
				(arc
					(start 128.993138 -271.825212)
					(mid 128.340358 -271.825212)
					(end 128.993138 -271.825212)
				)
			)
		)
	)
	(zone
		(layers "B.Cu" "In11.Cu" "In13.Cu" "In15.Cu")
		(hatch none 0.5)
		(connect_pads
			(clearance 0)
		)
		(min_thickness 0.25)
		(keepout
			(tracks not_allowed)
			(vias allowed)
			(pads allowed)
			(copperpour not_allowed)
			(footprints allowed)
		)
		(placement
			(enabled no)
			(sheetname "")
		)
		(fill yes
			(thermal_gap 0.5)
			(thermal_bridge_width 0.5)
			(island_removal_mode 0)
		)
		(polygon
			(pts
				(arc
					(start 102.568756 -248.806208)
					(mid 101.915976 -248.806208)
					(end 102.568756 -248.806208)
				)
			)
		)
	)
	(zone
		(layers "B.Cu" "In11.Cu" "In13.Cu" "In15.Cu")
		(hatch none 0.5)
		(connect_pads
			(clearance 0)
		)
		(min_thickness 0.25)
		(keepout
			(tracks not_allowed)
			(vias allowed)
			(pads allowed)
			(copperpour not_allowed)
			(footprints allowed)
		)
		(placement
			(enabled no)
			(sheetname "")
		)
		(fill yes
			(thermal_gap 0.5)
			(thermal_bridge_width 0.5)
			(island_removal_mode 0)
		)
		(polygon
			(pts
				(arc
					(start 436.150004 -244.066568)
					(mid 435.497224 -244.066568)
					(end 436.150004 -244.066568)
				)
			)
		)
	)
	(zone
		(layers "B.Cu" "In11.Cu" "In13.Cu" "In15.Cu")
		(hatch none 0.5)
		(connect_pads
			(clearance 0)
		)
		(min_thickness 0.25)
		(keepout
			(tracks not_allowed)
			(vias allowed)
			(pads allowed)
			(copperpour not_allowed)
			(footprints allowed)
		)
		(placement
			(enabled no)
			(sheetname "")
		)
		(fill yes
			(thermal_gap 0.5)
			(thermal_bridge_width 0.5)
			(island_removal_mode 0)
		)
		(polygon
			(pts
				(arc
					(start 373.12092 -410.030168)
					(mid 372.41734 -410.030168)
					(end 373.12092 -410.030168)
				)
			)
		)
	)
	(zone
		(layers "B.Cu" "In11.Cu" "In13.Cu" "In15.Cu")
		(hatch none 0.5)
		(connect_pads
			(clearance 0)
		)
		(min_thickness 0.25)
		(keepout
			(tracks not_allowed)
			(vias allowed)
			(pads allowed)
			(copperpour not_allowed)
			(footprints allowed)
		)
		(placement
			(enabled no)
			(sheetname "")
		)
		(fill yes
			(thermal_gap 0.5)
			(thermal_bridge_width 0.5)
			(island_removal_mode 0)
		)
		(polygon
			(pts
				(arc
					(start 443.693804 -244.066568)
					(mid 443.041024 -244.066568)
					(end 443.693804 -244.066568)
				)
			)
		)
	)
	(zone
		(layers "B.Cu" "In11.Cu" "In13.Cu" "In15.Cu")
		(hatch none 0.5)
		(connect_pads
			(clearance 0)
		)
		(min_thickness 0.25)
		(keepout
			(tracks not_allowed)
			(vias allowed)
			(pads allowed)
			(copperpour not_allowed)
			(footprints allowed)
		)
		(placement
			(enabled no)
			(sheetname "")
		)
		(fill yes
			(thermal_gap 0.5)
			(thermal_bridge_width 0.5)
			(island_removal_mode 0)
		)
		(polygon
			(pts
				(arc
					(start 86.054946 -435.489858)
					(mid 85.245194 -435.489858)
					(end 86.054946 -435.489858)
				)
			)
		)
	)
	(zone
		(layers "B.Cu" "In11.Cu" "In13.Cu" "In15.Cu")
		(hatch none 0.5)
		(connect_pads
			(clearance 0)
		)
		(min_thickness 0.25)
		(keepout
			(tracks not_allowed)
			(vias allowed)
			(pads allowed)
			(copperpour not_allowed)
			(footprints allowed)
		)
		(placement
			(enabled no)
			(sheetname "")
		)
		(fill yes
			(thermal_gap 0.5)
			(thermal_bridge_width 0.5)
			(island_removal_mode 0)
		)
		(polygon
			(pts
				(arc
					(start 147.1549 -436.889906)
					(mid 146.345148 -436.889906)
					(end 147.1549 -436.889906)
				)
			)
		)
	)
	(zone
		(layers "B.Cu" "In11.Cu" "In13.Cu" "In15.Cu")
		(hatch none 0.5)
		(connect_pads
			(clearance 0)
		)
		(min_thickness 0.25)
		(keepout
			(tracks not_allowed)
			(vias allowed)
			(pads allowed)
			(copperpour not_allowed)
			(footprints allowed)
		)
		(placement
			(enabled no)
			(sheetname "")
		)
		(fill yes
			(thermal_gap 0.5)
			(thermal_bridge_width 0.5)
			(island_removal_mode 0)
		)
		(polygon
			(pts
				(arc
					(start 82.054954 -428.28972)
					(mid 81.245202 -428.28972)
					(end 82.054954 -428.28972)
				)
			)
		)
	)
	(zone
		(layers "B.Cu" "In11.Cu" "In13.Cu" "In15.Cu")
		(hatch none 0.5)
		(connect_pads
			(clearance 0)
		)
		(min_thickness 0.25)
		(keepout
			(tracks not_allowed)
			(vias allowed)
			(pads allowed)
			(copperpour not_allowed)
			(footprints allowed)
		)
		(placement
			(enabled no)
			(sheetname "")
		)
		(fill yes
			(thermal_gap 0.5)
			(thermal_bridge_width 0.5)
			(island_removal_mode 0)
		)
		(polygon
			(pts
				(arc
					(start 36.303204 -218.566746)
					(mid 35.650424 -218.566746)
					(end 36.303204 -218.566746)
				)
			)
		)
	)
	(zone
		(layers "B.Cu" "In11.Cu" "In13.Cu" "In15.Cu")
		(hatch none 0.5)
		(connect_pads
			(clearance 0)
		)
		(min_thickness 0.25)
		(keepout
			(tracks not_allowed)
			(vias allowed)
			(pads allowed)
			(copperpour not_allowed)
			(footprints allowed)
		)
		(placement
			(enabled no)
			(sheetname "")
		)
		(fill yes
			(thermal_gap 0.5)
			(thermal_bridge_width 0.5)
			(island_removal_mode 0)
		)
		(polygon
			(pts
				(arc
					(start 352.465132 -68.24218)
					(mid 351.761552 -68.24218)
					(end 352.465132 -68.24218)
				)
			)
		)
	)
	(zone
		(layers "B.Cu" "In11.Cu" "In13.Cu" "In15.Cu")
		(hatch none 0.5)
		(connect_pads
			(clearance 0)
		)
		(min_thickness 0.25)
		(keepout
			(tracks not_allowed)
			(vias allowed)
			(pads allowed)
			(copperpour not_allowed)
			(footprints allowed)
		)
		(placement
			(enabled no)
			(sheetname "")
		)
		(fill yes
			(thermal_gap 0.5)
			(thermal_bridge_width 0.5)
			(island_removal_mode 0)
		)
		(polygon
			(pts
				(arc
					(start 280.143204 -303.566576)
					(mid 279.490424 -303.566576)
					(end 280.143204 -303.566576)
				)
			)
		)
	)
	(zone
		(layers "B.Cu" "In11.Cu" "In13.Cu" "In15.Cu")
		(hatch none 0.5)
		(connect_pads
			(clearance 0)
		)
		(min_thickness 0.25)
		(keepout
			(tracks not_allowed)
			(vias allowed)
			(pads allowed)
			(copperpour not_allowed)
			(footprints allowed)
		)
		(placement
			(enabled no)
			(sheetname "")
		)
		(fill yes
			(thermal_gap 0.5)
			(thermal_bridge_width 0.5)
			(island_removal_mode 0)
		)
		(polygon
			(pts
				(arc
					(start 376.823224 -234.15625)
					(mid 376.170444 -234.15625)
					(end 376.823224 -234.15625)
				)
			)
		)
	)
	(zone
		(layers "B.Cu" "In11.Cu" "In13.Cu" "In15.Cu")
		(hatch none 0.5)
		(connect_pads
			(clearance 0)
		)
		(min_thickness 0.25)
		(keepout
			(tracks not_allowed)
			(vias allowed)
			(pads allowed)
			(copperpour not_allowed)
			(footprints allowed)
		)
		(placement
			(enabled no)
			(sheetname "")
		)
		(fill yes
			(thermal_gap 0.5)
			(thermal_bridge_width 0.5)
			(island_removal_mode 0)
		)
		(polygon
			(pts
				(arc
					(start 280.143204 -306.96662)
					(mid 279.490424 -306.96662)
					(end 280.143204 -306.96662)
				)
			)
		)
	)
	(zone
		(layers "B.Cu" "In11.Cu" "In13.Cu" "In15.Cu")
		(hatch none 0.5)
		(connect_pads
			(clearance 0)
		)
		(min_thickness 0.25)
		(keepout
			(tracks not_allowed)
			(vias allowed)
			(pads allowed)
			(copperpour not_allowed)
			(footprints allowed)
		)
		(placement
			(enabled no)
			(sheetname "")
		)
		(fill yes
			(thermal_gap 0.5)
			(thermal_bridge_width 0.5)
			(island_removal_mode 0)
		)
		(polygon
			(pts
				(arc
					(start 203.297536 -243.216684)
					(mid 202.644756 -243.216684)
					(end 203.297536 -243.216684)
				)
			)
		)
	)
	(zone
		(layers "B.Cu" "In11.Cu" "In13.Cu" "In15.Cu")
		(hatch none 0.5)
		(connect_pads
			(clearance 0)
		)
		(min_thickness 0.25)
		(keepout
			(tracks not_allowed)
			(vias allowed)
			(pads allowed)
			(copperpour not_allowed)
			(footprints allowed)
		)
		(placement
			(enabled no)
			(sheetname "")
		)
		(fill yes
			(thermal_gap 0.5)
			(thermal_bridge_width 0.5)
			(island_removal_mode 0)
		)
		(polygon
			(pts
				(arc
					(start 249.500136 -4.2672)
					(mid 248.796556 -4.2672)
					(end 249.500136 -4.2672)
				)
			)
		)
	)
	(zone
		(layers "B.Cu" "In11.Cu" "In13.Cu" "In15.Cu")
		(hatch none 0.5)
		(connect_pads
			(clearance 0)
		)
		(min_thickness 0.25)
		(keepout
			(tracks not_allowed)
			(vias allowed)
			(pads allowed)
			(copperpour not_allowed)
			(footprints allowed)
		)
		(placement
			(enabled no)
			(sheetname "")
		)
		(fill yes
			(thermal_gap 0.5)
			(thermal_bridge_width 0.5)
			(island_removal_mode 0)
		)
		(polygon
			(pts
				(arc
					(start 344.870024 -240.667286)
					(mid 344.217244 -240.667286)
					(end 344.870024 -240.667286)
				)
			)
		)
	)
	(zone
		(layers "B.Cu" "In11.Cu" "In13.Cu" "In15.Cu")
		(hatch none 0.5)
		(connect_pads
			(clearance 0)
		)
		(min_thickness 0.25)
		(keepout
			(tracks not_allowed)
			(vias allowed)
			(pads allowed)
			(copperpour not_allowed)
			(footprints allowed)
		)
		(placement
			(enabled no)
			(sheetname "")
		)
		(fill yes
			(thermal_gap 0.5)
			(thermal_bridge_width 0.5)
			(island_removal_mode 0)
		)
		(polygon
			(pts
				(arc
					(start 114.785902 -214.622634)
					(mid 114.133122 -214.622634)
					(end 114.785902 -214.622634)
				)
			)
		)
	)
	(zone
		(layers "B.Cu" "In11.Cu" "In13.Cu" "In15.Cu")
		(hatch none 0.5)
		(connect_pads
			(clearance 0)
		)
		(min_thickness 0.25)
		(keepout
			(tracks not_allowed)
			(vias allowed)
			(pads allowed)
			(copperpour not_allowed)
			(footprints allowed)
		)
		(placement
			(enabled no)
			(sheetname "")
		)
		(fill yes
			(thermal_gap 0.5)
			(thermal_bridge_width 0.5)
			(island_removal_mode 0)
		)
		(polygon
			(pts
				(arc
					(start 351.888298 -50.207672)
					(mid 351.184718 -50.207672)
					(end 351.888298 -50.207672)
				)
			)
		)
	)
	(zone
		(layers "B.Cu" "In11.Cu" "In13.Cu" "In15.Cu")
		(hatch none 0.5)
		(connect_pads
			(clearance 0)
		)
		(min_thickness 0.25)
		(keepout
			(tracks not_allowed)
			(vias allowed)
			(pads allowed)
			(copperpour not_allowed)
			(footprints allowed)
		)
		(placement
			(enabled no)
			(sheetname "")
		)
		(fill yes
			(thermal_gap 0.5)
			(thermal_bridge_width 0.5)
			(island_removal_mode 0)
		)
		(polygon
			(pts
				(arc
					(start 399.154904 -436.889906)
					(mid 398.345152 -436.889906)
					(end 399.154904 -436.889906)
				)
			)
		)
	)
	(zone
		(layers "B.Cu" "In11.Cu" "In13.Cu" "In15.Cu")
		(hatch none 0.5)
		(connect_pads
			(clearance 0)
		)
		(min_thickness 0.25)
		(keepout
			(tracks not_allowed)
			(vias allowed)
			(pads allowed)
			(copperpour not_allowed)
			(footprints allowed)
		)
		(placement
			(enabled no)
			(sheetname "")
		)
		(fill yes
			(thermal_gap 0.5)
			(thermal_bridge_width 0.5)
			(island_removal_mode 0)
		)
		(polygon
			(pts
				(arc
					(start 350.038924 -213.732618)
					(mid 349.386144 -213.732618)
					(end 350.038924 -213.732618)
				)
			)
		)
	)
	(zone
		(layers "B.Cu" "In11.Cu" "In13.Cu" "In15.Cu")
		(hatch none 0.5)
		(connect_pads
			(clearance 0)
		)
		(min_thickness 0.25)
		(keepout
			(tracks not_allowed)
			(vias allowed)
			(pads allowed)
			(copperpour not_allowed)
			(footprints allowed)
		)
		(placement
			(enabled no)
			(sheetname "")
		)
		(fill yes
			(thermal_gap 0.5)
			(thermal_bridge_width 0.5)
			(island_removal_mode 0)
		)
		(polygon
			(pts
				(arc
					(start 455.337672 -204.96657)
					(mid 454.684892 -204.96657)
					(end 455.337672 -204.96657)
				)
			)
		)
	)
	(zone
		(layers "B.Cu" "In11.Cu" "In13.Cu" "In15.Cu")
		(hatch none 0.5)
		(connect_pads
			(clearance 0)
		)
		(min_thickness 0.25)
		(keepout
			(tracks not_allowed)
			(vias allowed)
			(pads allowed)
			(copperpour not_allowed)
			(footprints allowed)
		)
		(placement
			(enabled no)
			(sheetname "")
		)
		(fill yes
			(thermal_gap 0.5)
			(thermal_bridge_width 0.5)
			(island_removal_mode 0)
		)
		(polygon
			(pts
				(arc
					(start 350.508316 -214.622634)
					(mid 349.855536 -214.622634)
					(end 350.508316 -214.622634)
				)
			)
		)
	)
	(zone
		(layers "B.Cu" "In11.Cu" "In13.Cu" "In15.Cu")
		(hatch none 0.5)
		(connect_pads
			(clearance 0)
		)
		(min_thickness 0.25)
		(keepout
			(tracks not_allowed)
			(vias allowed)
			(pads allowed)
			(copperpour not_allowed)
			(footprints allowed)
		)
		(placement
			(enabled no)
			(sheetname "")
		)
		(fill yes
			(thermal_gap 0.5)
			(thermal_bridge_width 0.5)
			(island_removal_mode 0)
		)
		(polygon
			(pts
				(arc
					(start 365.545624 -227.64496)
					(mid 364.892844 -227.64496)
					(end 365.545624 -227.64496)
				)
			)
		)
	)
	(zone
		(layers "B.Cu" "In11.Cu" "In13.Cu" "In15.Cu")
		(hatch none 0.5)
		(connect_pads
			(clearance 0)
		)
		(min_thickness 0.25)
		(keepout
			(tracks not_allowed)
			(vias allowed)
			(pads allowed)
			(copperpour not_allowed)
			(footprints allowed)
		)
		(placement
			(enabled no)
			(sheetname "")
		)
		(fill yes
			(thermal_gap 0.5)
			(thermal_bridge_width 0.5)
			(island_removal_mode 0)
		)
		(polygon
			(pts
				(arc
					(start 136.154922 -431.889916)
					(mid 135.34517 -431.889916)
					(end 136.154922 -431.889916)
				)
			)
		)
	)
	(zone
		(layers "B.Cu" "In11.Cu" "In13.Cu" "In15.Cu")
		(hatch none 0.5)
		(connect_pads
			(clearance 0)
		)
		(min_thickness 0.25)
		(keepout
			(tracks not_allowed)
			(vias allowed)
			(pads allowed)
			(copperpour not_allowed)
			(footprints allowed)
		)
		(placement
			(enabled no)
			(sheetname "")
		)
		(fill yes
			(thermal_gap 0.5)
			(thermal_bridge_width 0.5)
			(island_removal_mode 0)
		)
		(polygon
			(pts
				(arc
					(start 392.154918 -430.689766)
					(mid 391.345166 -430.689766)
					(end 392.154918 -430.689766)
				)
			)
		)
	)
	(zone
		(layers "B.Cu" "In11.Cu" "In13.Cu" "In15.Cu")
		(hatch none 0.5)
		(connect_pads
			(clearance 0)
		)
		(min_thickness 0.25)
		(keepout
			(tracks not_allowed)
			(vias allowed)
			(pads allowed)
			(copperpour not_allowed)
			(footprints allowed)
		)
		(placement
			(enabled no)
			(sheetname "")
		)
		(fill yes
			(thermal_gap 0.5)
			(thermal_bridge_width 0.5)
			(island_removal_mode 0)
		)
		(polygon
			(pts
				(arc
					(start 335.112106 -284.033722)
					(mid 334.459326 -284.033722)
					(end 335.112106 -284.033722)
				)
			)
		)
	)
	(zone
		(layers "B.Cu" "In11.Cu" "In13.Cu" "In15.Cu")
		(hatch none 0.5)
		(connect_pads
			(clearance 0)
		)
		(min_thickness 0.25)
		(keepout
			(tracks not_allowed)
			(vias allowed)
			(pads allowed)
			(copperpour not_allowed)
			(footprints allowed)
		)
		(placement
			(enabled no)
			(sheetname "")
		)
		(fill yes
			(thermal_gap 0.5)
			(thermal_bridge_width 0.5)
			(island_removal_mode 0)
		)
		(polygon
			(pts
				(arc
					(start 350.441514 -179.224432)
					(mid 349.737934 -179.224432)
					(end 350.441514 -179.224432)
				)
			)
		)
	)
	(zone
		(layers "B.Cu" "In11.Cu" "In13.Cu" "In15.Cu")
		(hatch none 0.5)
		(connect_pads
			(clearance 0)
		)
		(min_thickness 0.25)
		(keepout
			(tracks not_allowed)
			(vias allowed)
			(pads allowed)
			(copperpour not_allowed)
			(footprints allowed)
		)
		(placement
			(enabled no)
			(sheetname "")
		)
		(fill yes
			(thermal_gap 0.5)
			(thermal_bridge_width 0.5)
			(island_removal_mode 0)
		)
		(polygon
			(pts
				(arc
					(start 96.929956 -242.294918)
					(mid 96.277176 -242.294918)
					(end 96.929956 -242.294918)
				)
			)
		)
	)
	(zone
		(layers "B.Cu" "In11.Cu" "In13.Cu" "In15.Cu")
		(hatch none 0.5)
		(connect_pads
			(clearance 0)
		)
		(min_thickness 0.25)
		(keepout
			(tracks not_allowed)
			(vias allowed)
			(pads allowed)
			(copperpour not_allowed)
			(footprints allowed)
		)
		(placement
			(enabled no)
			(sheetname "")
		)
		(fill yes
			(thermal_gap 0.5)
			(thermal_bridge_width 0.5)
			(island_removal_mode 0)
		)
		(polygon
			(pts
				(arc
					(start 280.143204 -284.866588)
					(mid 279.490424 -284.866588)
					(end 280.143204 -284.866588)
				)
			)
		)
	)
	(zone
		(layers "B.Cu" "In11.Cu" "In13.Cu" "In15.Cu")
		(hatch none 0.5)
		(connect_pads
			(clearance 0)
		)
		(min_thickness 0.25)
		(keepout
			(tracks not_allowed)
			(vias allowed)
			(pads allowed)
			(copperpour not_allowed)
			(footprints allowed)
		)
		(placement
			(enabled no)
			(sheetname "")
		)
		(fill yes
			(thermal_gap 0.5)
			(thermal_bridge_width 0.5)
			(island_removal_mode 0)
		)
		(polygon
			(pts
				(arc
					(start 440.250072 -199.01662)
					(mid 439.597292 -199.01662)
					(end 440.250072 -199.01662)
				)
			)
		)
	)
	(zone
		(layers "B.Cu" "In11.Cu" "In13.Cu" "In15.Cu")
		(hatch none 0.5)
		(connect_pads
			(clearance 0)
		)
		(min_thickness 0.25)
		(keepout
			(tracks not_allowed)
			(vias allowed)
			(pads allowed)
			(copperpour not_allowed)
			(footprints allowed)
		)
		(placement
			(enabled no)
			(sheetname "")
		)
		(fill yes
			(thermal_gap 0.5)
			(thermal_bridge_width 0.5)
			(island_removal_mode 0)
		)
		(polygon
			(pts
				(arc
					(start 321.054984 -428.28972)
					(mid 320.245232 -428.28972)
					(end 321.054984 -428.28972)
				)
			)
		)
	)
	(zone
		(layers "B.Cu" "In11.Cu" "In13.Cu" "In15.Cu")
		(hatch none 0.5)
		(connect_pads
			(clearance 0)
		)
		(min_thickness 0.25)
		(keepout
			(tracks not_allowed)
			(vias allowed)
			(pads allowed)
			(copperpour not_allowed)
			(footprints allowed)
		)
		(placement
			(enabled no)
			(sheetname "")
		)
		(fill yes
			(thermal_gap 0.5)
			(thermal_bridge_width 0.5)
			(island_removal_mode 0)
		)
		(polygon
			(pts
				(arc
					(start 104.558338 -275.08073)
					(mid 103.905558 -275.08073)
					(end 104.558338 -275.08073)
				)
			)
		)
	)
	(zone
		(layers "B.Cu" "In11.Cu" "In13.Cu" "In15.Cu")
		(hatch none 0.5)
		(connect_pads
			(clearance 0)
		)
		(min_thickness 0.25)
		(keepout
			(tracks not_allowed)
			(vias allowed)
			(pads allowed)
			(copperpour not_allowed)
			(footprints allowed)
		)
		(placement
			(enabled no)
			(sheetname "")
		)
		(fill yes
			(thermal_gap 0.5)
			(thermal_bridge_width 0.5)
			(island_removal_mode 0)
		)
		(polygon
			(pts
				(arc
					(start 230.84917 -54.70652)
					(mid 230.14559 -54.70652)
					(end 230.84917 -54.70652)
				)
			)
		)
	)
	(zone
		(layers "B.Cu" "In11.Cu" "In13.Cu" "In15.Cu")
		(hatch none 0.5)
		(connect_pads
			(clearance 0)
		)
		(min_thickness 0.25)
		(keepout
			(tracks not_allowed)
			(vias allowed)
			(pads allowed)
			(copperpour not_allowed)
			(footprints allowed)
		)
		(placement
			(enabled no)
			(sheetname "")
		)
		(fill yes
			(thermal_gap 0.5)
			(thermal_bridge_width 0.5)
			(island_removal_mode 0)
		)
		(polygon
			(pts
				(arc
					(start 344.040206 -253.919736)
					(mid 343.387426 -253.919736)
					(end 344.040206 -253.919736)
				)
			)
		)
	)
	(zone
		(layers "B.Cu" "In11.Cu" "In13.Cu" "In15.Cu")
		(hatch none 0.5)
		(connect_pads
			(clearance 0)
		)
		(min_thickness 0.25)
		(keepout
			(tracks not_allowed)
			(vias allowed)
			(pads allowed)
			(copperpour not_allowed)
			(footprints allowed)
		)
		(placement
			(enabled no)
			(sheetname "")
		)
		(fill yes
			(thermal_gap 0.5)
			(thermal_bridge_width 0.5)
			(island_removal_mode 0)
		)
		(polygon
			(pts
				(arc
					(start 343.46007 -226.831144)
					(mid 342.80729 -226.831144)
					(end 343.46007 -226.831144)
				)
			)
		)
	)
	(zone
		(layers "B.Cu" "In11.Cu" "In13.Cu" "In15.Cu")
		(hatch none 0.5)
		(connect_pads
			(clearance 0)
		)
		(min_thickness 0.25)
		(keepout
			(tracks not_allowed)
			(vias allowed)
			(pads allowed)
			(copperpour not_allowed)
			(footprints allowed)
		)
		(placement
			(enabled no)
			(sheetname "")
		)
		(fill yes
			(thermal_gap 0.5)
			(thermal_bridge_width 0.5)
			(island_removal_mode 0)
		)
		(polygon
			(pts
				(arc
					(start 127.473202 -236.597952)
					(mid 126.820422 -236.597952)
					(end 127.473202 -236.597952)
				)
			)
		)
	)
	(zone
		(layers "B.Cu" "In11.Cu" "In13.Cu" "In15.Cu")
		(hatch none 0.5)
		(connect_pads
			(clearance 0)
		)
		(min_thickness 0.25)
		(keepout
			(tracks not_allowed)
			(vias allowed)
			(pads allowed)
			(copperpour not_allowed)
			(footprints allowed)
		)
		(placement
			(enabled no)
			(sheetname "")
		)
		(fill yes
			(thermal_gap 0.5)
			(thermal_bridge_width 0.5)
			(island_removal_mode 0)
		)
		(polygon
			(pts
				(arc
					(start 89.521538 -281.59202)
					(mid 88.868758 -281.59202)
					(end 89.521538 -281.59202)
				)
			)
		)
	)
	(zone
		(layers "B.Cu" "In11.Cu" "In13.Cu" "In15.Cu")
		(hatch none 0.5)
		(connect_pads
			(clearance 0)
		)
		(min_thickness 0.25)
		(keepout
			(tracks not_allowed)
			(vias allowed)
			(pads allowed)
			(copperpour not_allowed)
			(footprints allowed)
		)
		(placement
			(enabled no)
			(sheetname "")
		)
		(fill yes
			(thermal_gap 0.5)
			(thermal_bridge_width 0.5)
			(island_removal_mode 0)
		)
		(polygon
			(pts
				(arc
					(start 130.402584 -254.733552)
					(mid 129.749804 -254.733552)
					(end 130.402584 -254.733552)
				)
			)
		)
	)
	(zone
		(layers "B.Cu" "In11.Cu" "In13.Cu" "In15.Cu")
		(hatch none 0.5)
		(connect_pads
			(clearance 0)
		)
		(min_thickness 0.25)
		(keepout
			(tracks not_allowed)
			(vias allowed)
			(pads allowed)
			(copperpour not_allowed)
			(footprints allowed)
		)
		(placement
			(enabled no)
			(sheetname "")
		)
		(fill yes
			(thermal_gap 0.5)
			(thermal_bridge_width 0.5)
			(island_removal_mode 0)
		)
		(polygon
			(pts
				(arc
					(start 349.517462 -182.805832)
					(mid 348.813882 -182.805832)
					(end 349.517462 -182.805832)
				)
			)
		)
	)
	(zone
		(layers "B.Cu" "In11.Cu" "In13.Cu" "In15.Cu")
		(hatch none 0.5)
		(connect_pads
			(clearance 0)
		)
		(min_thickness 0.25)
		(keepout
			(tracks not_allowed)
			(vias allowed)
			(pads allowed)
			(copperpour not_allowed)
			(footprints allowed)
		)
		(placement
			(enabled no)
			(sheetname "")
		)
		(fill yes
			(thermal_gap 0.5)
			(thermal_bridge_width 0.5)
			(island_removal_mode 0)
		)
		(polygon
			(pts
				(arc
					(start 107.847384 -275.8948)
					(mid 107.194604 -275.8948)
					(end 107.847384 -275.8948)
				)
			)
		)
	)
	(zone
		(layers "B.Cu" "In11.Cu" "In13.Cu" "In15.Cu")
		(hatch none 0.5)
		(connect_pads
			(clearance 0)
		)
		(min_thickness 0.25)
		(keepout
			(tracks not_allowed)
			(vias allowed)
			(pads allowed)
			(copperpour not_allowed)
			(footprints allowed)
		)
		(placement
			(enabled no)
			(sheetname "")
		)
		(fill yes
			(thermal_gap 0.5)
			(thermal_bridge_width 0.5)
			(island_removal_mode 0)
		)
		(polygon
			(pts
				(arc
					(start 347.329252 -254.733552)
					(mid 346.676472 -254.733552)
					(end 347.329252 -254.733552)
				)
			)
		)
	)
	(zone
		(layers "B.Cu" "In11.Cu" "In13.Cu" "In15.Cu")
		(hatch none 0.5)
		(connect_pads
			(clearance 0)
		)
		(min_thickness 0.25)
		(keepout
			(tracks not_allowed)
			(vias allowed)
			(pads allowed)
			(copperpour not_allowed)
			(footprints allowed)
		)
		(placement
			(enabled no)
			(sheetname "")
		)
		(fill yes
			(thermal_gap 0.5)
			(thermal_bridge_width 0.5)
			(island_removal_mode 0)
		)
		(polygon
			(pts
				(arc
					(start 376.35307 -234.970066)
					(mid 375.70029 -234.970066)
					(end 376.35307 -234.970066)
				)
			)
		)
	)
	(zone
		(layers "B.Cu" "In11.Cu" "In13.Cu" "In15.Cu")
		(hatch none 0.5)
		(connect_pads
			(clearance 0)
		)
		(min_thickness 0.25)
		(keepout
			(tracks not_allowed)
			(vias allowed)
			(pads allowed)
			(copperpour not_allowed)
			(footprints allowed)
		)
		(placement
			(enabled no)
			(sheetname "")
		)
		(fill yes
			(thermal_gap 0.5)
			(thermal_bridge_width 0.5)
			(island_removal_mode 0)
		)
		(polygon
			(pts
				(arc
					(start 95.629984 -254.733552)
					(mid 94.977204 -254.733552)
					(end 95.629984 -254.733552)
				)
			)
		)
	)
	(zone
		(layers "B.Cu" "In11.Cu" "In13.Cu" "In15.Cu")
		(hatch none 0.5)
		(connect_pads
			(clearance 0)
		)
		(min_thickness 0.25)
		(keepout
			(tracks not_allowed)
			(vias allowed)
			(pads allowed)
			(copperpour not_allowed)
			(footprints allowed)
		)
		(placement
			(enabled no)
			(sheetname "")
		)
		(fill yes
			(thermal_gap 0.5)
			(thermal_bridge_width 0.5)
			(island_removal_mode 0)
		)
		(polygon
			(pts
				(arc
					(start 17.115536 -245.76659)
					(mid 16.462756 -245.76659)
					(end 17.115536 -245.76659)
				)
			)
		)
	)
	(zone
		(layers "B.Cu" "In11.Cu" "In13.Cu" "In15.Cu")
		(hatch none 0.5)
		(connect_pads
			(clearance 0)
		)
		(min_thickness 0.25)
		(keepout
			(tracks not_allowed)
			(vias allowed)
			(pads allowed)
			(copperpour not_allowed)
			(footprints allowed)
		)
		(placement
			(enabled no)
			(sheetname "")
		)
		(fill yes
			(thermal_gap 0.5)
			(thermal_bridge_width 0.5)
			(island_removal_mode 0)
		)
		(polygon
			(pts
				(arc
					(start 92.563188 -410.030168)
					(mid 91.859608 -410.030168)
					(end 92.563188 -410.030168)
				)
			)
		)
	)
	(zone
		(layers "B.Cu" "In11.Cu" "In13.Cu" "In15.Cu")
		(hatch none 0.5)
		(connect_pads
			(clearance 0)
		)
		(min_thickness 0.25)
		(keepout
			(tracks not_allowed)
			(vias allowed)
			(pads allowed)
			(copperpour not_allowed)
			(footprints allowed)
		)
		(placement
			(enabled no)
			(sheetname "")
		)
		(fill yes
			(thermal_gap 0.5)
			(thermal_bridge_width 0.5)
			(island_removal_mode 0)
		)
		(polygon
			(pts
				(arc
					(start 319.054988 -433.289964)
					(mid 318.245236 -433.289964)
					(end 319.054988 -433.289964)
				)
			)
		)
	)
	(zone
		(layers "B.Cu" "In11.Cu" "In13.Cu" "In15.Cu")
		(hatch none 0.5)
		(connect_pads
			(clearance 0)
		)
		(min_thickness 0.25)
		(keepout
			(tracks not_allowed)
			(vias allowed)
			(pads allowed)
			(copperpour not_allowed)
			(footprints allowed)
		)
		(placement
			(enabled no)
			(sheetname "")
		)
		(fill yes
			(thermal_gap 0.5)
			(thermal_bridge_width 0.5)
			(island_removal_mode 0)
		)
		(polygon
			(pts
				(arc
					(start 32.203136 -302.716692)
					(mid 31.550356 -302.716692)
					(end 32.203136 -302.716692)
				)
			)
		)
	)
	(zone
		(layers "B.Cu" "In11.Cu" "In13.Cu" "In15.Cu")
		(hatch none 0.5)
		(connect_pads
			(clearance 0)
		)
		(min_thickness 0.25)
		(keepout
			(tracks not_allowed)
			(vias allowed)
			(pads allowed)
			(copperpour not_allowed)
			(footprints allowed)
		)
		(placement
			(enabled no)
			(sheetname "")
		)
		(fill yes
			(thermal_gap 0.5)
			(thermal_bridge_width 0.5)
			(island_removal_mode 0)
		)
		(polygon
			(pts
				(arc
					(start 32.203136 -226.216718)
					(mid 31.550356 -226.216718)
					(end 32.203136 -226.216718)
				)
			)
		)
	)
	(zone
		(layers "B.Cu" "In11.Cu" "In13.Cu" "In15.Cu")
		(hatch none 0.5)
		(connect_pads
			(clearance 0)
		)
		(min_thickness 0.25)
		(keepout
			(tracks not_allowed)
			(vias allowed)
			(pads allowed)
			(copperpour not_allowed)
			(footprints allowed)
		)
		(placement
			(enabled no)
			(sheetname "")
		)
		(fill yes
			(thermal_gap 0.5)
			(thermal_bridge_width 0.5)
			(island_removal_mode 0)
		)
		(polygon
			(pts
				(arc
					(start 147.1549 -438.089802)
					(mid 146.345148 -438.089802)
					(end 147.1549 -438.089802)
				)
			)
		)
	)
	(zone
		(layers "B.Cu" "In11.Cu" "In13.Cu" "In15.Cu")
		(hatch none 0.5)
		(connect_pads
			(clearance 0)
		)
		(min_thickness 0.25)
		(keepout
			(tracks not_allowed)
			(vias allowed)
			(pads allowed)
			(copperpour not_allowed)
			(footprints allowed)
		)
		(placement
			(enabled no)
			(sheetname "")
		)
		(fill yes
			(thermal_gap 0.5)
			(thermal_bridge_width 0.5)
			(island_removal_mode 0)
		)
		(polygon
			(pts
				(arc
					(start 128.522984 -266.128246)
					(mid 127.870204 -266.128246)
					(end 128.522984 -266.128246)
				)
			)
		)
	)
	(zone
		(layers "B.Cu" "In11.Cu" "In13.Cu" "In15.Cu")
		(hatch none 0.5)
		(connect_pads
			(clearance 0)
		)
		(min_thickness 0.25)
		(keepout
			(tracks not_allowed)
			(vias allowed)
			(pads allowed)
			(copperpour not_allowed)
			(footprints allowed)
		)
		(placement
			(enabled no)
			(sheetname "")
		)
		(fill yes
			(thermal_gap 0.5)
			(thermal_bridge_width 0.5)
			(island_removal_mode 0)
		)
		(polygon
			(pts
				(arc
					(start 145.154904 -431.889916)
					(mid 144.345152 -431.889916)
					(end 145.154904 -431.889916)
				)
			)
		)
	)
	(zone
		(layers "B.Cu" "In11.Cu" "In13.Cu" "In15.Cu")
		(hatch none 0.5)
		(connect_pads
			(clearance 0)
		)
		(min_thickness 0.25)
		(keepout
			(tracks not_allowed)
			(vias allowed)
			(pads allowed)
			(copperpour not_allowed)
			(footprints allowed)
		)
		(placement
			(enabled no)
			(sheetname "")
		)
		(fill yes
			(thermal_gap 0.5)
			(thermal_bridge_width 0.5)
			(island_removal_mode 0)
		)
		(polygon
			(pts
				(arc
					(start 376.933206 -276.708616)
					(mid 376.280426 -276.708616)
					(end 376.933206 -276.708616)
				)
			)
		)
	)
	(zone
		(layers "B.Cu" "In11.Cu" "In13.Cu" "In15.Cu")
		(hatch none 0.5)
		(connect_pads
			(clearance 0)
		)
		(min_thickness 0.25)
		(keepout
			(tracks not_allowed)
			(vias allowed)
			(pads allowed)
			(copperpour not_allowed)
			(footprints allowed)
		)
		(placement
			(enabled no)
			(sheetname "")
		)
		(fill yes
			(thermal_gap 0.5)
			(thermal_bridge_width 0.5)
			(island_removal_mode 0)
		)
		(polygon
			(pts
				(arc
					(start 451.237604 -243.216684)
					(mid 450.584824 -243.216684)
					(end 451.237604 -243.216684)
				)
			)
		)
	)
	(zone
		(layers "B.Cu" "In11.Cu" "In13.Cu" "In15.Cu")
		(hatch none 0.5)
		(connect_pads
			(clearance 0)
		)
		(min_thickness 0.25)
		(keepout
			(tracks not_allowed)
			(vias allowed)
			(pads allowed)
			(copperpour not_allowed)
			(footprints allowed)
		)
		(placement
			(enabled no)
			(sheetname "")
		)
		(fill yes
			(thermal_gap 0.5)
			(thermal_bridge_width 0.5)
			(island_removal_mode 0)
		)
		(polygon
			(pts
				(arc
					(start 386.15493 -430.889918)
					(mid 385.345178 -430.889918)
					(end 386.15493 -430.889918)
				)
			)
		)
	)
	(zone
		(layers "B.Cu" "In11.Cu" "In13.Cu" "In15.Cu")
		(hatch none 0.5)
		(connect_pads
			(clearance 0)
		)
		(min_thickness 0.25)
		(keepout
			(tracks not_allowed)
			(vias allowed)
			(pads allowed)
			(copperpour not_allowed)
			(footprints allowed)
		)
		(placement
			(enabled no)
			(sheetname "")
		)
		(fill yes
			(thermal_gap 0.5)
			(thermal_bridge_width 0.5)
			(island_removal_mode 0)
		)
		(polygon
			(pts
				(arc
					(start 155.154884 -430.889918)
					(mid 154.345132 -430.889918)
					(end 155.154884 -430.889918)
				)
			)
		)
	)
	(zone
		(layers "B.Cu" "In11.Cu" "In13.Cu" "In15.Cu")
		(hatch none 0.5)
		(connect_pads
			(clearance 0)
		)
		(min_thickness 0.25)
		(keepout
			(tracks not_allowed)
			(vias allowed)
			(pads allowed)
			(copperpour not_allowed)
			(footprints allowed)
		)
		(placement
			(enabled no)
			(sheetname "")
		)
		(fill yes
			(thermal_gap 0.5)
			(thermal_bridge_width 0.5)
			(island_removal_mode 0)
		)
		(polygon
			(pts
				(arc
					(start 440.250072 -283.166566)
					(mid 439.597292 -283.166566)
					(end 440.250072 -283.166566)
				)
			)
		)
	)
	(zone
		(layers "B.Cu" "In11.Cu" "In13.Cu" "In15.Cu")
		(hatch none 0.5)
		(connect_pads
			(clearance 0)
		)
		(min_thickness 0.25)
		(keepout
			(tracks not_allowed)
			(vias allowed)
			(pads allowed)
			(copperpour not_allowed)
			(footprints allowed)
		)
		(placement
			(enabled no)
			(sheetname "")
		)
		(fill yes
			(thermal_gap 0.5)
			(thermal_bridge_width 0.5)
			(island_removal_mode 0)
		)
		(polygon
			(pts
				(arc
					(start 339.230716 -214.622634)
					(mid 338.577936 -214.622634)
					(end 339.230716 -214.622634)
				)
			)
		)
	)
	(zone
		(layers "B.Cu" "In11.Cu" "In13.Cu" "In15.Cu")
		(hatch none 0.5)
		(connect_pads
			(clearance 0)
		)
		(min_thickness 0.25)
		(keepout
			(tracks not_allowed)
			(vias allowed)
			(pads allowed)
			(copperpour not_allowed)
			(footprints allowed)
		)
		(placement
			(enabled no)
			(sheetname "")
		)
		(fill yes
			(thermal_gap 0.5)
			(thermal_bridge_width 0.5)
			(island_removal_mode 0)
		)
		(polygon
			(pts
				(arc
					(start 280.143204 -200.716642)
					(mid 279.490424 -200.716642)
					(end 280.143204 -200.716642)
				)
			)
		)
	)
	(zone
		(layers "B.Cu" "In11.Cu" "In13.Cu" "In15.Cu")
		(hatch none 0.5)
		(connect_pads
			(clearance 0)
		)
		(min_thickness 0.25)
		(keepout
			(tracks not_allowed)
			(vias allowed)
			(pads allowed)
			(copperpour not_allowed)
			(footprints allowed)
		)
		(placement
			(enabled no)
			(sheetname "")
		)
		(fill yes
			(thermal_gap 0.5)
			(thermal_bridge_width 0.5)
			(island_removal_mode 0)
		)
		(polygon
			(pts
				(arc
					(start 344.040206 -270.19758)
					(mid 343.387426 -270.19758)
					(end 344.040206 -270.19758)
				)
			)
		)
	)
	(zone
		(layers "B.Cu" "In11.Cu" "In13.Cu" "In15.Cu")
		(hatch none 0.5)
		(connect_pads
			(clearance 0)
		)
		(min_thickness 0.25)
		(keepout
			(tracks not_allowed)
			(vias allowed)
			(pads allowed)
			(copperpour not_allowed)
			(footprints allowed)
		)
		(placement
			(enabled no)
			(sheetname "")
		)
		(fill yes
			(thermal_gap 0.5)
			(thermal_bridge_width 0.5)
			(island_removal_mode 0)
		)
		(polygon
			(pts
				(arc
					(start 32.203136 -230.466646)
					(mid 31.550356 -230.466646)
					(end 32.203136 -230.466646)
				)
			)
		)
	)
	(zone
		(layers "B.Cu" "In11.Cu" "In13.Cu" "In15.Cu")
		(hatch none 0.5)
		(connect_pads
			(clearance 0)
		)
		(min_thickness 0.25)
		(keepout
			(tracks not_allowed)
			(vias allowed)
			(pads allowed)
			(copperpour not_allowed)
			(footprints allowed)
		)
		(placement
			(enabled no)
			(sheetname "")
		)
		(fill yes
			(thermal_gap 0.5)
			(thermal_bridge_width 0.5)
			(island_removal_mode 0)
		)
		(polygon
			(pts
				(arc
					(start 436.150004 -222.816674)
					(mid 435.497224 -222.816674)
					(end 436.150004 -222.816674)
				)
			)
		)
	)
	(zone
		(layers "B.Cu" "In11.Cu" "In13.Cu" "In15.Cu")
		(hatch none 0.5)
		(connect_pads
			(clearance 0)
		)
		(min_thickness 0.25)
		(keepout
			(tracks not_allowed)
			(vias allowed)
			(pads allowed)
			(copperpour not_allowed)
			(footprints allowed)
		)
		(placement
			(enabled no)
			(sheetname "")
		)
		(fill yes
			(thermal_gap 0.5)
			(thermal_bridge_width 0.5)
			(island_removal_mode 0)
		)
		(polygon
			(pts
				(arc
					(start 103.618538 -276.708616)
					(mid 102.965758 -276.708616)
					(end 103.618538 -276.708616)
				)
			)
		)
	)
	(zone
		(layers "B.Cu" "In11.Cu" "In13.Cu" "In15.Cu")
		(hatch none 0.5)
		(connect_pads
			(clearance 0)
		)
		(min_thickness 0.25)
		(keepout
			(tracks not_allowed)
			(vias allowed)
			(pads allowed)
			(copperpour not_allowed)
			(footprints allowed)
		)
		(placement
			(enabled no)
			(sheetname "")
		)
		(fill yes
			(thermal_gap 0.5)
			(thermal_bridge_width 0.5)
			(island_removal_mode 0)
		)
		(polygon
			(pts
				(arc
					(start 96.929956 -237.411514)
					(mid 96.277176 -237.411514)
					(end 96.929956 -237.411514)
				)
			)
		)
	)
	(zone
		(layers "B.Cu" "In11.Cu" "In13.Cu" "In15.Cu")
		(hatch none 0.5)
		(connect_pads
			(clearance 0)
		)
		(min_thickness 0.25)
		(keepout
			(tracks not_allowed)
			(vias allowed)
			(pads allowed)
			(copperpour not_allowed)
			(footprints allowed)
		)
		(placement
			(enabled no)
			(sheetname "")
		)
		(fill yes
			(thermal_gap 0.5)
			(thermal_bridge_width 0.5)
			(island_removal_mode 0)
		)
		(polygon
			(pts
				(arc
					(start 338.290916 -214.622634)
					(mid 337.638136 -214.622634)
					(end 338.290916 -214.622634)
				)
			)
		)
	)
	(zone
		(layers "B.Cu" "In11.Cu" "In13.Cu" "In15.Cu")
		(hatch none 0.5)
		(connect_pads
			(clearance 0)
		)
		(min_thickness 0.25)
		(keepout
			(tracks not_allowed)
			(vias allowed)
			(pads allowed)
			(copperpour not_allowed)
			(footprints allowed)
		)
		(placement
			(enabled no)
			(sheetname "")
		)
		(fill yes
			(thermal_gap 0.5)
			(thermal_bridge_width 0.5)
			(island_removal_mode 0)
		)
		(polygon
			(pts
				(arc
					(start 269.155672 -206.666592)
					(mid 268.502892 -206.666592)
					(end 269.155672 -206.666592)
				)
			)
		)
	)
	(zone
		(layers "B.Cu" "In11.Cu" "In13.Cu" "In15.Cu")
		(hatch none 0.5)
		(connect_pads
			(clearance 0)
		)
		(min_thickness 0.25)
		(keepout
			(tracks not_allowed)
			(vias allowed)
			(pads allowed)
			(copperpour not_allowed)
			(footprints allowed)
		)
		(placement
			(enabled no)
			(sheetname "")
		)
		(fill yes
			(thermal_gap 0.5)
			(thermal_bridge_width 0.5)
			(island_removal_mode 0)
		)
		(polygon
			(pts
				(arc
					(start 376.35307 -241.481102)
					(mid 375.70029 -241.481102)
					(end 376.35307 -241.481102)
				)
			)
		)
	)
	(zone
		(layers "B.Cu" "In11.Cu" "In13.Cu" "In15.Cu")
		(hatch none 0.5)
		(connect_pads
			(clearance 0)
		)
		(min_thickness 0.25)
		(keepout
			(tracks not_allowed)
			(vias allowed)
			(pads allowed)
			(copperpour not_allowed)
			(footprints allowed)
		)
		(placement
			(enabled no)
			(sheetname "")
		)
		(fill yes
			(thermal_gap 0.5)
			(thermal_bridge_width 0.5)
			(island_removal_mode 0)
		)
		(polygon
			(pts
				(arc
					(start 344.980006 -262.058658)
					(mid 344.327226 -262.058658)
					(end 344.980006 -262.058658)
				)
			)
		)
	)
	(zone
		(layers "B.Cu" "In11.Cu" "In13.Cu" "In15.Cu")
		(hatch none 0.5)
		(connect_pads
			(clearance 0)
		)
		(min_thickness 0.25)
		(keepout
			(tracks not_allowed)
			(vias allowed)
			(pads allowed)
			(copperpour not_allowed)
			(footprints allowed)
		)
		(placement
			(enabled no)
			(sheetname "")
		)
		(fill yes
			(thermal_gap 0.5)
			(thermal_bridge_width 0.5)
			(island_removal_mode 0)
		)
		(polygon
			(pts
				(arc
					(start 71.120508 -410.030168)
					(mid 70.416928 -410.030168)
					(end 71.120508 -410.030168)
				)
			)
		)
	)
	(zone
		(layers "B.Cu" "In11.Cu" "In13.Cu" "In15.Cu")
		(hatch none 0.5)
		(connect_pads
			(clearance 0)
		)
		(min_thickness 0.25)
		(keepout
			(tracks not_allowed)
			(vias allowed)
			(pads allowed)
			(copperpour not_allowed)
			(footprints allowed)
		)
		(placement
			(enabled no)
			(sheetname "")
		)
		(fill yes
			(thermal_gap 0.5)
			(thermal_bridge_width 0.5)
			(island_removal_mode 0)
		)
		(polygon
			(pts
				(arc
					(start 32.203136 -200.716642)
					(mid 31.550356 -200.716642)
					(end 32.203136 -200.716642)
				)
			)
		)
	)
	(zone
		(layers "B.Cu" "In11.Cu" "In13.Cu" "In15.Cu")
		(hatch none 0.5)
		(connect_pads
			(clearance 0)
		)
		(min_thickness 0.25)
		(keepout
			(tracks not_allowed)
			(vias allowed)
			(pads allowed)
			(copperpour not_allowed)
			(footprints allowed)
		)
		(placement
			(enabled no)
			(sheetname "")
		)
		(fill yes
			(thermal_gap 0.5)
			(thermal_bridge_width 0.5)
			(island_removal_mode 0)
		)
		(polygon
			(pts
				(arc
					(start 105.498138 -275.08073)
					(mid 104.845358 -275.08073)
					(end 105.498138 -275.08073)
				)
			)
		)
	)
	(zone
		(layers "B.Cu" "In11.Cu" "In13.Cu" "In15.Cu")
		(hatch none 0.5)
		(connect_pads
			(clearance 0)
		)
		(min_thickness 0.25)
		(keepout
			(tracks not_allowed)
			(vias allowed)
			(pads allowed)
			(copperpour not_allowed)
			(footprints allowed)
		)
		(placement
			(enabled no)
			(sheetname "")
		)
		(fill yes
			(thermal_gap 0.5)
			(thermal_bridge_width 0.5)
			(island_removal_mode 0)
		)
		(polygon
			(pts
				(arc
					(start 354.73767 -228.45903)
					(mid 354.08489 -228.45903)
					(end 354.73767 -228.45903)
				)
			)
		)
	)
	(zone
		(layers "B.Cu" "In11.Cu" "In13.Cu" "In15.Cu")
		(hatch none 0.5)
		(connect_pads
			(clearance 0)
		)
		(min_thickness 0.25)
		(keepout
			(tracks not_allowed)
			(vias allowed)
			(pads allowed)
			(copperpour not_allowed)
			(footprints allowed)
		)
		(placement
			(enabled no)
			(sheetname "")
		)
		(fill yes
			(thermal_gap 0.5)
			(thermal_bridge_width 0.5)
			(island_removal_mode 0)
		)
		(polygon
			(pts
				(arc
					(start 36.303204 -217.716608)
					(mid 35.650424 -217.716608)
					(end 36.303204 -217.716608)
				)
			)
		)
	)
	(zone
		(layers "B.Cu" "In11.Cu" "In13.Cu" "In15.Cu")
		(hatch none 0.5)
		(connect_pads
			(clearance 0)
		)
		(min_thickness 0.25)
		(keepout
			(tracks not_allowed)
			(vias allowed)
			(pads allowed)
			(copperpour not_allowed)
			(footprints allowed)
		)
		(placement
			(enabled no)
			(sheetname "")
		)
		(fill yes
			(thermal_gap 0.5)
			(thermal_bridge_width 0.5)
			(island_removal_mode 0)
		)
		(polygon
			(pts
				(arc
					(start 373.98452 -410.030168)
					(mid 373.28094 -410.030168)
					(end 373.98452 -410.030168)
				)
			)
		)
	)
	(zone
		(layers "B.Cu" "In11.Cu" "In13.Cu" "In15.Cu")
		(hatch none 0.5)
		(connect_pads
			(clearance 0)
		)
		(min_thickness 0.25)
		(keepout
			(tracks not_allowed)
			(vias allowed)
			(pads allowed)
			(copperpour not_allowed)
			(footprints allowed)
		)
		(placement
			(enabled no)
			(sheetname "")
		)
		(fill yes
			(thermal_gap 0.5)
			(thermal_bridge_width 0.5)
			(island_removal_mode 0)
		)
		(polygon
			(pts
				(arc
					(start 67.054984 -433.289964)
					(mid 66.245232 -433.289964)
					(end 67.054984 -433.289964)
				)
			)
		)
	)
	(zone
		(layers "B.Cu" "In11.Cu" "In13.Cu" "In15.Cu")
		(hatch none 0.5)
		(connect_pads
			(clearance 0)
		)
		(min_thickness 0.25)
		(keepout
			(tracks not_allowed)
			(vias allowed)
			(pads allowed)
			(copperpour not_allowed)
			(footprints allowed)
		)
		(placement
			(enabled no)
			(sheetname "")
		)
		(fill yes
			(thermal_gap 0.5)
			(thermal_bridge_width 0.5)
			(island_removal_mode 0)
		)
		(polygon
			(pts
				(arc
					(start 97.399602 -226.831144)
					(mid 96.746822 -226.831144)
					(end 97.399602 -226.831144)
				)
			)
		)
	)
	(zone
		(layers "B.Cu" "In11.Cu" "In13.Cu" "In15.Cu")
		(hatch none 0.5)
		(connect_pads
			(clearance 0)
		)
		(min_thickness 0.25)
		(keepout
			(tracks not_allowed)
			(vias allowed)
			(pads allowed)
			(copperpour not_allowed)
			(footprints allowed)
		)
		(placement
			(enabled no)
			(sheetname "")
		)
		(fill yes
			(thermal_gap 0.5)
			(thermal_bridge_width 0.5)
			(island_removal_mode 0)
		)
		(polygon
			(pts
				(arc
					(start 338.05495 -428.28972)
					(mid 337.245198 -428.28972)
					(end 338.05495 -428.28972)
				)
			)
		)
	)
	(zone
		(layers "B.Cu" "In11.Cu" "In13.Cu" "In15.Cu")
		(hatch none 0.5)
		(connect_pads
			(clearance 0)
		)
		(min_thickness 0.25)
		(keepout
			(tracks not_allowed)
			(vias allowed)
			(pads allowed)
			(copperpour not_allowed)
			(footprints allowed)
		)
		(placement
			(enabled no)
			(sheetname "")
		)
		(fill yes
			(thermal_gap 0.5)
			(thermal_bridge_width 0.5)
			(island_removal_mode 0)
		)
		(polygon
			(pts
				(arc
					(start 105.858056 -213.732618)
					(mid 105.205276 -213.732618)
					(end 105.858056 -213.732618)
				)
			)
		)
	)
	(zone
		(layers "B.Cu" "In11.Cu" "In13.Cu" "In15.Cu")
		(hatch none 0.5)
		(connect_pads
			(clearance 0)
		)
		(min_thickness 0.25)
		(keepout
			(tracks not_allowed)
			(vias allowed)
			(pads allowed)
			(copperpour not_allowed)
			(footprints allowed)
		)
		(placement
			(enabled no)
			(sheetname "")
		)
		(fill yes
			(thermal_gap 0.5)
			(thermal_bridge_width 0.5)
			(island_removal_mode 0)
		)
		(polygon
			(pts
				(arc
					(start 93.426788 -410.030168)
					(mid 92.723208 -410.030168)
					(end 93.426788 -410.030168)
				)
			)
		)
	)
	(zone
		(layers "B.Cu" "In11.Cu" "In13.Cu" "In15.Cu")
		(hatch none 0.5)
		(connect_pads
			(clearance 0)
		)
		(min_thickness 0.25)
		(keepout
			(tracks not_allowed)
			(vias allowed)
			(pads allowed)
			(copperpour not_allowed)
			(footprints allowed)
		)
		(placement
			(enabled no)
			(sheetname "")
		)
		(fill yes
			(thermal_gap 0.5)
			(thermal_bridge_width 0.5)
			(island_removal_mode 0)
		)
		(polygon
			(pts
				(arc
					(start 344.040206 -268.569694)
					(mid 343.387426 -268.569694)
					(end 344.040206 -268.569694)
				)
			)
		)
	)
	(zone
		(layers "B.Cu" "In11.Cu" "In13.Cu" "In15.Cu")
		(hatch none 0.5)
		(connect_pads
			(clearance 0)
		)
		(min_thickness 0.25)
		(keepout
			(tracks not_allowed)
			(vias allowed)
			(pads allowed)
			(copperpour not_allowed)
			(footprints allowed)
		)
		(placement
			(enabled no)
			(sheetname "")
		)
		(fill yes
			(thermal_gap 0.5)
			(thermal_bridge_width 0.5)
			(island_removal_mode 0)
		)
		(polygon
			(pts
				(arc
					(start 338.05495 -434.289962)
					(mid 337.245198 -434.289962)
					(end 338.05495 -434.289962)
				)
			)
		)
	)
	(zone
		(layers "B.Cu" "In11.Cu" "In13.Cu" "In15.Cu")
		(hatch none 0.5)
		(connect_pads
			(clearance 0)
		)
		(min_thickness 0.25)
		(keepout
			(tracks not_allowed)
			(vias allowed)
			(pads allowed)
			(copperpour not_allowed)
			(footprints allowed)
		)
		(placement
			(enabled no)
			(sheetname "")
		)
		(fill yes
			(thermal_gap 0.5)
			(thermal_bridge_width 0.5)
			(island_removal_mode 0)
		)
		(polygon
			(pts
				(arc
					(start 131.232402 -215.436704)
					(mid 130.579622 -215.436704)
					(end 131.232402 -215.436704)
				)
			)
		)
	)
	(zone
		(layers "B.Cu" "In11.Cu" "In13.Cu" "In15.Cu")
		(hatch none 0.5)
		(connect_pads
			(clearance 0)
		)
		(min_thickness 0.25)
		(keepout
			(tracks not_allowed)
			(vias allowed)
			(pads allowed)
			(copperpour not_allowed)
			(footprints allowed)
		)
		(placement
			(enabled no)
			(sheetname "")
		)
		(fill yes
			(thermal_gap 0.5)
			(thermal_bridge_width 0.5)
			(island_removal_mode 0)
		)
		(polygon
			(pts
				(arc
					(start 451.237604 -210.066636)
					(mid 450.584824 -210.066636)
					(end 451.237604 -210.066636)
				)
			)
		)
	)
	(zone
		(layers "B.Cu" "In11.Cu" "In13.Cu" "In15.Cu")
		(hatch none 0.5)
		(connect_pads
			(clearance 0)
		)
		(min_thickness 0.25)
		(keepout
			(tracks not_allowed)
			(vias allowed)
			(pads allowed)
			(copperpour not_allowed)
			(footprints allowed)
		)
		(placement
			(enabled no)
			(sheetname "")
		)
		(fill yes
			(thermal_gap 0.5)
			(thermal_bridge_width 0.5)
			(island_removal_mode 0)
		)
		(polygon
			(pts
				(arc
					(start 383.041652 -254.733552)
					(mid 382.388872 -254.733552)
					(end 383.041652 -254.733552)
				)
			)
		)
	)
	(zone
		(layers "B.Cu" "In11.Cu" "In13.Cu" "In15.Cu")
		(hatch none 0.5)
		(connect_pads
			(clearance 0)
		)
		(min_thickness 0.25)
		(keepout
			(tracks not_allowed)
			(vias allowed)
			(pads allowed)
			(copperpour not_allowed)
			(footprints allowed)
		)
		(placement
			(enabled no)
			(sheetname "")
		)
		(fill yes
			(thermal_gap 0.5)
			(thermal_bridge_width 0.5)
			(island_removal_mode 0)
		)
		(polygon
			(pts
				(arc
					(start 203.297536 -310.366664)
					(mid 202.644756 -310.366664)
					(end 203.297536 -310.366664)
				)
			)
		)
	)
	(zone
		(layers "B.Cu" "In11.Cu" "In13.Cu" "In15.Cu")
		(hatch none 0.5)
		(connect_pads
			(clearance 0)
		)
		(min_thickness 0.25)
		(keepout
			(tracks not_allowed)
			(vias allowed)
			(pads allowed)
			(copperpour not_allowed)
			(footprints allowed)
		)
		(placement
			(enabled no)
			(sheetname "")
		)
		(fill yes
			(thermal_gap 0.5)
			(thermal_bridge_width 0.5)
			(island_removal_mode 0)
		)
		(polygon
			(pts
				(arc
					(start 371.398546 -166.342568)
					(mid 370.694966 -166.342568)
					(end 371.398546 -166.342568)
				)
			)
		)
	)
	(zone
		(layers "B.Cu" "In11.Cu" "In13.Cu" "In15.Cu")
		(hatch none 0.5)
		(connect_pads
			(clearance 0)
		)
		(min_thickness 0.25)
		(keepout
			(tracks not_allowed)
			(vias allowed)
			(pads allowed)
			(copperpour not_allowed)
			(footprints allowed)
		)
		(placement
			(enabled no)
			(sheetname "")
		)
		(fill yes
			(thermal_gap 0.5)
			(thermal_bridge_width 0.5)
			(island_removal_mode 0)
		)
		(polygon
			(pts
				(arc
					(start 107.267248 -214.622634)
					(mid 106.614468 -214.622634)
					(end 107.267248 -214.622634)
				)
			)
		)
	)
	(zone
		(layers "B.Cu" "In11.Cu" "In13.Cu" "In15.Cu")
		(hatch none 0.5)
		(connect_pads
			(clearance 0)
		)
		(min_thickness 0.25)
		(keepout
			(tracks not_allowed)
			(vias allowed)
			(pads allowed)
			(copperpour not_allowed)
			(footprints allowed)
		)
		(placement
			(enabled no)
			(sheetname "")
		)
		(fill yes
			(thermal_gap 0.5)
			(thermal_bridge_width 0.5)
			(island_removal_mode 0)
		)
		(polygon
			(pts
				(arc
					(start 379.282452 -279.150318)
					(mid 378.629672 -279.150318)
					(end 379.282452 -279.150318)
				)
			)
		)
	)
	(zone
		(layers "B.Cu" "In11.Cu" "In13.Cu" "In15.Cu")
		(hatch none 0.5)
		(connect_pads
			(clearance 0)
		)
		(min_thickness 0.25)
		(keepout
			(tracks not_allowed)
			(vias allowed)
			(pads allowed)
			(copperpour not_allowed)
			(footprints allowed)
		)
		(placement
			(enabled no)
			(sheetname "")
		)
		(fill yes
			(thermal_gap 0.5)
			(thermal_bridge_width 0.5)
			(island_removal_mode 0)
		)
		(polygon
			(pts
				(arc
					(start 97.509584 -256.361438)
					(mid 96.856804 -256.361438)
					(end 97.509584 -256.361438)
				)
			)
		)
	)
	(zone
		(layers "B.Cu" "In11.Cu" "In13.Cu" "In15.Cu")
		(hatch none 0.5)
		(connect_pads
			(clearance 0)
		)
		(min_thickness 0.25)
		(keepout
			(tracks not_allowed)
			(vias allowed)
			(pads allowed)
			(copperpour not_allowed)
			(footprints allowed)
		)
		(placement
			(enabled no)
			(sheetname "")
		)
		(fill yes
			(thermal_gap 0.5)
			(thermal_bridge_width 0.5)
			(island_removal_mode 0)
		)
		(polygon
			(pts
				(arc
					(start 351.033842 -63.269876)
					(mid 350.330262 -63.269876)
					(end 351.033842 -63.269876)
				)
			)
		)
	)
	(zone
		(layers "B.Cu" "In11.Cu" "In13.Cu" "In15.Cu")
		(hatch none 0.5)
		(connect_pads
			(clearance 0)
		)
		(min_thickness 0.25)
		(keepout
			(tracks not_allowed)
			(vias allowed)
			(pads allowed)
			(copperpour not_allowed)
			(footprints allowed)
		)
		(placement
			(enabled no)
			(sheetname "")
		)
		(fill yes
			(thermal_gap 0.5)
			(thermal_bridge_width 0.5)
			(island_removal_mode 0)
		)
		(polygon
			(pts
				(arc
					(start 87.172038 -282.405836)
					(mid 86.519258 -282.405836)
					(end 87.172038 -282.405836)
				)
			)
		)
	)
	(zone
		(layers "B.Cu" "In11.Cu" "In13.Cu" "In15.Cu")
		(hatch none 0.5)
		(connect_pads
			(clearance 0)
		)
		(min_thickness 0.25)
		(keepout
			(tracks not_allowed)
			(vias allowed)
			(pads allowed)
			(copperpour not_allowed)
			(footprints allowed)
		)
		(placement
			(enabled no)
			(sheetname "")
		)
		(fill yes
			(thermal_gap 0.5)
			(thermal_bridge_width 0.5)
			(island_removal_mode 0)
		)
		(polygon
			(pts
				(arc
					(start 257.511804 -245.76659)
					(mid 256.859024 -245.76659)
					(end 257.511804 -245.76659)
				)
			)
		)
	)
	(zone
		(layers "B.Cu" "In11.Cu" "In13.Cu" "In15.Cu")
		(hatch none 0.5)
		(connect_pads
			(clearance 0)
		)
		(min_thickness 0.25)
		(keepout
			(tracks not_allowed)
			(vias allowed)
			(pads allowed)
			(copperpour not_allowed)
			(footprints allowed)
		)
		(placement
			(enabled no)
			(sheetname "")
		)
		(fill yes
			(thermal_gap 0.5)
			(thermal_bridge_width 0.5)
			(island_removal_mode 0)
		)
		(polygon
			(pts
				(arc
					(start 100.328984 -254.733552)
					(mid 99.676204 -254.733552)
					(end 100.328984 -254.733552)
				)
			)
		)
	)
	(zone
		(layers "B.Cu" "In11.Cu" "In13.Cu" "In15.Cu")
		(hatch none 0.5)
		(connect_pads
			(clearance 0)
		)
		(min_thickness 0.25)
		(keepout
			(tracks not_allowed)
			(vias allowed)
			(pads allowed)
			(copperpour not_allowed)
			(footprints allowed)
		)
		(placement
			(enabled no)
			(sheetname "")
		)
		(fill yes
			(thermal_gap 0.5)
			(thermal_bridge_width 0.5)
			(island_removal_mode 0)
		)
		(polygon
			(pts
				(arc
					(start 342.765126 -71.185786)
					(mid 342.061546 -71.185786)
					(end 342.765126 -71.185786)
				)
			)
		)
	)
	(zone
		(layers "B.Cu" "In11.Cu" "In13.Cu" "In15.Cu")
		(hatch none 0.5)
		(connect_pads
			(clearance 0)
		)
		(min_thickness 0.25)
		(keepout
			(tracks not_allowed)
			(vias allowed)
			(pads allowed)
			(copperpour not_allowed)
			(footprints allowed)
		)
		(placement
			(enabled no)
			(sheetname "")
		)
		(fill yes
			(thermal_gap 0.5)
			(thermal_bridge_width 0.5)
			(island_removal_mode 0)
		)
		(polygon
			(pts
				(arc
					(start 332.054962 -433.289964)
					(mid 331.24521 -433.289964)
					(end 332.054962 -433.289964)
				)
			)
		)
	)
	(zone
		(layers "B.Cu" "In11.Cu" "In13.Cu" "In15.Cu")
		(hatch none 0.5)
		(connect_pads
			(clearance 0)
		)
		(min_thickness 0.25)
		(keepout
			(tracks not_allowed)
			(vias allowed)
			(pads allowed)
			(copperpour not_allowed)
			(footprints allowed)
		)
		(placement
			(enabled no)
			(sheetname "")
		)
		(fill yes
			(thermal_gap 0.5)
			(thermal_bridge_width 0.5)
			(island_removal_mode 0)
		)
		(polygon
			(pts
				(arc
					(start 315.054996 -427.289976)
					(mid 314.245244 -427.289976)
					(end 315.054996 -427.289976)
				)
			)
		)
	)
	(zone
		(layers "B.Cu" "In11.Cu" "In13.Cu" "In15.Cu")
		(hatch none 0.5)
		(connect_pads
			(clearance 0)
		)
		(min_thickness 0.25)
		(keepout
			(tracks not_allowed)
			(vias allowed)
			(pads allowed)
			(copperpour not_allowed)
			(footprints allowed)
		)
		(placement
			(enabled no)
			(sheetname "")
		)
		(fill yes
			(thermal_gap 0.5)
			(thermal_bridge_width 0.5)
			(island_removal_mode 0)
		)
		(polygon
			(pts
				(arc
					(start 96.929956 -239.0394)
					(mid 96.277176 -239.0394)
					(end 96.929956 -239.0394)
				)
			)
		)
	)
	(zone
		(layers "B.Cu" "In11.Cu" "In13.Cu" "In15.Cu")
		(hatch none 0.5)
		(connect_pads
			(clearance 0)
		)
		(min_thickness 0.25)
		(keepout
			(tracks not_allowed)
			(vias allowed)
			(pads allowed)
			(copperpour not_allowed)
			(footprints allowed)
		)
		(placement
			(enabled no)
			(sheetname "")
		)
		(fill yes
			(thermal_gap 0.5)
			(thermal_bridge_width 0.5)
			(island_removal_mode 0)
		)
		(polygon
			(pts
				(arc
					(start 36.303204 -225.36658)
					(mid 35.650424 -225.36658)
					(end 36.303204 -225.36658)
				)
			)
		)
	)
	(zone
		(layers "B.Cu" "In11.Cu" "In13.Cu" "In15.Cu")
		(hatch none 0.5)
		(connect_pads
			(clearance 0)
		)
		(min_thickness 0.25)
		(keepout
			(tracks not_allowed)
			(vias allowed)
			(pads allowed)
			(copperpour not_allowed)
			(footprints allowed)
		)
		(placement
			(enabled no)
			(sheetname "")
		)
		(fill yes
			(thermal_gap 0.5)
			(thermal_bridge_width 0.5)
			(island_removal_mode 0)
		)
		(polygon
			(pts
				(arc
					(start 95.629984 -280.778204)
					(mid 94.977204 -280.778204)
					(end 95.629984 -280.778204)
				)
			)
		)
	)
	(zone
		(layers "B.Cu" "In11.Cu" "In13.Cu" "In15.Cu")
		(hatch none 0.5)
		(connect_pads
			(clearance 0)
		)
		(min_thickness 0.25)
		(keepout
			(tracks not_allowed)
			(vias allowed)
			(pads allowed)
			(copperpour not_allowed)
			(footprints allowed)
		)
		(placement
			(enabled no)
			(sheetname "")
		)
		(fill yes
			(thermal_gap 0.5)
			(thermal_bridge_width 0.5)
			(island_removal_mode 0)
		)
		(polygon
			(pts
				(arc
					(start 344.054938 -426.089826)
					(mid 343.245186 -426.089826)
					(end 344.054938 -426.089826)
				)
			)
		)
	)
	(zone
		(layers "B.Cu" "In11.Cu" "In13.Cu" "In15.Cu")
		(hatch none 0.5)
		(connect_pads
			(clearance 0)
		)
		(min_thickness 0.25)
		(keepout
			(tracks not_allowed)
			(vias allowed)
			(pads allowed)
			(copperpour not_allowed)
			(footprints allowed)
		)
		(placement
			(enabled no)
			(sheetname "")
		)
		(fill yes
			(thermal_gap 0.5)
			(thermal_bridge_width 0.5)
			(island_removal_mode 0)
		)
		(polygon
			(pts
				(arc
					(start 207.397604 -204.96657)
					(mid 206.744824 -204.96657)
					(end 207.397604 -204.96657)
				)
			)
		)
	)
	(zone
		(layers "B.Cu" "In11.Cu" "In13.Cu" "In15.Cu")
		(hatch none 0.5)
		(connect_pads
			(clearance 0)
		)
		(min_thickness 0.25)
		(keepout
			(tracks not_allowed)
			(vias allowed)
			(pads allowed)
			(copperpour not_allowed)
			(footprints allowed)
		)
		(placement
			(enabled no)
			(sheetname "")
		)
		(fill yes
			(thermal_gap 0.5)
			(thermal_bridge_width 0.5)
			(island_removal_mode 0)
		)
		(polygon
			(pts
				(arc
					(start 36.303204 -274.66671)
					(mid 35.650424 -274.66671)
					(end 36.303204 -274.66671)
				)
			)
		)
	)
	(zone
		(layers "B.Cu" "In11.Cu" "In13.Cu" "In15.Cu")
		(hatch none 0.5)
		(connect_pads
			(clearance 0)
		)
		(min_thickness 0.25)
		(keepout
			(tracks not_allowed)
			(vias allowed)
			(pads allowed)
			(copperpour not_allowed)
			(footprints allowed)
		)
		(placement
			(enabled no)
			(sheetname "")
		)
		(fill yes
			(thermal_gap 0.5)
			(thermal_bridge_width 0.5)
			(island_removal_mode 0)
		)
		(polygon
			(pts
				(arc
					(start 343.46007 -236.597952)
					(mid 342.80729 -236.597952)
					(end 343.46007 -236.597952)
				)
			)
		)
	)
	(zone
		(layers "B.Cu" "In11.Cu" "In13.Cu" "In15.Cu")
		(hatch none 0.5)
		(connect_pads
			(clearance 0)
		)
		(min_thickness 0.25)
		(keepout
			(tracks not_allowed)
			(vias allowed)
			(pads allowed)
			(copperpour not_allowed)
			(footprints allowed)
		)
		(placement
			(enabled no)
			(sheetname "")
		)
		(fill yes
			(thermal_gap 0.5)
			(thermal_bridge_width 0.5)
			(island_removal_mode 0)
		)
		(polygon
			(pts
				(arc
					(start 407.154888 -438.089802)
					(mid 406.345136 -438.089802)
					(end 407.154888 -438.089802)
				)
			)
		)
	)
	(zone
		(layers "B.Cu" "In11.Cu" "In13.Cu" "In15.Cu")
		(hatch none 0.5)
		(connect_pads
			(clearance 0)
		)
		(min_thickness 0.25)
		(keepout
			(tracks not_allowed)
			(vias allowed)
			(pads allowed)
			(copperpour not_allowed)
			(footprints allowed)
		)
		(placement
			(enabled no)
			(sheetname "")
		)
		(fill yes
			(thermal_gap 0.5)
			(thermal_bridge_width 0.5)
			(island_removal_mode 0)
		)
		(polygon
			(pts
				(arc
					(start 284.243272 -278.066754)
					(mid 283.590492 -278.066754)
					(end 284.243272 -278.066754)
				)
			)
		)
	)
	(zone
		(layers "B.Cu" "In11.Cu" "In13.Cu" "In15.Cu")
		(hatch none 0.5)
		(connect_pads
			(clearance 0)
		)
		(min_thickness 0.25)
		(keepout
			(tracks not_allowed)
			(vias allowed)
			(pads allowed)
			(copperpour not_allowed)
			(footprints allowed)
		)
		(placement
			(enabled no)
			(sheetname "")
		)
		(fill yes
			(thermal_gap 0.5)
			(thermal_bridge_width 0.5)
			(island_removal_mode 0)
		)
		(polygon
			(pts
				(arc
					(start 265.055604 -314.616592)
					(mid 264.402824 -314.616592)
					(end 265.055604 -314.616592)
				)
			)
		)
	)
	(zone
		(layers "B.Cu" "In11.Cu" "In13.Cu" "In15.Cu")
		(hatch none 0.5)
		(connect_pads
			(clearance 0)
		)
		(min_thickness 0.25)
		(keepout
			(tracks not_allowed)
			(vias allowed)
			(pads allowed)
			(copperpour not_allowed)
			(footprints allowed)
		)
		(placement
			(enabled no)
			(sheetname "")
		)
		(fill yes
			(thermal_gap 0.5)
			(thermal_bridge_width 0.5)
			(island_removal_mode 0)
		)
		(polygon
			(pts
				(arc
					(start 155.154884 -429.689768)
					(mid 154.345132 -429.689768)
					(end 155.154884 -429.689768)
				)
			)
		)
	)
	(zone
		(layers "B.Cu" "In11.Cu" "In13.Cu" "In15.Cu")
		(hatch none 0.5)
		(connect_pads
			(clearance 0)
		)
		(min_thickness 0.25)
		(keepout
			(tracks not_allowed)
			(vias allowed)
			(pads allowed)
			(copperpour not_allowed)
			(footprints allowed)
		)
		(placement
			(enabled no)
			(sheetname "")
		)
		(fill yes
			(thermal_gap 0.5)
			(thermal_bridge_width 0.5)
			(island_removal_mode 0)
		)
		(polygon
			(pts
				(arc
					(start 78.054962 -428.28972)
					(mid 77.24521 -428.28972)
					(end 78.054962 -428.28972)
				)
			)
		)
	)
	(zone
		(layers "B.Cu" "In11.Cu" "In13.Cu" "In15.Cu")
		(hatch none 0.5)
		(connect_pads
			(clearance 0)
		)
		(min_thickness 0.25)
		(keepout
			(tracks not_allowed)
			(vias allowed)
			(pads allowed)
			(copperpour not_allowed)
			(footprints allowed)
		)
		(placement
			(enabled no)
			(sheetname "")
		)
		(fill yes
			(thermal_gap 0.5)
			(thermal_bridge_width 0.5)
			(island_removal_mode 0)
		)
		(polygon
			(pts
				(arc
					(start 141.36624 -18.144744)
					(mid 140.66266 -18.144744)
					(end 141.36624 -18.144744)
				)
			)
		)
	)
	(zone
		(layers "B.Cu" "In11.Cu" "In13.Cu" "In15.Cu")
		(hatch none 0.5)
		(connect_pads
			(clearance 0)
		)
		(min_thickness 0.25)
		(keepout
			(tracks not_allowed)
			(vias allowed)
			(pads allowed)
			(copperpour not_allowed)
			(footprints allowed)
		)
		(placement
			(enabled no)
			(sheetname "")
		)
		(fill yes
			(thermal_gap 0.5)
			(thermal_bridge_width 0.5)
			(island_removal_mode 0)
		)
		(polygon
			(pts
				(arc
					(start 17.115536 -209.216752)
					(mid 16.462756 -209.216752)
					(end 17.115536 -209.216752)
				)
			)
		)
	)
	(zone
		(layers "B.Cu" "In11.Cu" "In13.Cu" "In15.Cu")
		(hatch none 0.5)
		(connect_pads
			(clearance 0)
		)
		(min_thickness 0.25)
		(keepout
			(tracks not_allowed)
			(vias allowed)
			(pads allowed)
			(copperpour not_allowed)
			(footprints allowed)
		)
		(placement
			(enabled no)
			(sheetname "")
		)
		(fill yes
			(thermal_gap 0.5)
			(thermal_bridge_width 0.5)
			(island_removal_mode 0)
		)
		(polygon
			(pts
				(arc
					(start 203.297536 -205.816708)
					(mid 202.644756 -205.816708)
					(end 203.297536 -205.816708)
				)
			)
		)
	)
	(zone
		(layers "B.Cu" "In11.Cu" "In13.Cu" "In15.Cu")
		(hatch none 0.5)
		(connect_pads
			(clearance 0)
		)
		(min_thickness 0.25)
		(keepout
			(tracks not_allowed)
			(vias allowed)
			(pads allowed)
			(copperpour not_allowed)
			(footprints allowed)
		)
		(placement
			(enabled no)
			(sheetname "")
		)
		(fill yes
			(thermal_gap 0.5)
			(thermal_bridge_width 0.5)
			(island_removal_mode 0)
		)
		(polygon
			(pts
				(arc
					(start 158.009336 -244.066568)
					(mid 157.356556 -244.066568)
					(end 158.009336 -244.066568)
				)
			)
		)
	)
	(zone
		(layers "B.Cu" "In11.Cu" "In13.Cu" "In15.Cu")
		(hatch none 0.5)
		(connect_pads
			(clearance 0)
		)
		(min_thickness 0.25)
		(keepout
			(tracks not_allowed)
			(vias allowed)
			(pads allowed)
			(copperpour not_allowed)
			(footprints allowed)
		)
		(placement
			(enabled no)
			(sheetname "")
		)
		(fill yes
			(thermal_gap 0.5)
			(thermal_bridge_width 0.5)
			(island_removal_mode 0)
		)
		(polygon
			(pts
				(arc
					(start 455.337672 -244.916706)
					(mid 454.684892 -244.916706)
					(end 455.337672 -244.916706)
				)
			)
		)
	)
	(zone
		(layers "B.Cu" "In11.Cu" "In13.Cu" "In15.Cu")
		(hatch none 0.5)
		(connect_pads
			(clearance 0)
		)
		(min_thickness 0.25)
		(keepout
			(tracks not_allowed)
			(vias allowed)
			(pads allowed)
			(copperpour not_allowed)
			(footprints allowed)
		)
		(placement
			(enabled no)
			(sheetname "")
		)
		(fill yes
			(thermal_gap 0.5)
			(thermal_bridge_width 0.5)
			(island_removal_mode 0)
		)
		(polygon
			(pts
				(arc
					(start 127.583184 -267.755878)
					(mid 126.930404 -267.755878)
					(end 127.583184 -267.755878)
				)
			)
		)
	)
	(zone
		(layers "B.Cu" "In11.Cu" "In13.Cu" "In15.Cu")
		(hatch none 0.5)
		(connect_pads
			(clearance 0)
		)
		(min_thickness 0.25)
		(keepout
			(tracks not_allowed)
			(vias allowed)
			(pads allowed)
			(copperpour not_allowed)
			(footprints allowed)
		)
		(placement
			(enabled no)
			(sheetname "")
		)
		(fill yes
			(thermal_gap 0.5)
			(thermal_bridge_width 0.5)
			(island_removal_mode 0)
		)
		(polygon
			(pts
				(arc
					(start 108.787184 -277.522432)
					(mid 108.134404 -277.522432)
					(end 108.787184 -277.522432)
				)
			)
		)
	)
	(zone
		(layers "B.Cu" "In11.Cu" "In13.Cu" "In15.Cu")
		(hatch none 0.5)
		(connect_pads
			(clearance 0)
		)
		(min_thickness 0.25)
		(keepout
			(tracks not_allowed)
			(vias allowed)
			(pads allowed)
			(copperpour not_allowed)
			(footprints allowed)
		)
		(placement
			(enabled no)
			(sheetname "")
		)
		(fill yes
			(thermal_gap 0.5)
			(thermal_bridge_width 0.5)
			(island_removal_mode 0)
		)
		(polygon
			(pts
				(arc
					(start 416.00628 -410.030168)
					(mid 415.3027 -410.030168)
					(end 416.00628 -410.030168)
				)
			)
		)
	)
	(zone
		(layers "B.Cu" "In11.Cu" "In13.Cu" "In15.Cu")
		(hatch none 0.5)
		(connect_pads
			(clearance 0)
		)
		(min_thickness 0.25)
		(keepout
			(tracks not_allowed)
			(vias allowed)
			(pads allowed)
			(copperpour not_allowed)
			(footprints allowed)
		)
		(placement
			(enabled no)
			(sheetname "")
		)
		(fill yes
			(thermal_gap 0.5)
			(thermal_bridge_width 0.5)
			(island_removal_mode 0)
		)
		(polygon
			(pts
				(arc
					(start 344.040206 -276.708616)
					(mid 343.387426 -276.708616)
					(end 344.040206 -276.708616)
				)
			)
		)
	)
	(zone
		(layers "B.Cu" "In11.Cu" "In13.Cu" "In15.Cu")
		(hatch none 0.5)
		(connect_pads
			(clearance 0)
		)
		(min_thickness 0.25)
		(keepout
			(tracks not_allowed)
			(vias allowed)
			(pads allowed)
			(copperpour not_allowed)
			(footprints allowed)
		)
		(placement
			(enabled no)
			(sheetname "")
		)
		(fill yes
			(thermal_gap 0.5)
			(thermal_bridge_width 0.5)
			(island_removal_mode 0)
		)
		(polygon
			(pts
				(arc
					(start 188.209936 -284.016704)
					(mid 187.557156 -284.016704)
					(end 188.209936 -284.016704)
				)
			)
		)
	)
	(zone
		(layers "B.Cu" "In11.Cu" "In13.Cu" "In15.Cu")
		(hatch none 0.5)
		(connect_pads
			(clearance 0)
		)
		(min_thickness 0.25)
		(keepout
			(tracks not_allowed)
			(vias allowed)
			(pads allowed)
			(copperpour not_allowed)
			(footprints allowed)
		)
		(placement
			(enabled no)
			(sheetname "")
		)
		(fill yes
			(thermal_gap 0.5)
			(thermal_bridge_width 0.5)
			(island_removal_mode 0)
		)
		(polygon
			(pts
				(arc
					(start 353.095306 -64.465962)
					(mid 352.391726 -64.465962)
					(end 353.095306 -64.465962)
				)
			)
		)
	)
	(zone
		(layers "B.Cu" "In11.Cu" "In13.Cu" "In15.Cu")
		(hatch none 0.5)
		(connect_pads
			(clearance 0)
		)
		(min_thickness 0.25)
		(keepout
			(tracks not_allowed)
			(vias allowed)
			(pads allowed)
			(copperpour not_allowed)
			(footprints allowed)
		)
		(placement
			(enabled no)
			(sheetname "")
		)
		(fill yes
			(thermal_gap 0.5)
			(thermal_bridge_width 0.5)
			(island_removal_mode 0)
		)
		(polygon
			(pts
				(arc
					(start 95.520002 -241.481102)
					(mid 94.867222 -241.481102)
					(end 95.520002 -241.481102)
				)
			)
		)
	)
	(zone
		(layers "B.Cu" "In11.Cu" "In13.Cu" "In15.Cu")
		(hatch none 0.5)
		(connect_pads
			(clearance 0)
		)
		(min_thickness 0.25)
		(keepout
			(tracks not_allowed)
			(vias allowed)
			(pads allowed)
			(copperpour not_allowed)
			(footprints allowed)
		)
		(placement
			(enabled no)
			(sheetname "")
		)
		(fill yes
			(thermal_gap 0.5)
			(thermal_bridge_width 0.5)
			(island_removal_mode 0)
		)
		(polygon
			(pts
				(arc
					(start 213.712044 -5.1308)
					(mid 213.008464 -5.1308)
					(end 213.712044 -5.1308)
				)
			)
		)
	)
	(zone
		(layers "B.Cu" "In11.Cu" "In13.Cu" "In15.Cu")
		(hatch none 0.5)
		(connect_pads
			(clearance 0)
		)
		(min_thickness 0.25)
		(keepout
			(tracks not_allowed)
			(vias allowed)
			(pads allowed)
			(copperpour not_allowed)
			(footprints allowed)
		)
		(placement
			(enabled no)
			(sheetname "")
		)
		(fill yes
			(thermal_gap 0.5)
			(thermal_bridge_width 0.5)
			(island_removal_mode 0)
		)
		(polygon
			(pts
				(arc
					(start 409.154884 -430.689766)
					(mid 408.345132 -430.689766)
					(end 409.154884 -430.689766)
				)
			)
		)
	)
	(zone
		(layers "B.Cu" "In11.Cu" "In13.Cu" "In15.Cu")
		(hatch none 0.5)
		(connect_pads
			(clearance 0)
		)
		(min_thickness 0.25)
		(keepout
			(tracks not_allowed)
			(vias allowed)
			(pads allowed)
			(copperpour not_allowed)
			(footprints allowed)
		)
		(placement
			(enabled no)
			(sheetname "")
		)
		(fill yes
			(thermal_gap 0.5)
			(thermal_bridge_width 0.5)
			(island_removal_mode 0)
		)
		(polygon
			(pts
				(arc
					(start 192.268094 -300.166786)
					(mid 191.615314 -300.166786)
					(end 192.268094 -300.166786)
				)
			)
		)
	)
	(zone
		(layers "B.Cu" "In11.Cu" "In13.Cu" "In15.Cu")
		(hatch none 0.5)
		(connect_pads
			(clearance 0)
		)
		(min_thickness 0.25)
		(keepout
			(tracks not_allowed)
			(vias allowed)
			(pads allowed)
			(copperpour not_allowed)
			(footprints allowed)
		)
		(placement
			(enabled no)
			(sheetname "")
		)
		(fill yes
			(thermal_gap 0.5)
			(thermal_bridge_width 0.5)
			(island_removal_mode 0)
		)
		(polygon
			(pts
				(arc
					(start 121.834402 -215.436704)
					(mid 121.181622 -215.436704)
					(end 121.834402 -215.436704)
				)
			)
		)
	)
	(zone
		(layers "B.Cu" "In11.Cu" "In13.Cu" "In15.Cu")
		(hatch none 0.5)
		(connect_pads
			(clearance 0)
		)
		(min_thickness 0.25)
		(keepout
			(tracks not_allowed)
			(vias allowed)
			(pads allowed)
			(copperpour not_allowed)
			(footprints allowed)
		)
		(placement
			(enabled no)
			(sheetname "")
		)
		(fill yes
			(thermal_gap 0.5)
			(thermal_bridge_width 0.5)
			(island_removal_mode 0)
		)
		(polygon
			(pts
				(arc
					(start 379.752606 -279.964134)
					(mid 379.099826 -279.964134)
					(end 379.752606 -279.964134)
				)
			)
		)
	)
	(zone
		(layers "B.Cu" "In11.Cu" "In13.Cu" "In15.Cu")
		(hatch none 0.5)
		(connect_pads
			(clearance 0)
		)
		(min_thickness 0.25)
		(keepout
			(tracks not_allowed)
			(vias allowed)
			(pads allowed)
			(copperpour not_allowed)
			(footprints allowed)
		)
		(placement
			(enabled no)
			(sheetname "")
		)
		(fill yes
			(thermal_gap 0.5)
			(thermal_bridge_width 0.5)
			(island_removal_mode 0)
		)
		(polygon
			(pts
				(arc
					(start 53.604668 -410.030168)
					(mid 52.901088 -410.030168)
					(end 53.604668 -410.030168)
				)
			)
		)
	)
	(zone
		(layers "B.Cu" "In11.Cu" "In13.Cu" "In15.Cu")
		(hatch none 0.5)
		(connect_pads
			(clearance 0)
		)
		(min_thickness 0.25)
		(keepout
			(tracks not_allowed)
			(vias allowed)
			(pads allowed)
			(copperpour not_allowed)
			(footprints allowed)
		)
		(placement
			(enabled no)
			(sheetname "")
		)
		(fill yes
			(thermal_gap 0.5)
			(thermal_bridge_width 0.5)
			(island_removal_mode 0)
		)
		(polygon
			(pts
				(arc
					(start 16.306292 -105.6005)
					(mid 15.602712 -105.6005)
					(end 16.306292 -105.6005)
				)
			)
		)
	)
	(zone
		(layers "B.Cu" "In11.Cu" "In13.Cu" "In15.Cu")
		(hatch none 0.5)
		(connect_pads
			(clearance 0)
		)
		(min_thickness 0.25)
		(keepout
			(tracks not_allowed)
			(vias allowed)
			(pads allowed)
			(copperpour not_allowed)
			(footprints allowed)
		)
		(placement
			(enabled no)
			(sheetname "")
		)
		(fill yes
			(thermal_gap 0.5)
			(thermal_bridge_width 0.5)
			(island_removal_mode 0)
		)
		(polygon
			(pts
				(arc
					(start 192.310004 -283.166566)
					(mid 191.657224 -283.166566)
					(end 192.310004 -283.166566)
				)
			)
		)
	)
	(zone
		(layers "B.Cu" "In11.Cu" "In13.Cu" "In15.Cu")
		(hatch none 0.5)
		(connect_pads
			(clearance 0)
		)
		(min_thickness 0.25)
		(keepout
			(tracks not_allowed)
			(vias allowed)
			(pads allowed)
			(copperpour not_allowed)
			(footprints allowed)
		)
		(placement
			(enabled no)
			(sheetname "")
		)
		(fill yes
			(thermal_gap 0.5)
			(thermal_bridge_width 0.5)
			(island_removal_mode 0)
		)
		(polygon
			(pts
				(arc
					(start 126.154942 -429.689768)
					(mid 125.34519 -429.689768)
					(end 126.154942 -429.689768)
				)
			)
		)
	)
	(zone
		(layers "B.Cu" "In11.Cu" "In13.Cu" "In15.Cu")
		(hatch none 0.5)
		(connect_pads
			(clearance 0)
		)
		(min_thickness 0.25)
		(keepout
			(tracks not_allowed)
			(vias allowed)
			(pads allowed)
			(copperpour not_allowed)
			(footprints allowed)
		)
		(placement
			(enabled no)
			(sheetname "")
		)
		(fill yes
			(thermal_gap 0.5)
			(thermal_bridge_width 0.5)
			(island_removal_mode 0)
		)
		(polygon
			(pts
				(arc
					(start 343.570052 -269.38351)
					(mid 342.917272 -269.38351)
					(end 343.570052 -269.38351)
				)
			)
		)
	)
	(zone
		(layers "B.Cu" "In11.Cu" "In13.Cu" "In15.Cu")
		(hatch none 0.5)
		(connect_pads
			(clearance 0)
		)
		(min_thickness 0.25)
		(keepout
			(tracks not_allowed)
			(vias allowed)
			(pads allowed)
			(copperpour not_allowed)
			(footprints allowed)
		)
		(placement
			(enabled no)
			(sheetname "")
		)
		(fill yes
			(thermal_gap 0.5)
			(thermal_bridge_width 0.5)
			(island_removal_mode 0)
		)
		(polygon
			(pts
				(arc
					(start 377.04776 -410.030168)
					(mid 376.34418 -410.030168)
					(end 377.04776 -410.030168)
				)
			)
		)
	)
	(zone
		(layers "B.Cu" "In11.Cu" "In13.Cu" "In15.Cu")
		(hatch none 0.5)
		(connect_pads
			(clearance 0)
		)
		(min_thickness 0.25)
		(keepout
			(tracks not_allowed)
			(vias allowed)
			(pads allowed)
			(copperpour not_allowed)
			(footprints allowed)
		)
		(placement
			(enabled no)
			(sheetname "")
		)
		(fill yes
			(thermal_gap 0.5)
			(thermal_bridge_width 0.5)
			(island_removal_mode 0)
		)
		(polygon
			(pts
				(arc
					(start 338.761324 -213.732618)
					(mid 338.108544 -213.732618)
					(end 338.761324 -213.732618)
				)
			)
		)
	)
	(zone
		(layers "B.Cu" "In11.Cu" "In13.Cu" "In15.Cu")
		(hatch none 0.5)
		(connect_pads
			(clearance 0)
		)
		(min_thickness 0.25)
		(keepout
			(tracks not_allowed)
			(vias allowed)
			(pads allowed)
			(copperpour not_allowed)
			(footprints allowed)
		)
		(placement
			(enabled no)
			(sheetname "")
		)
		(fill yes
			(thermal_gap 0.5)
			(thermal_bridge_width 0.5)
			(island_removal_mode 0)
		)
		(polygon
			(pts
				(arc
					(start 84.05495 -427.289976)
					(mid 83.245198 -427.289976)
					(end 84.05495 -427.289976)
				)
			)
		)
	)
	(zone
		(layers "B.Cu" "In11.Cu" "In13.Cu" "In15.Cu")
		(hatch none 0.5)
		(connect_pads
			(clearance 0)
		)
		(min_thickness 0.25)
		(keepout
			(tracks not_allowed)
			(vias allowed)
			(pads allowed)
			(copperpour not_allowed)
			(footprints allowed)
		)
		(placement
			(enabled no)
			(sheetname "")
		)
		(fill yes
			(thermal_gap 0.5)
			(thermal_bridge_width 0.5)
			(island_removal_mode 0)
		)
		(polygon
			(pts
				(arc
					(start 192.310004 -302.716692)
					(mid 191.657224 -302.716692)
					(end 192.310004 -302.716692)
				)
			)
		)
	)
	(zone
		(layers "B.Cu" "In11.Cu" "In13.Cu" "In15.Cu")
		(hatch none 0.5)
		(connect_pads
			(clearance 0)
		)
		(min_thickness 0.25)
		(keepout
			(tracks not_allowed)
			(vias allowed)
			(pads allowed)
			(copperpour not_allowed)
			(footprints allowed)
		)
		(placement
			(enabled no)
			(sheetname "")
		)
		(fill yes
			(thermal_gap 0.5)
			(thermal_bridge_width 0.5)
			(island_removal_mode 0)
		)
		(polygon
			(pts
				(arc
					(start 343.930224 -237.411514)
					(mid 343.277444 -237.411514)
					(end 343.930224 -237.411514)
				)
			)
		)
	)
	(zone
		(layers "B.Cu" "In11.Cu" "In13.Cu" "In15.Cu")
		(hatch none 0.5)
		(connect_pads
			(clearance 0)
		)
		(min_thickness 0.25)
		(keepout
			(tracks not_allowed)
			(vias allowed)
			(pads allowed)
			(copperpour not_allowed)
			(footprints allowed)
		)
		(placement
			(enabled no)
			(sheetname "")
		)
		(fill yes
			(thermal_gap 0.5)
			(thermal_bridge_width 0.5)
			(island_removal_mode 0)
		)
		(polygon
			(pts
				(arc
					(start 354.226114 -176.201832)
					(mid 353.522534 -176.201832)
					(end 354.226114 -176.201832)
				)
			)
		)
	)
	(zone
		(layers "B.Cu" "In11.Cu" "In13.Cu" "In15.Cu")
		(hatch none 0.5)
		(connect_pads
			(clearance 0)
		)
		(min_thickness 0.25)
		(keepout
			(tracks not_allowed)
			(vias allowed)
			(pads allowed)
			(copperpour not_allowed)
			(footprints allowed)
		)
		(placement
			(enabled no)
			(sheetname "")
		)
		(fill yes
			(thermal_gap 0.5)
			(thermal_bridge_width 0.5)
			(island_removal_mode 0)
		)
		(polygon
			(pts
				(arc
					(start 394.154914 -438.089802)
					(mid 393.345162 -438.089802)
					(end 394.154914 -438.089802)
				)
			)
		)
	)
	(zone
		(layers "B.Cu" "In11.Cu" "In13.Cu" "In15.Cu")
		(hatch none 0.5)
		(connect_pads
			(clearance 0)
		)
		(min_thickness 0.25)
		(keepout
			(tracks not_allowed)
			(vias allowed)
			(pads allowed)
			(copperpour not_allowed)
			(footprints allowed)
		)
		(placement
			(enabled no)
			(sheetname "")
		)
		(fill yes
			(thermal_gap 0.5)
			(thermal_bridge_width 0.5)
			(island_removal_mode 0)
		)
		(polygon
			(pts
				(arc
					(start 344.870024 -230.900478)
					(mid 344.217244 -230.900478)
					(end 344.870024 -230.900478)
				)
			)
		)
	)
	(zone
		(layers "B.Cu" "In11.Cu" "In13.Cu" "In15.Cu")
		(hatch none 0.5)
		(connect_pads
			(clearance 0)
		)
		(min_thickness 0.25)
		(keepout
			(tracks not_allowed)
			(vias allowed)
			(pads allowed)
			(copperpour not_allowed)
			(footprints allowed)
		)
		(placement
			(enabled no)
			(sheetname "")
		)
		(fill yes
			(thermal_gap 0.5)
			(thermal_bridge_width 0.5)
			(island_removal_mode 0)
		)
		(polygon
			(pts
				(arc
					(start 139.220702 -219.506038)
					(mid 138.567922 -219.506038)
					(end 139.220702 -219.506038)
				)
			)
		)
	)
	(zone
		(layers "B.Cu" "In11.Cu" "In13.Cu" "In15.Cu")
		(hatch none 0.5)
		(connect_pads
			(clearance 0)
		)
		(min_thickness 0.25)
		(keepout
			(tracks not_allowed)
			(vias allowed)
			(pads allowed)
			(copperpour not_allowed)
			(footprints allowed)
		)
		(placement
			(enabled no)
			(sheetname "")
		)
		(fill yes
			(thermal_gap 0.5)
			(thermal_bridge_width 0.5)
			(island_removal_mode 0)
		)
		(polygon
			(pts
				(arc
					(start 284.243272 -284.016704)
					(mid 283.590492 -284.016704)
					(end 284.243272 -284.016704)
				)
			)
		)
	)
	(zone
		(layers "B.Cu" "In11.Cu" "In13.Cu" "In15.Cu")
		(hatch none 0.5)
		(connect_pads
			(clearance 0)
		)
		(min_thickness 0.25)
		(keepout
			(tracks not_allowed)
			(vias allowed)
			(pads allowed)
			(copperpour not_allowed)
			(footprints allowed)
		)
		(placement
			(enabled no)
			(sheetname "")
		)
		(fill yes
			(thermal_gap 0.5)
			(thermal_bridge_width 0.5)
			(island_removal_mode 0)
		)
		(polygon
			(pts
				(arc
					(start 284.243272 -304.416714)
					(mid 283.590492 -304.416714)
					(end 284.243272 -304.416714)
				)
			)
		)
	)
	(zone
		(layers "B.Cu" "In11.Cu" "In13.Cu" "In15.Cu")
		(hatch none 0.5)
		(connect_pads
			(clearance 0)
		)
		(min_thickness 0.25)
		(keepout
			(tracks not_allowed)
			(vias allowed)
			(pads allowed)
			(copperpour not_allowed)
			(footprints allowed)
		)
		(placement
			(enabled no)
			(sheetname "")
		)
		(fill yes
			(thermal_gap 0.5)
			(thermal_bridge_width 0.5)
			(island_removal_mode 0)
		)
		(polygon
			(pts
				(arc
					(start 36.303204 -300.166786)
					(mid 35.650424 -300.166786)
					(end 36.303204 -300.166786)
				)
			)
		)
	)
	(zone
		(layers "B.Cu" "In11.Cu" "In13.Cu" "In15.Cu")
		(hatch none 0.5)
		(connect_pads
			(clearance 0)
		)
		(min_thickness 0.25)
		(keepout
			(tracks not_allowed)
			(vias allowed)
			(pads allowed)
			(copperpour not_allowed)
			(footprints allowed)
		)
		(placement
			(enabled no)
			(sheetname "")
		)
		(fill yes
			(thermal_gap 0.5)
			(thermal_bridge_width 0.5)
			(island_removal_mode 0)
		)
		(polygon
			(pts
				(arc
					(start 376.823224 -235.783882)
					(mid 376.170444 -235.783882)
					(end 376.823224 -235.783882)
				)
			)
		)
	)
	(zone
		(layers "B.Cu" "In11.Cu" "In13.Cu" "In15.Cu")
		(hatch none 0.5)
		(connect_pads
			(clearance 0)
		)
		(min_thickness 0.25)
		(keepout
			(tracks not_allowed)
			(vias allowed)
			(pads allowed)
			(copperpour not_allowed)
			(footprints allowed)
		)
		(placement
			(enabled no)
			(sheetname "")
		)
		(fill yes
			(thermal_gap 0.5)
			(thermal_bridge_width 0.5)
			(island_removal_mode 0)
		)
		(polygon
			(pts
				(arc
					(start 440.250072 -220.266768)
					(mid 439.597292 -220.266768)
					(end 440.250072 -220.266768)
				)
			)
		)
	)
	(zone
		(layers "B.Cu" "In11.Cu" "In13.Cu" "In15.Cu")
		(hatch none 0.5)
		(connect_pads
			(clearance 0)
		)
		(min_thickness 0.25)
		(keepout
			(tracks not_allowed)
			(vias allowed)
			(pads allowed)
			(copperpour not_allowed)
			(footprints allowed)
		)
		(placement
			(enabled no)
			(sheetname "")
		)
		(fill yes
			(thermal_gap 0.5)
			(thermal_bridge_width 0.5)
			(island_removal_mode 0)
		)
		(polygon
			(pts
				(arc
					(start 192.268094 -301.866808)
					(mid 191.615314 -301.866808)
					(end 192.268094 -301.866808)
				)
			)
		)
	)
	(zone
		(layers "B.Cu" "In11.Cu" "In13.Cu" "In15.Cu")
		(hatch none 0.5)
		(connect_pads
			(clearance 0)
		)
		(min_thickness 0.25)
		(keepout
			(tracks not_allowed)
			(vias allowed)
			(pads allowed)
			(copperpour not_allowed)
			(footprints allowed)
		)
		(placement
			(enabled no)
			(sheetname "")
		)
		(fill yes
			(thermal_gap 0.5)
			(thermal_bridge_width 0.5)
			(island_removal_mode 0)
		)
		(polygon
			(pts
				(arc
					(start 123.243848 -214.622634)
					(mid 122.591068 -214.622634)
					(end 123.243848 -214.622634)
				)
			)
		)
	)
	(zone
		(layers "B.Cu" "In11.Cu" "In13.Cu" "In15.Cu")
		(hatch none 0.5)
		(connect_pads
			(clearance 0)
		)
		(min_thickness 0.25)
		(keepout
			(tracks not_allowed)
			(vias allowed)
			(pads allowed)
			(copperpour not_allowed)
			(footprints allowed)
		)
		(placement
			(enabled no)
			(sheetname "")
		)
		(fill yes
			(thermal_gap 0.5)
			(thermal_bridge_width 0.5)
			(island_removal_mode 0)
		)
		(polygon
			(pts
				(arc
					(start 353.907852 -280.778204)
					(mid 353.255072 -280.778204)
					(end 353.907852 -280.778204)
				)
			)
		)
	)
	(zone
		(layers "B.Cu" "In11.Cu" "In13.Cu" "In15.Cu")
		(hatch none 0.5)
		(connect_pads
			(clearance 0)
		)
		(min_thickness 0.25)
		(keepout
			(tracks not_allowed)
			(vias allowed)
			(pads allowed)
			(copperpour not_allowed)
			(footprints allowed)
		)
		(placement
			(enabled no)
			(sheetname "")
		)
		(fill yes
			(thermal_gap 0.5)
			(thermal_bridge_width 0.5)
			(island_removal_mode 0)
		)
		(polygon
			(pts
				(arc
					(start 458.781404 -243.216684)
					(mid 458.128624 -243.216684)
					(end 458.781404 -243.216684)
				)
			)
		)
	)
	(zone
		(layers "B.Cu" "In11.Cu" "In13.Cu" "In15.Cu")
		(hatch none 0.5)
		(connect_pads
			(clearance 0)
		)
		(min_thickness 0.25)
		(keepout
			(tracks not_allowed)
			(vias allowed)
			(pads allowed)
			(copperpour not_allowed)
			(footprints allowed)
		)
		(placement
			(enabled no)
			(sheetname "")
		)
		(fill yes
			(thermal_gap 0.5)
			(thermal_bridge_width 0.5)
			(island_removal_mode 0)
		)
		(polygon
			(pts
				(arc
					(start 101.628448 -214.622634)
					(mid 100.975668 -214.622634)
					(end 101.628448 -214.622634)
				)
			)
		)
	)
	(zone
		(layers "B.Cu" "In11.Cu" "In13.Cu" "In15.Cu")
		(hatch none 0.5)
		(connect_pads
			(clearance 0)
		)
		(min_thickness 0.25)
		(keepout
			(tracks not_allowed)
			(vias allowed)
			(pads allowed)
			(copperpour not_allowed)
			(footprints allowed)
		)
		(placement
			(enabled no)
			(sheetname "")
		)
		(fill yes
			(thermal_gap 0.5)
			(thermal_bridge_width 0.5)
			(island_removal_mode 0)
		)
		(polygon
			(pts
				(arc
					(start 440.250072 -274.66671)
					(mid 439.597292 -274.66671)
					(end 440.250072 -274.66671)
				)
			)
		)
	)
	(zone
		(layers "B.Cu" "In11.Cu" "In13.Cu" "In15.Cu")
		(hatch none 0.5)
		(connect_pads
			(clearance 0)
		)
		(min_thickness 0.25)
		(keepout
			(tracks not_allowed)
			(vias allowed)
			(pads allowed)
			(copperpour not_allowed)
			(footprints allowed)
		)
		(placement
			(enabled no)
			(sheetname "")
		)
		(fill yes
			(thermal_gap 0.5)
			(thermal_bridge_width 0.5)
			(island_removal_mode 0)
		)
		(polygon
			(pts
				(arc
					(start 97.869756 -242.294918)
					(mid 97.216976 -242.294918)
					(end 97.869756 -242.294918)
				)
			)
		)
	)
	(zone
		(layers "B.Cu" "In11.Cu" "In13.Cu" "In15.Cu")
		(hatch none 0.5)
		(connect_pads
			(clearance 0)
		)
		(min_thickness 0.25)
		(keepout
			(tracks not_allowed)
			(vias allowed)
			(pads allowed)
			(copperpour not_allowed)
			(footprints allowed)
		)
		(placement
			(enabled no)
			(sheetname "")
		)
		(fill yes
			(thermal_gap 0.5)
			(thermal_bridge_width 0.5)
			(island_removal_mode 0)
		)
		(polygon
			(pts
				(arc
					(start 188.209936 -278.916638)
					(mid 187.557156 -278.916638)
					(end 188.209936 -278.916638)
				)
			)
		)
	)
	(zone
		(layers "B.Cu" "In11.Cu" "In13.Cu" "In15.Cu")
		(hatch none 0.5)
		(connect_pads
			(clearance 0)
		)
		(min_thickness 0.25)
		(keepout
			(tracks not_allowed)
			(vias allowed)
			(pads allowed)
			(copperpour not_allowed)
			(footprints allowed)
		)
		(placement
			(enabled no)
			(sheetname "")
		)
		(fill yes
			(thermal_gap 0.5)
			(thermal_bridge_width 0.5)
			(island_removal_mode 0)
		)
		(polygon
			(pts
				(arc
					(start 409.8798 -410.030168)
					(mid 409.17622 -410.030168)
					(end 409.8798 -410.030168)
				)
			)
		)
	)
	(zone
		(layers "B.Cu" "In11.Cu" "In13.Cu" "In15.Cu")
		(hatch none 0.5)
		(connect_pads
			(clearance 0)
		)
		(min_thickness 0.25)
		(keepout
			(tracks not_allowed)
			(vias allowed)
			(pads allowed)
			(copperpour not_allowed)
			(footprints allowed)
		)
		(placement
			(enabled no)
			(sheetname "")
		)
		(fill yes
			(thermal_gap 0.5)
			(thermal_bridge_width 0.5)
			(island_removal_mode 0)
		)
		(polygon
			(pts
				(arc
					(start 374.259094 -178.026568)
					(mid 373.555514 -178.026568)
					(end 374.259094 -178.026568)
				)
			)
		)
	)
	(zone
		(layers "B.Cu" "In11.Cu" "In13.Cu" "In15.Cu")
		(hatch none 0.5)
		(connect_pads
			(clearance 0)
		)
		(min_thickness 0.25)
		(keepout
			(tracks not_allowed)
			(vias allowed)
			(pads allowed)
			(copperpour not_allowed)
			(footprints allowed)
		)
		(placement
			(enabled no)
			(sheetname "")
		)
		(fill yes
			(thermal_gap 0.5)
			(thermal_bridge_width 0.5)
			(island_removal_mode 0)
		)
		(polygon
			(pts
				(arc
					(start 403.75332 -410.030168)
					(mid 403.04974 -410.030168)
					(end 403.75332 -410.030168)
				)
			)
		)
	)
	(zone
		(layers "B.Cu" "In11.Cu" "In13.Cu" "In15.Cu")
		(hatch none 0.5)
		(connect_pads
			(clearance 0)
		)
		(min_thickness 0.25)
		(keepout
			(tracks not_allowed)
			(vias allowed)
			(pads allowed)
			(copperpour not_allowed)
			(footprints allowed)
		)
		(placement
			(enabled no)
			(sheetname "")
		)
		(fill yes
			(thermal_gap 0.5)
			(thermal_bridge_width 0.5)
			(island_removal_mode 0)
		)
		(polygon
			(pts
				(arc
					(start 335.111852 -287.28924)
					(mid 334.459072 -287.28924)
					(end 335.111852 -287.28924)
				)
			)
		)
	)
	(zone
		(layers "B.Cu" "In11.Cu" "In13.Cu" "In15.Cu")
		(hatch none 0.5)
		(connect_pads
			(clearance 0)
		)
		(min_thickness 0.25)
		(keepout
			(tracks not_allowed)
			(vias allowed)
			(pads allowed)
			(copperpour not_allowed)
			(footprints allowed)
		)
		(placement
			(enabled no)
			(sheetname "")
		)
		(fill yes
			(thermal_gap 0.5)
			(thermal_bridge_width 0.5)
			(island_removal_mode 0)
		)
		(polygon
			(pts
				(arc
					(start 440.250072 -214.316564)
					(mid 439.597292 -214.316564)
					(end 440.250072 -214.316564)
				)
			)
		)
	)
	(zone
		(layers "B.Cu" "In11.Cu" "In13.Cu" "In15.Cu")
		(hatch none 0.5)
		(connect_pads
			(clearance 0)
		)
		(min_thickness 0.25)
		(keepout
			(tracks not_allowed)
			(vias allowed)
			(pads allowed)
			(copperpour not_allowed)
			(footprints allowed)
		)
		(placement
			(enabled no)
			(sheetname "")
		)
		(fill yes
			(thermal_gap 0.5)
			(thermal_bridge_width 0.5)
			(island_removal_mode 0)
		)
		(polygon
			(pts
				(arc
					(start 265.055604 -310.366664)
					(mid 264.402824 -310.366664)
					(end 265.055604 -310.366664)
				)
			)
		)
	)
	(zone
		(layers "B.Cu" "In11.Cu" "In13.Cu" "In15.Cu")
		(hatch none 0.5)
		(connect_pads
			(clearance 0)
		)
		(min_thickness 0.25)
		(keepout
			(tracks not_allowed)
			(vias allowed)
			(pads allowed)
			(copperpour not_allowed)
			(footprints allowed)
		)
		(placement
			(enabled no)
			(sheetname "")
		)
		(fill yes
			(thermal_gap 0.5)
			(thermal_bridge_width 0.5)
			(island_removal_mode 0)
		)
		(polygon
			(pts
				(arc
					(start 192.310004 -216.016586)
					(mid 191.657224 -216.016586)
					(end 192.310004 -216.016586)
				)
			)
		)
	)
	(zone
		(layers "B.Cu" "In11.Cu" "In13.Cu" "In15.Cu")
		(hatch none 0.5)
		(connect_pads
			(clearance 0)
		)
		(min_thickness 0.25)
		(keepout
			(tracks not_allowed)
			(vias allowed)
			(pads allowed)
			(copperpour not_allowed)
			(footprints allowed)
		)
		(placement
			(enabled no)
			(sheetname "")
		)
		(fill yes
			(thermal_gap 0.5)
			(thermal_bridge_width 0.5)
			(island_removal_mode 0)
		)
		(polygon
			(pts
				(arc
					(start 375.053606 -276.708616)
					(mid 374.400826 -276.708616)
					(end 375.053606 -276.708616)
				)
			)
		)
	)
	(zone
		(layers "B.Cu" "In11.Cu" "In13.Cu" "In15.Cu")
		(hatch none 0.5)
		(connect_pads
			(clearance 0)
		)
		(min_thickness 0.25)
		(keepout
			(tracks not_allowed)
			(vias allowed)
			(pads allowed)
			(copperpour not_allowed)
			(footprints allowed)
		)
		(placement
			(enabled no)
			(sheetname "")
		)
		(fill yes
			(thermal_gap 0.5)
			(thermal_bridge_width 0.5)
			(island_removal_mode 0)
		)
		(polygon
			(pts
				(arc
					(start 123.714002 -215.436704)
					(mid 123.061222 -215.436704)
					(end 123.714002 -215.436704)
				)
			)
		)
	)
	(zone
		(layers "B.Cu" "In11.Cu" "In13.Cu" "In15.Cu")
		(hatch none 0.5)
		(connect_pads
			(clearance 0)
		)
		(min_thickness 0.25)
		(keepout
			(tracks not_allowed)
			(vias allowed)
			(pads allowed)
			(copperpour not_allowed)
			(footprints allowed)
		)
		(placement
			(enabled no)
			(sheetname "")
		)
		(fill yes
			(thermal_gap 0.5)
			(thermal_bridge_width 0.5)
			(island_removal_mode 0)
		)
		(polygon
			(pts
				(arc
					(start 345.33967 -233.34218)
					(mid 344.68689 -233.34218)
					(end 345.33967 -233.34218)
				)
			)
		)
	)
	(zone
		(layers "B.Cu" "In11.Cu" "In13.Cu" "In15.Cu")
		(hatch none 0.5)
		(connect_pads
			(clearance 0)
		)
		(min_thickness 0.25)
		(keepout
			(tracks not_allowed)
			(vias allowed)
			(pads allowed)
			(copperpour not_allowed)
			(footprints allowed)
		)
		(placement
			(enabled no)
			(sheetname "")
		)
		(fill yes
			(thermal_gap 0.5)
			(thermal_bridge_width 0.5)
			(island_removal_mode 0)
		)
		(polygon
			(pts
				(arc
					(start 352.388424 -227.64496)
					(mid 351.735644 -227.64496)
					(end 352.388424 -227.64496)
				)
			)
		)
	)
	(zone
		(layers "B.Cu" "In11.Cu" "In13.Cu" "In15.Cu")
		(hatch none 0.5)
		(connect_pads
			(clearance 0)
		)
		(min_thickness 0.25)
		(keepout
			(tracks not_allowed)
			(vias allowed)
			(pads allowed)
			(copperpour not_allowed)
			(footprints allowed)
		)
		(placement
			(enabled no)
			(sheetname "")
		)
		(fill yes
			(thermal_gap 0.5)
			(thermal_bridge_width 0.5)
			(island_removal_mode 0)
		)
		(polygon
			(pts
				(arc
					(start 97.039938 -265.314176)
					(mid 96.387158 -265.314176)
					(end 97.039938 -265.314176)
				)
			)
		)
	)
	(zone
		(layers "B.Cu" "In11.Cu" "In13.Cu" "In15.Cu")
		(hatch none 0.5)
		(connect_pads
			(clearance 0)
		)
		(min_thickness 0.25)
		(keepout
			(tracks not_allowed)
			(vias allowed)
			(pads allowed)
			(copperpour not_allowed)
			(footprints allowed)
		)
		(placement
			(enabled no)
			(sheetname "")
		)
		(fill yes
			(thermal_gap 0.5)
			(thermal_bridge_width 0.5)
			(island_removal_mode 0)
		)
		(polygon
			(pts
				(arc
					(start 36.303204 -201.56678)
					(mid 35.650424 -201.56678)
					(end 36.303204 -201.56678)
				)
			)
		)
	)
	(zone
		(layers "B.Cu" "In11.Cu" "In13.Cu" "In15.Cu")
		(hatch none 0.5)
		(connect_pads
			(clearance 0)
		)
		(min_thickness 0.25)
		(keepout
			(tracks not_allowed)
			(vias allowed)
			(pads allowed)
			(copperpour not_allowed)
			(footprints allowed)
		)
		(placement
			(enabled no)
			(sheetname "")
		)
		(fill yes
			(thermal_gap 0.5)
			(thermal_bridge_width 0.5)
			(island_removal_mode 0)
		)
		(polygon
			(pts
				(arc
					(start 388.43712 -410.030168)
					(mid 387.73354 -410.030168)
					(end 388.43712 -410.030168)
				)
			)
		)
	)
	(zone
		(layers "B.Cu" "In11.Cu" "In13.Cu" "In15.Cu")
		(hatch none 0.5)
		(connect_pads
			(clearance 0)
		)
		(min_thickness 0.25)
		(keepout
			(tracks not_allowed)
			(vias allowed)
			(pads allowed)
			(copperpour not_allowed)
			(footprints allowed)
		)
		(placement
			(enabled no)
			(sheetname "")
		)
		(fill yes
			(thermal_gap 0.5)
			(thermal_bridge_width 0.5)
			(island_removal_mode 0)
		)
		(polygon
			(pts
				(arc
					(start 203.297536 -316.316614)
					(mid 202.644756 -316.316614)
					(end 203.297536 -316.316614)
				)
			)
		)
	)
	(zone
		(layers "B.Cu" "In11.Cu" "In13.Cu" "In15.Cu")
		(hatch none 0.5)
		(connect_pads
			(clearance 0)
		)
		(min_thickness 0.25)
		(keepout
			(tracks not_allowed)
			(vias allowed)
			(pads allowed)
			(copperpour not_allowed)
			(footprints allowed)
		)
		(placement
			(enabled no)
			(sheetname "")
		)
		(fill yes
			(thermal_gap 0.5)
			(thermal_bridge_width 0.5)
			(island_removal_mode 0)
		)
		(polygon
			(pts
				(arc
					(start 374.259094 -181.709568)
					(mid 373.555514 -181.709568)
					(end 374.259094 -181.709568)
				)
			)
		)
	)
	(zone
		(layers "B.Cu" "In11.Cu" "In13.Cu" "In15.Cu")
		(hatch none 0.5)
		(connect_pads
			(clearance 0)
		)
		(min_thickness 0.25)
		(keepout
			(tracks not_allowed)
			(vias allowed)
			(pads allowed)
			(copperpour not_allowed)
			(footprints allowed)
		)
		(placement
			(enabled no)
			(sheetname "")
		)
		(fill yes
			(thermal_gap 0.5)
			(thermal_bridge_width 0.5)
			(island_removal_mode 0)
		)
		(polygon
			(pts
				(arc
					(start 384.154934 -437.889904)
					(mid 383.345182 -437.889904)
					(end 384.154934 -437.889904)
				)
			)
		)
	)
	(zone
		(layers "B.Cu" "In11.Cu" "In13.Cu" "In15.Cu")
		(hatch none 0.5)
		(connect_pads
			(clearance 0)
		)
		(min_thickness 0.25)
		(keepout
			(tracks not_allowed)
			(vias allowed)
			(pads allowed)
			(copperpour not_allowed)
			(footprints allowed)
		)
		(placement
			(enabled no)
			(sheetname "")
		)
		(fill yes
			(thermal_gap 0.5)
			(thermal_bridge_width 0.5)
			(island_removal_mode 0)
		)
		(polygon
			(pts
				(arc
					(start 127.583184 -254.733552)
					(mid 126.930404 -254.733552)
					(end 127.583184 -254.733552)
				)
			)
		)
	)
	(zone
		(layers "B.Cu" "In11.Cu" "In13.Cu" "In15.Cu")
		(hatch none 0.5)
		(connect_pads
			(clearance 0)
		)
		(min_thickness 0.25)
		(keepout
			(tracks not_allowed)
			(vias allowed)
			(pads allowed)
			(copperpour not_allowed)
			(footprints allowed)
		)
		(placement
			(enabled no)
			(sheetname "")
		)
		(fill yes
			(thermal_gap 0.5)
			(thermal_bridge_width 0.5)
			(island_removal_mode 0)
		)
		(polygon
			(pts
				(arc
					(start 373.53367 -247.992138)
					(mid 372.88089 -247.992138)
					(end 373.53367 -247.992138)
				)
			)
		)
	)
	(zone
		(layers "B.Cu" "In11.Cu" "In13.Cu" "In15.Cu")
		(hatch none 0.5)
		(connect_pads
			(clearance 0)
		)
		(min_thickness 0.25)
		(keepout
			(tracks not_allowed)
			(vias allowed)
			(pads allowed)
			(copperpour not_allowed)
			(footprints allowed)
		)
		(placement
			(enabled no)
			(sheetname "")
		)
		(fill yes
			(thermal_gap 0.5)
			(thermal_bridge_width 0.5)
			(island_removal_mode 0)
		)
		(polygon
			(pts
				(arc
					(start 119.484648 -214.622634)
					(mid 118.831868 -214.622634)
					(end 119.484648 -214.622634)
				)
			)
		)
	)
	(zone
		(layers "B.Cu" "In11.Cu" "In13.Cu" "In15.Cu")
		(hatch none 0.5)
		(connect_pads
			(clearance 0)
		)
		(min_thickness 0.25)
		(keepout
			(tracks not_allowed)
			(vias allowed)
			(pads allowed)
			(copperpour not_allowed)
			(footprints allowed)
		)
		(placement
			(enabled no)
			(sheetname "")
		)
		(fill yes
			(thermal_gap 0.5)
			(thermal_bridge_width 0.5)
			(island_removal_mode 0)
		)
		(polygon
			(pts
				(arc
					(start 128.413002 -243.108988)
					(mid 127.760222 -243.108988)
					(end 128.413002 -243.108988)
				)
			)
		)
	)
	(zone
		(layers "B.Cu" "In11.Cu" "In13.Cu" "In15.Cu")
		(hatch none 0.5)
		(connect_pads
			(clearance 0)
		)
		(min_thickness 0.25)
		(keepout
			(tracks not_allowed)
			(vias allowed)
			(pads allowed)
			(copperpour not_allowed)
			(footprints allowed)
		)
		(placement
			(enabled no)
			(sheetname "")
		)
		(fill yes
			(thermal_gap 0.5)
			(thermal_bridge_width 0.5)
			(island_removal_mode 0)
		)
		(polygon
			(pts
				(arc
					(start 327.054972 -434.48986)
					(mid 326.24522 -434.48986)
					(end 327.054972 -434.48986)
				)
			)
		)
	)
	(zone
		(layers "B.Cu" "In11.Cu" "In13.Cu" "In15.Cu")
		(hatch none 0.5)
		(connect_pads
			(clearance 0)
		)
		(min_thickness 0.25)
		(keepout
			(tracks not_allowed)
			(vias allowed)
			(pads allowed)
			(copperpour not_allowed)
			(footprints allowed)
		)
		(placement
			(enabled no)
			(sheetname "")
		)
		(fill yes
			(thermal_gap 0.5)
			(thermal_bridge_width 0.5)
			(island_removal_mode 0)
		)
		(polygon
			(pts
				(arc
					(start 344.040206 -265.314176)
					(mid 343.387426 -265.314176)
					(end 344.040206 -265.314176)
				)
			)
		)
	)
	(zone
		(layers "B.Cu" "In11.Cu" "In13.Cu" "In15.Cu")
		(hatch none 0.5)
		(connect_pads
			(clearance 0)
		)
		(min_thickness 0.25)
		(keepout
			(tracks not_allowed)
			(vias allowed)
			(pads allowed)
			(copperpour not_allowed)
			(footprints allowed)
		)
		(placement
			(enabled no)
			(sheetname "")
		)
		(fill yes
			(thermal_gap 0.5)
			(thermal_bridge_width 0.5)
			(island_removal_mode 0)
		)
		(polygon
			(pts
				(arc
					(start 280.143204 -199.866758)
					(mid 279.490424 -199.866758)
					(end 280.143204 -199.866758)
				)
			)
		)
	)
	(zone
		(layers "B.Cu" "In11.Cu" "In13.Cu" "In15.Cu")
		(hatch none 0.5)
		(connect_pads
			(clearance 0)
		)
		(min_thickness 0.25)
		(keepout
			(tracks not_allowed)
			(vias allowed)
			(pads allowed)
			(copperpour not_allowed)
			(footprints allowed)
		)
		(placement
			(enabled no)
			(sheetname "")
		)
		(fill yes
			(thermal_gap 0.5)
			(thermal_bridge_width 0.5)
			(island_removal_mode 0)
		)
		(polygon
			(pts
				(arc
					(start 382.154938 -436.889906)
					(mid 381.345186 -436.889906)
					(end 382.154938 -436.889906)
				)
			)
		)
	)
	(zone
		(layers "B.Cu" "In11.Cu" "In13.Cu" "In15.Cu")
		(hatch none 0.5)
		(connect_pads
			(clearance 0)
		)
		(min_thickness 0.25)
		(keepout
			(tracks not_allowed)
			(vias allowed)
			(pads allowed)
			(copperpour not_allowed)
			(footprints allowed)
		)
		(placement
			(enabled no)
			(sheetname "")
		)
		(fill yes
			(thermal_gap 0.5)
			(thermal_bridge_width 0.5)
			(island_removal_mode 0)
		)
		(polygon
			(pts
				(arc
					(start 345.809824 -227.64496)
					(mid 345.157044 -227.64496)
					(end 345.809824 -227.64496)
				)
			)
		)
	)
	(zone
		(layers "B.Cu" "In11.Cu" "In13.Cu" "In15.Cu")
		(hatch none 0.5)
		(connect_pads
			(clearance 0)
		)
		(min_thickness 0.25)
		(keepout
			(tracks not_allowed)
			(vias allowed)
			(pads allowed)
			(copperpour not_allowed)
			(footprints allowed)
		)
		(placement
			(enabled no)
			(sheetname "")
		)
		(fill yes
			(thermal_gap 0.5)
			(thermal_bridge_width 0.5)
			(island_removal_mode 0)
		)
		(polygon
			(pts
				(arc
					(start 375.41327 -234.970066)
					(mid 374.76049 -234.970066)
					(end 375.41327 -234.970066)
				)
			)
		)
	)
	(zone
		(layers "B.Cu" "In11.Cu" "In13.Cu" "In15.Cu")
		(hatch none 0.5)
		(connect_pads
			(clearance 0)
		)
		(min_thickness 0.25)
		(keepout
			(tracks not_allowed)
			(vias allowed)
			(pads allowed)
			(copperpour not_allowed)
			(footprints allowed)
		)
		(placement
			(enabled no)
			(sheetname "")
		)
		(fill yes
			(thermal_gap 0.5)
			(thermal_bridge_width 0.5)
			(island_removal_mode 0)
		)
		(polygon
			(pts
				(arc
					(start 95.520002 -226.831144)
					(mid 94.867222 -226.831144)
					(end 95.520002 -226.831144)
				)
			)
		)
	)
	(zone
		(layers "B.Cu" "In11.Cu" "In13.Cu" "In15.Cu")
		(hatch none 0.5)
		(connect_pads
			(clearance 0)
		)
		(min_thickness 0.25)
		(keepout
			(tracks not_allowed)
			(vias allowed)
			(pads allowed)
			(copperpour not_allowed)
			(footprints allowed)
		)
		(placement
			(enabled no)
			(sheetname "")
		)
		(fill yes
			(thermal_gap 0.5)
			(thermal_bridge_width 0.5)
			(island_removal_mode 0)
		)
		(polygon
			(pts
				(arc
					(start 90.054938 -434.289962)
					(mid 89.245186 -434.289962)
					(end 90.054938 -434.289962)
				)
			)
		)
	)
	(zone
		(layers "B.Cu" "In11.Cu" "In13.Cu" "In15.Cu")
		(hatch none 0.5)
		(connect_pads
			(clearance 0)
		)
		(min_thickness 0.25)
		(keepout
			(tracks not_allowed)
			(vias allowed)
			(pads allowed)
			(copperpour not_allowed)
			(footprints allowed)
		)
		(placement
			(enabled no)
			(sheetname "")
		)
		(fill yes
			(thermal_gap 0.5)
			(thermal_bridge_width 0.5)
			(island_removal_mode 0)
		)
		(polygon
			(pts
				(arc
					(start 192.310004 -195.616576)
					(mid 191.657224 -195.616576)
					(end 192.310004 -195.616576)
				)
			)
		)
	)
	(zone
		(layers "B.Cu" "In11.Cu" "In13.Cu" "In15.Cu")
		(hatch none 0.5)
		(connect_pads
			(clearance 0)
		)
		(min_thickness 0.25)
		(keepout
			(tracks not_allowed)
			(vias allowed)
			(pads allowed)
			(copperpour not_allowed)
			(footprints allowed)
		)
		(placement
			(enabled no)
			(sheetname "")
		)
		(fill yes
			(thermal_gap 0.5)
			(thermal_bridge_width 0.5)
			(island_removal_mode 0)
		)
		(polygon
			(pts
				(arc
					(start 374.47347 -230.086662)
					(mid 373.82069 -230.086662)
					(end 374.47347 -230.086662)
				)
			)
		)
	)
	(zone
		(layers "B.Cu" "In11.Cu" "In13.Cu" "In15.Cu")
		(hatch none 0.5)
		(connect_pads
			(clearance 0)
		)
		(min_thickness 0.25)
		(keepout
			(tracks not_allowed)
			(vias allowed)
			(pads allowed)
			(copperpour not_allowed)
			(footprints allowed)
		)
		(placement
			(enabled no)
			(sheetname "")
		)
		(fill yes
			(thermal_gap 0.5)
			(thermal_bridge_width 0.5)
			(island_removal_mode 0)
		)
		(polygon
			(pts
				(arc
					(start 147.1549 -429.689768)
					(mid 146.345148 -429.689768)
					(end 147.1549 -429.689768)
				)
			)
		)
	)
	(zone
		(layers "B.Cu" "In11.Cu" "In13.Cu" "In15.Cu")
		(hatch none 0.5)
		(connect_pads
			(clearance 0)
		)
		(min_thickness 0.25)
		(keepout
			(tracks not_allowed)
			(vias allowed)
			(pads allowed)
			(copperpour not_allowed)
			(footprints allowed)
		)
		(placement
			(enabled no)
			(sheetname "")
		)
		(fill yes
			(thermal_gap 0.5)
			(thermal_bridge_width 0.5)
			(island_removal_mode 0)
		)
		(polygon
			(pts
				(arc
					(start 32.203136 -272.966688)
					(mid 31.550356 -272.966688)
					(end 32.203136 -272.966688)
				)
			)
		)
	)
	(zone
		(layers "B.Cu" "In11.Cu" "In13.Cu" "In15.Cu")
		(hatch none 0.5)
		(connect_pads
			(clearance 0)
		)
		(min_thickness 0.25)
		(keepout
			(tracks not_allowed)
			(vias allowed)
			(pads allowed)
			(copperpour not_allowed)
			(footprints allowed)
		)
		(placement
			(enabled no)
			(sheetname "")
		)
		(fill yes
			(thermal_gap 0.5)
			(thermal_bridge_width 0.5)
			(island_removal_mode 0)
		)
		(polygon
			(pts
				(arc
					(start 157.15488 -437.889904)
					(mid 156.345128 -437.889904)
					(end 157.15488 -437.889904)
				)
			)
		)
	)
	(zone
		(layers "B.Cu" "In11.Cu" "In13.Cu" "In15.Cu")
		(hatch none 0.5)
		(connect_pads
			(clearance 0)
		)
		(min_thickness 0.25)
		(keepout
			(tracks not_allowed)
			(vias allowed)
			(pads allowed)
			(copperpour not_allowed)
			(footprints allowed)
		)
		(placement
			(enabled no)
			(sheetname "")
		)
		(fill yes
			(thermal_gap 0.5)
			(thermal_bridge_width 0.5)
			(island_removal_mode 0)
		)
		(polygon
			(pts
				(arc
					(start 125.593602 -215.436704)
					(mid 124.940822 -215.436704)
					(end 125.593602 -215.436704)
				)
			)
		)
	)
	(zone
		(layers "B.Cu" "In11.Cu" "In13.Cu" "In15.Cu")
		(hatch none 0.5)
		(connect_pads
			(clearance 0)
		)
		(min_thickness 0.25)
		(keepout
			(tracks not_allowed)
			(vias allowed)
			(pads allowed)
			(copperpour not_allowed)
			(footprints allowed)
		)
		(placement
			(enabled no)
			(sheetname "")
		)
		(fill yes
			(thermal_gap 0.5)
			(thermal_bridge_width 0.5)
			(island_removal_mode 0)
		)
		(polygon
			(pts
				(arc
					(start 343.930224 -235.783882)
					(mid 343.277444 -235.783882)
					(end 343.930224 -235.783882)
				)
			)
		)
	)
	(zone
		(layers "B.Cu" "In11.Cu" "In13.Cu" "In15.Cu")
		(hatch none 0.5)
		(connect_pads
			(clearance 0)
		)
		(min_thickness 0.25)
		(keepout
			(tracks not_allowed)
			(vias allowed)
			(pads allowed)
			(copperpour not_allowed)
			(footprints allowed)
		)
		(placement
			(enabled no)
			(sheetname "")
		)
		(fill yes
			(thermal_gap 0.5)
			(thermal_bridge_width 0.5)
			(island_removal_mode 0)
		)
		(polygon
			(pts
				(arc
					(start 440.250072 -197.316598)
					(mid 439.597292 -197.316598)
					(end 440.250072 -197.316598)
				)
			)
		)
	)
	(zone
		(layers "B.Cu" "In11.Cu" "In13.Cu" "In15.Cu")
		(hatch none 0.5)
		(connect_pads
			(clearance 0)
		)
		(min_thickness 0.25)
		(keepout
			(tracks not_allowed)
			(vias allowed)
			(pads allowed)
			(copperpour not_allowed)
			(footprints allowed)
		)
		(placement
			(enabled no)
			(sheetname "")
		)
		(fill yes
			(thermal_gap 0.5)
			(thermal_bridge_width 0.5)
			(island_removal_mode 0)
		)
		(polygon
			(pts
				(arc
					(start 436.150004 -224.516696)
					(mid 435.497224 -224.516696)
					(end 436.150004 -224.516696)
				)
			)
		)
	)
	(zone
		(layers "B.Cu" "In11.Cu" "In13.Cu" "In15.Cu")
		(hatch none 0.5)
		(connect_pads
			(clearance 0)
		)
		(min_thickness 0.25)
		(keepout
			(tracks not_allowed)
			(vias allowed)
			(pads allowed)
			(copperpour not_allowed)
			(footprints allowed)
		)
		(placement
			(enabled no)
			(sheetname "")
		)
		(fill yes
			(thermal_gap 0.5)
			(thermal_bridge_width 0.5)
			(island_removal_mode 0)
		)
		(polygon
			(pts
				(arc
					(start 188.209936 -277.216616)
					(mid 187.557156 -277.216616)
					(end 188.209936 -277.216616)
				)
			)
		)
	)
	(zone
		(layers "B.Cu" "In11.Cu" "In13.Cu" "In15.Cu")
		(hatch none 0.5)
		(connect_pads
			(clearance 0)
		)
		(min_thickness 0.25)
		(keepout
			(tracks not_allowed)
			(vias allowed)
			(pads allowed)
			(copperpour not_allowed)
			(footprints allowed)
		)
		(placement
			(enabled no)
			(sheetname "")
		)
		(fill yes
			(thermal_gap 0.5)
			(thermal_bridge_width 0.5)
			(island_removal_mode 0)
		)
		(polygon
			(pts
				(arc
					(start 192.310004 -227.066602)
					(mid 191.657224 -227.066602)
					(end 192.310004 -227.066602)
				)
			)
		)
	)
	(zone
		(layers "B.Cu" "In11.Cu" "In13.Cu" "In15.Cu")
		(hatch none 0.5)
		(connect_pads
			(clearance 0)
		)
		(min_thickness 0.25)
		(keepout
			(tracks not_allowed)
			(vias allowed)
			(pads allowed)
			(copperpour not_allowed)
			(footprints allowed)
		)
		(placement
			(enabled no)
			(sheetname "")
		)
		(fill yes
			(thermal_gap 0.5)
			(thermal_bridge_width 0.5)
			(island_removal_mode 0)
		)
		(polygon
			(pts
				(arc
					(start 315.054996 -433.289964)
					(mid 314.245244 -433.289964)
					(end 315.054996 -433.289964)
				)
			)
		)
	)
	(zone
		(layers "B.Cu" "In11.Cu" "In13.Cu" "In15.Cu")
		(hatch none 0.5)
		(connect_pads
			(clearance 0)
		)
		(min_thickness 0.25)
		(keepout
			(tracks not_allowed)
			(vias allowed)
			(pads allowed)
			(copperpour not_allowed)
			(footprints allowed)
		)
		(placement
			(enabled no)
			(sheetname "")
		)
		(fill yes
			(thermal_gap 0.5)
			(thermal_bridge_width 0.5)
			(island_removal_mode 0)
		)
		(polygon
			(pts
				(arc
					(start 265.055604 -209.216752)
					(mid 264.402824 -209.216752)
					(end 265.055604 -209.216752)
				)
			)
		)
	)
	(zone
		(layers "B.Cu" "In11.Cu" "In13.Cu" "In15.Cu")
		(hatch none 0.5)
		(connect_pads
			(clearance 0)
		)
		(min_thickness 0.25)
		(keepout
			(tracks not_allowed)
			(vias allowed)
			(pads allowed)
			(copperpour not_allowed)
			(footprints allowed)
		)
		(placement
			(enabled no)
			(sheetname "")
		)
		(fill yes
			(thermal_gap 0.5)
			(thermal_bridge_width 0.5)
			(island_removal_mode 0)
		)
		(polygon
			(pts
				(arc
					(start 349.09887 -215.436704)
					(mid 348.44609 -215.436704)
					(end 349.09887 -215.436704)
				)
			)
		)
	)
	(zone
		(layers "B.Cu" "In11.Cu" "In13.Cu" "In15.Cu")
		(hatch none 0.5)
		(connect_pads
			(clearance 0)
		)
		(min_thickness 0.25)
		(keepout
			(tracks not_allowed)
			(vias allowed)
			(pads allowed)
			(copperpour not_allowed)
			(footprints allowed)
		)
		(placement
			(enabled no)
			(sheetname "")
		)
		(fill yes
			(thermal_gap 0.5)
			(thermal_bridge_width 0.5)
			(island_removal_mode 0)
		)
		(polygon
			(pts
				(arc
					(start 96.929956 -243.922804)
					(mid 96.277176 -243.922804)
					(end 96.929956 -243.922804)
				)
			)
		)
	)
	(zone
		(layers "B.Cu" "In11.Cu" "In13.Cu" "In15.Cu")
		(hatch none 0.5)
		(connect_pads
			(clearance 0)
		)
		(min_thickness 0.25)
		(keepout
			(tracks not_allowed)
			(vias allowed)
			(pads allowed)
			(copperpour not_allowed)
			(footprints allowed)
		)
		(placement
			(enabled no)
			(sheetname "")
		)
		(fill yes
			(thermal_gap 0.5)
			(thermal_bridge_width 0.5)
			(island_removal_mode 0)
		)
		(polygon
			(pts
				(arc
					(start 32.203136 -218.566746)
					(mid 31.550356 -218.566746)
					(end 32.203136 -218.566746)
				)
			)
		)
	)
	(zone
		(layers "B.Cu" "In11.Cu" "In13.Cu" "In15.Cu")
		(hatch none 0.5)
		(connect_pads
			(clearance 0)
		)
		(min_thickness 0.25)
		(keepout
			(tracks not_allowed)
			(vias allowed)
			(pads allowed)
			(copperpour not_allowed)
			(footprints allowed)
		)
		(placement
			(enabled no)
			(sheetname "")
		)
		(fill yes
			(thermal_gap 0.5)
			(thermal_bridge_width 0.5)
			(island_removal_mode 0)
		)
		(polygon
			(pts
				(arc
					(start 36.303204 -231.316784)
					(mid 35.650424 -231.316784)
					(end 36.303204 -231.316784)
				)
			)
		)
	)
	(zone
		(layers "B.Cu" "In11.Cu" "In13.Cu" "In15.Cu")
		(hatch none 0.5)
		(connect_pads
			(clearance 0)
		)
		(min_thickness 0.25)
		(keepout
			(tracks not_allowed)
			(vias allowed)
			(pads allowed)
			(copperpour not_allowed)
			(footprints allowed)
		)
		(placement
			(enabled no)
			(sheetname "")
		)
		(fill yes
			(thermal_gap 0.5)
			(thermal_bridge_width 0.5)
			(island_removal_mode 0)
		)
		(polygon
			(pts
				(arc
					(start 127.473202 -243.108988)
					(mid 126.820422 -243.108988)
					(end 127.473202 -243.108988)
				)
			)
		)
	)
	(zone
		(layers "B.Cu" "In11.Cu" "In13.Cu" "In15.Cu")
		(hatch none 0.5)
		(connect_pads
			(clearance 0)
		)
		(min_thickness 0.25)
		(keepout
			(tracks not_allowed)
			(vias allowed)
			(pads allowed)
			(copperpour not_allowed)
			(footprints allowed)
		)
		(placement
			(enabled no)
			(sheetname "")
		)
		(fill yes
			(thermal_gap 0.5)
			(thermal_bridge_width 0.5)
			(island_removal_mode 0)
		)
		(polygon
			(pts
				(arc
					(start 111.496602 -215.436704)
					(mid 110.843822 -215.436704)
					(end 111.496602 -215.436704)
				)
			)
		)
	)
	(zone
		(layers "B.Cu" "In11.Cu" "In13.Cu" "In15.Cu")
		(hatch none 0.5)
		(connect_pads
			(clearance 0)
		)
		(min_thickness 0.25)
		(keepout
			(tracks not_allowed)
			(vias allowed)
			(pads allowed)
			(copperpour not_allowed)
			(footprints allowed)
		)
		(placement
			(enabled no)
			(sheetname "")
		)
		(fill yes
			(thermal_gap 0.5)
			(thermal_bridge_width 0.5)
			(island_removal_mode 0)
		)
		(polygon
			(pts
				(arc
					(start 257.511804 -243.216684)
					(mid 256.859024 -243.216684)
					(end 257.511804 -243.216684)
				)
			)
		)
	)
	(zone
		(layers "B.Cu" "In11.Cu" "In13.Cu" "In15.Cu")
		(hatch none 0.5)
		(connect_pads
			(clearance 0)
		)
		(min_thickness 0.25)
		(keepout
			(tracks not_allowed)
			(vias allowed)
			(pads allowed)
			(copperpour not_allowed)
			(footprints allowed)
		)
		(placement
			(enabled no)
			(sheetname "")
		)
		(fill yes
			(thermal_gap 0.5)
			(thermal_bridge_width 0.5)
			(island_removal_mode 0)
		)
		(polygon
			(pts
				(arc
					(start 350.508824 -248.806208)
					(mid 349.856044 -248.806208)
					(end 350.508824 -248.806208)
				)
			)
		)
	)
	(zone
		(layers "B.Cu" "In11.Cu" "In13.Cu" "In15.Cu")
		(hatch none 0.5)
		(connect_pads
			(clearance 0)
		)
		(min_thickness 0.25)
		(keepout
			(tracks not_allowed)
			(vias allowed)
			(pads allowed)
			(copperpour not_allowed)
			(footprints allowed)
		)
		(placement
			(enabled no)
			(sheetname "")
		)
		(fill yes
			(thermal_gap 0.5)
			(thermal_bridge_width 0.5)
			(island_removal_mode 0)
		)
		(polygon
			(pts
				(arc
					(start 188.209936 -303.566576)
					(mid 187.557156 -303.566576)
					(end 188.209936 -303.566576)
				)
			)
		)
	)
	(zone
		(layers "B.Cu" "In11.Cu" "In13.Cu" "In15.Cu")
		(hatch none 0.5)
		(connect_pads
			(clearance 0)
		)
		(min_thickness 0.25)
		(keepout
			(tracks not_allowed)
			(vias allowed)
			(pads allowed)
			(copperpour not_allowed)
			(footprints allowed)
		)
		(placement
			(enabled no)
			(sheetname "")
		)
		(fill yes
			(thermal_gap 0.5)
			(thermal_bridge_width 0.5)
			(island_removal_mode 0)
		)
		(polygon
			(pts
				(arc
					(start 96.100138 -273.453098)
					(mid 95.447358 -273.453098)
					(end 96.100138 -273.453098)
				)
			)
		)
	)
	(zone
		(layers "B.Cu" "In11.Cu" "In13.Cu" "In15.Cu")
		(hatch none 0.5)
		(connect_pads
			(clearance 0)
		)
		(min_thickness 0.25)
		(keepout
			(tracks not_allowed)
			(vias allowed)
			(pads allowed)
			(copperpour not_allowed)
			(footprints allowed)
		)
		(placement
			(enabled no)
			(sheetname "")
		)
		(fill yes
			(thermal_gap 0.5)
			(thermal_bridge_width 0.5)
			(island_removal_mode 0)
		)
		(polygon
			(pts
				(arc
					(start 374.47347 -234.970066)
					(mid 373.82069 -234.970066)
					(end 374.47347 -234.970066)
				)
			)
		)
	)
	(zone
		(layers "B.Cu" "In11.Cu" "In13.Cu" "In15.Cu")
		(hatch none 0.5)
		(connect_pads
			(clearance 0)
		)
		(min_thickness 0.25)
		(keepout
			(tracks not_allowed)
			(vias allowed)
			(pads allowed)
			(copperpour not_allowed)
			(footprints allowed)
		)
		(placement
			(enabled no)
			(sheetname "")
		)
		(fill yes
			(thermal_gap 0.5)
			(thermal_bridge_width 0.5)
			(island_removal_mode 0)
		)
		(polygon
			(pts
				(arc
					(start 403.154896 -430.889918)
					(mid 402.345144 -430.889918)
					(end 403.154896 -430.889918)
				)
			)
		)
	)
	(zone
		(layers "B.Cu" "In11.Cu" "In13.Cu" "In15.Cu")
		(hatch none 0.5)
		(connect_pads
			(clearance 0)
		)
		(min_thickness 0.25)
		(keepout
			(tracks not_allowed)
			(vias allowed)
			(pads allowed)
			(copperpour not_allowed)
			(footprints allowed)
		)
		(placement
			(enabled no)
			(sheetname "")
		)
		(fill yes
			(thermal_gap 0.5)
			(thermal_bridge_width 0.5)
			(island_removal_mode 0)
		)
		(polygon
			(pts
				(arc
					(start 343.570052 -266.128246)
					(mid 342.917272 -266.128246)
					(end 343.570052 -266.128246)
				)
			)
		)
	)
	(zone
		(layers "B.Cu" "In11.Cu" "In13.Cu" "In15.Cu")
		(hatch none 0.5)
		(connect_pads
			(clearance 0)
		)
		(min_thickness 0.25)
		(keepout
			(tracks not_allowed)
			(vias allowed)
			(pads allowed)
			(copperpour not_allowed)
			(footprints allowed)
		)
		(placement
			(enabled no)
			(sheetname "")
		)
		(fill yes
			(thermal_gap 0.5)
			(thermal_bridge_width 0.5)
			(island_removal_mode 0)
		)
		(polygon
			(pts
				(arc
					(start 128.522984 -275.8948)
					(mid 127.870204 -275.8948)
					(end 128.522984 -275.8948)
				)
			)
		)
	)
	(zone
		(layers "B.Cu" "In11.Cu" "In13.Cu" "In15.Cu")
		(hatch none 0.5)
		(connect_pads
			(clearance 0)
		)
		(min_thickness 0.25)
		(keepout
			(tracks not_allowed)
			(vias allowed)
			(pads allowed)
			(copperpour not_allowed)
			(footprints allowed)
		)
		(placement
			(enabled no)
			(sheetname "")
		)
		(fill yes
			(thermal_gap 0.5)
			(thermal_bridge_width 0.5)
			(island_removal_mode 0)
		)
		(polygon
			(pts
				(arc
					(start 128.883156 -243.922804)
					(mid 128.230376 -243.922804)
					(end 128.883156 -243.922804)
				)
			)
		)
	)
	(zone
		(layers "B.Cu" "In11.Cu" "In13.Cu" "In15.Cu")
		(hatch none 0.5)
		(connect_pads
			(clearance 0)
		)
		(min_thickness 0.25)
		(keepout
			(tracks not_allowed)
			(vias allowed)
			(pads allowed)
			(copperpour not_allowed)
			(footprints allowed)
		)
		(placement
			(enabled no)
			(sheetname "")
		)
		(fill yes
			(thermal_gap 0.5)
			(thermal_bridge_width 0.5)
			(island_removal_mode 0)
		)
		(polygon
			(pts
				(arc
					(start 397.62684 -410.030168)
					(mid 396.92326 -410.030168)
					(end 397.62684 -410.030168)
				)
			)
		)
	)
	(zone
		(layers "B.Cu" "In11.Cu" "In13.Cu" "In15.Cu")
		(hatch none 0.5)
		(connect_pads
			(clearance 0)
		)
		(min_thickness 0.25)
		(keepout
			(tracks not_allowed)
			(vias allowed)
			(pads allowed)
			(copperpour not_allowed)
			(footprints allowed)
		)
		(placement
			(enabled no)
			(sheetname "")
		)
		(fill yes
			(thermal_gap 0.5)
			(thermal_bridge_width 0.5)
			(island_removal_mode 0)
		)
		(polygon
			(pts
				(arc
					(start 127.583184 -269.38351)
					(mid 126.930404 -269.38351)
					(end 127.583184 -269.38351)
				)
			)
		)
	)
	(zone
		(layers "B.Cu" "In11.Cu" "In13.Cu" "In15.Cu")
		(hatch none 0.5)
		(connect_pads
			(clearance 0)
		)
		(min_thickness 0.25)
		(keepout
			(tracks not_allowed)
			(vias allowed)
			(pads allowed)
			(copperpour not_allowed)
			(footprints allowed)
		)
		(placement
			(enabled no)
			(sheetname "")
		)
		(fill yes
			(thermal_gap 0.5)
			(thermal_bridge_width 0.5)
			(island_removal_mode 0)
		)
		(polygon
			(pts
				(arc
					(start 71.054976 -433.289964)
					(mid 70.245224 -433.289964)
					(end 71.054976 -433.289964)
				)
			)
		)
	)
	(zone
		(layers "B.Cu" "In11.Cu" "In13.Cu" "In15.Cu")
		(hatch none 0.5)
		(connect_pads
			(clearance 0)
		)
		(min_thickness 0.25)
		(keepout
			(tracks not_allowed)
			(vias allowed)
			(pads allowed)
			(copperpour not_allowed)
			(footprints allowed)
		)
		(placement
			(enabled no)
			(sheetname "")
		)
		(fill yes
			(thermal_gap 0.5)
			(thermal_bridge_width 0.5)
			(island_removal_mode 0)
		)
		(polygon
			(pts
				(arc
					(start 272.599404 -244.066568)
					(mid 271.946624 -244.066568)
					(end 272.599404 -244.066568)
				)
			)
		)
	)
	(zone
		(layers "B.Cu" "In11.Cu" "In13.Cu" "In15.Cu")
		(hatch none 0.5)
		(connect_pads
			(clearance 0)
		)
		(min_thickness 0.25)
		(keepout
			(tracks not_allowed)
			(vias allowed)
			(pads allowed)
			(copperpour not_allowed)
			(footprints allowed)
		)
		(placement
			(enabled no)
			(sheetname "")
		)
		(fill yes
			(thermal_gap 0.5)
			(thermal_bridge_width 0.5)
			(island_removal_mode 0)
		)
		(polygon
			(pts
				(arc
					(start 345.33967 -226.831144)
					(mid 344.68689 -226.831144)
					(end 345.33967 -226.831144)
				)
			)
		)
	)
	(zone
		(layers "B.Cu" "In11.Cu" "In13.Cu" "In15.Cu")
		(hatch none 0.5)
		(connect_pads
			(clearance 0)
		)
		(min_thickness 0.25)
		(keepout
			(tracks not_allowed)
			(vias allowed)
			(pads allowed)
			(copperpour not_allowed)
			(footprints allowed)
		)
		(placement
			(enabled no)
			(sheetname "")
		)
		(fill yes
			(thermal_gap 0.5)
			(thermal_bridge_width 0.5)
			(island_removal_mode 0)
		)
		(polygon
			(pts
				(arc
					(start 203.297536 -207.51673)
					(mid 202.644756 -207.51673)
					(end 203.297536 -207.51673)
				)
			)
		)
	)
	(zone
		(layers "B.Cu" "In11.Cu" "In13.Cu" "In15.Cu")
		(hatch none 0.5)
		(connect_pads
			(clearance 0)
		)
		(min_thickness 0.25)
		(keepout
			(tracks not_allowed)
			(vias allowed)
			(pads allowed)
			(copperpour not_allowed)
			(footprints allowed)
		)
		(placement
			(enabled no)
			(sheetname "")
		)
		(fill yes
			(thermal_gap 0.5)
			(thermal_bridge_width 0.5)
			(island_removal_mode 0)
		)
		(polygon
			(pts
				(arc
					(start 36.303204 -227.066602)
					(mid 35.650424 -227.066602)
					(end 36.303204 -227.066602)
				)
			)
		)
	)
	(zone
		(layers "B.Cu" "In11.Cu" "In13.Cu" "In15.Cu")
		(hatch none 0.5)
		(connect_pads
			(clearance 0)
		)
		(min_thickness 0.25)
		(keepout
			(tracks not_allowed)
			(vias allowed)
			(pads allowed)
			(copperpour not_allowed)
			(footprints allowed)
		)
		(placement
			(enabled no)
			(sheetname "")
		)
		(fill yes
			(thermal_gap 0.5)
			(thermal_bridge_width 0.5)
			(island_removal_mode 0)
		)
		(polygon
			(pts
				(arc
					(start 375.183146 -178.559968)
					(mid 374.479566 -178.559968)
					(end 375.183146 -178.559968)
				)
			)
		)
	)
	(zone
		(layers "B.Cu" "In11.Cu" "In13.Cu" "In15.Cu")
		(hatch none 0.5)
		(connect_pads
			(clearance 0)
		)
		(min_thickness 0.25)
		(keepout
			(tracks not_allowed)
			(vias allowed)
			(pads allowed)
			(copperpour not_allowed)
			(footprints allowed)
		)
		(placement
			(enabled no)
			(sheetname "")
		)
		(fill yes
			(thermal_gap 0.5)
			(thermal_bridge_width 0.5)
			(island_removal_mode 0)
		)
		(polygon
			(pts
				(arc
					(start 375.183146 -167.510968)
					(mid 374.479566 -167.510968)
					(end 375.183146 -167.510968)
				)
			)
		)
	)
	(zone
		(layers "B.Cu" "In11.Cu" "In13.Cu" "In15.Cu")
		(hatch none 0.5)
		(connect_pads
			(clearance 0)
		)
		(min_thickness 0.25)
		(keepout
			(tracks not_allowed)
			(vias allowed)
			(pads allowed)
			(copperpour not_allowed)
			(footprints allowed)
		)
		(placement
			(enabled no)
			(sheetname "")
		)
		(fill yes
			(thermal_gap 0.5)
			(thermal_bridge_width 0.5)
			(island_removal_mode 0)
		)
		(polygon
			(pts
				(arc
					(start 80.054958 -434.48986)
					(mid 79.245206 -434.48986)
					(end 80.054958 -434.48986)
				)
			)
		)
	)
	(zone
		(layers "B.Cu" "In11.Cu" "In13.Cu" "In15.Cu")
		(hatch none 0.5)
		(connect_pads
			(clearance 0)
		)
		(min_thickness 0.25)
		(keepout
			(tracks not_allowed)
			(vias allowed)
			(pads allowed)
			(copperpour not_allowed)
			(footprints allowed)
		)
		(placement
			(enabled no)
			(sheetname "")
		)
		(fill yes
			(thermal_gap 0.5)
			(thermal_bridge_width 0.5)
			(island_removal_mode 0)
		)
		(polygon
			(pts
				(arc
					(start 413.154876 -439.0898)
					(mid 412.345124 -439.0898)
					(end 413.154876 -439.0898)
				)
			)
		)
	)
	(zone
		(layers "B.Cu" "In11.Cu" "In13.Cu" "In15.Cu")
		(hatch none 0.5)
		(connect_pads
			(clearance 0)
		)
		(min_thickness 0.25)
		(keepout
			(tracks not_allowed)
			(vias allowed)
			(pads allowed)
			(copperpour not_allowed)
			(footprints allowed)
		)
		(placement
			(enabled no)
			(sheetname "")
		)
		(fill yes
			(thermal_gap 0.5)
			(thermal_bridge_width 0.5)
			(island_removal_mode 0)
		)
		(polygon
			(pts
				(arc
					(start 71.054976 -434.48986)
					(mid 70.245224 -434.48986)
					(end 71.054976 -434.48986)
				)
			)
		)
	)
	(zone
		(layers "B.Cu" "In11.Cu" "In13.Cu" "In15.Cu")
		(hatch none 0.5)
		(connect_pads
			(clearance 0)
		)
		(min_thickness 0.25)
		(keepout
			(tracks not_allowed)
			(vias allowed)
			(pads allowed)
			(copperpour not_allowed)
			(footprints allowed)
		)
		(placement
			(enabled no)
			(sheetname "")
		)
		(fill yes
			(thermal_gap 0.5)
			(thermal_bridge_width 0.5)
			(island_removal_mode 0)
		)
		(polygon
			(pts
				(arc
					(start 192.310004 -203.266802)
					(mid 191.657224 -203.266802)
					(end 192.310004 -203.266802)
				)
			)
		)
	)
	(zone
		(layers "B.Cu" "In11.Cu" "In13.Cu" "In15.Cu")
		(hatch none 0.5)
		(connect_pads
			(clearance 0)
		)
		(min_thickness 0.25)
		(keepout
			(tracks not_allowed)
			(vias allowed)
			(pads allowed)
			(copperpour not_allowed)
			(footprints allowed)
		)
		(placement
			(enabled no)
			(sheetname "")
		)
		(fill yes
			(thermal_gap 0.5)
			(thermal_bridge_width 0.5)
			(island_removal_mode 0)
		)
		(polygon
			(pts
				(arc
					(start 280.143204 -301.01667)
					(mid 279.490424 -301.01667)
					(end 280.143204 -301.01667)
				)
			)
		)
	)
	(zone
		(layers "B.Cu" "In11.Cu" "In13.Cu" "In15.Cu")
		(hatch none 0.5)
		(connect_pads
			(clearance 0)
		)
		(min_thickness 0.25)
		(keepout
			(tracks not_allowed)
			(vias allowed)
			(pads allowed)
			(copperpour not_allowed)
			(footprints allowed)
		)
		(placement
			(enabled no)
			(sheetname "")
		)
		(fill yes
			(thermal_gap 0.5)
			(thermal_bridge_width 0.5)
			(island_removal_mode 0)
		)
		(polygon
			(pts
				(arc
					(start 102.568248 -214.622634)
					(mid 101.915468 -214.622634)
					(end 102.568248 -214.622634)
				)
			)
		)
	)
	(zone
		(layers "B.Cu" "In11.Cu" "In13.Cu" "In15.Cu")
		(hatch none 0.5)
		(connect_pads
			(clearance 0)
		)
		(min_thickness 0.25)
		(keepout
			(tracks not_allowed)
			(vias allowed)
			(pads allowed)
			(copperpour not_allowed)
			(footprints allowed)
		)
		(placement
			(enabled no)
			(sheetname "")
		)
		(fill yes
			(thermal_gap 0.5)
			(thermal_bridge_width 0.5)
			(island_removal_mode 0)
		)
		(polygon
			(pts
				(arc
					(start 96.929956 -227.64496)
					(mid 96.277176 -227.64496)
					(end 96.929956 -227.64496)
				)
			)
		)
	)
	(zone
		(layers "B.Cu" "In11.Cu" "In13.Cu" "In15.Cu")
		(hatch none 0.5)
		(connect_pads
			(clearance 0)
		)
		(min_thickness 0.25)
		(keepout
			(tracks not_allowed)
			(vias allowed)
			(pads allowed)
			(copperpour not_allowed)
			(footprints allowed)
		)
		(placement
			(enabled no)
			(sheetname "")
		)
		(fill yes
			(thermal_gap 0.5)
			(thermal_bridge_width 0.5)
			(island_removal_mode 0)
		)
		(polygon
			(pts
				(arc
					(start 128.154938 -431.889916)
					(mid 127.345186 -431.889916)
					(end 128.154938 -431.889916)
				)
			)
		)
	)
	(zone
		(layers "B.Cu" "In11.Cu" "In13.Cu" "In15.Cu")
		(hatch none 0.5)
		(connect_pads
			(clearance 0)
		)
		(min_thickness 0.25)
		(keepout
			(tracks not_allowed)
			(vias allowed)
			(pads allowed)
			(copperpour not_allowed)
			(footprints allowed)
		)
		(placement
			(enabled no)
			(sheetname "")
		)
		(fill yes
			(thermal_gap 0.5)
			(thermal_bridge_width 0.5)
			(island_removal_mode 0)
		)
		(polygon
			(pts
				(arc
					(start 436.150004 -272.966688)
					(mid 435.497224 -272.966688)
					(end 436.150004 -272.966688)
				)
			)
		)
	)
	(zone
		(layers "B.Cu" "In11.Cu" "In13.Cu" "In15.Cu")
		(hatch none 0.5)
		(connect_pads
			(clearance 0)
		)
		(min_thickness 0.25)
		(keepout
			(tracks not_allowed)
			(vias allowed)
			(pads allowed)
			(copperpour not_allowed)
			(footprints allowed)
		)
		(placement
			(enabled no)
			(sheetname "")
		)
		(fill yes
			(thermal_gap 0.5)
			(thermal_bridge_width 0.5)
			(island_removal_mode 0)
		)
		(polygon
			(pts
				(arc
					(start 413.154876 -431.889916)
					(mid 412.345124 -431.889916)
					(end 413.154876 -431.889916)
				)
			)
		)
	)
	(zone
		(layers "B.Cu" "In11.Cu" "In13.Cu" "In15.Cu")
		(hatch none 0.5)
		(connect_pads
			(clearance 0)
		)
		(min_thickness 0.25)
		(keepout
			(tracks not_allowed)
			(vias allowed)
			(pads allowed)
			(copperpour not_allowed)
			(footprints allowed)
		)
		(placement
			(enabled no)
			(sheetname "")
		)
		(fill yes
			(thermal_gap 0.5)
			(thermal_bridge_width 0.5)
			(island_removal_mode 0)
		)
		(polygon
			(pts
				(arc
					(start 89.499948 -410.030168)
					(mid 88.796368 -410.030168)
					(end 89.499948 -410.030168)
				)
			)
		)
	)
	(zone
		(layers "B.Cu" "In11.Cu" "In13.Cu" "In15.Cu")
		(hatch none 0.5)
		(connect_pads
			(clearance 0)
		)
		(min_thickness 0.25)
		(keepout
			(tracks not_allowed)
			(vias allowed)
			(pads allowed)
			(copperpour not_allowed)
			(footprints allowed)
		)
		(placement
			(enabled no)
			(sheetname "")
		)
		(fill yes
			(thermal_gap 0.5)
			(thermal_bridge_width 0.5)
			(island_removal_mode 0)
		)
		(polygon
			(pts
				(arc
					(start 36.303204 -279.766776)
					(mid 35.650424 -279.766776)
					(end 36.303204 -279.766776)
				)
			)
		)
	)
	(zone
		(layers "B.Cu" "In11.Cu" "In13.Cu" "In15.Cu")
		(hatch none 0.5)
		(connect_pads
			(clearance 0)
		)
		(min_thickness 0.25)
		(keepout
			(tracks not_allowed)
			(vias allowed)
			(pads allowed)
			(copperpour not_allowed)
			(footprints allowed)
		)
		(placement
			(enabled no)
			(sheetname "")
		)
		(fill yes
			(thermal_gap 0.5)
			(thermal_bridge_width 0.5)
			(island_removal_mode 0)
		)
		(polygon
			(pts
				(arc
					(start 353.302062 -175.668432)
					(mid 352.598482 -175.668432)
					(end 353.302062 -175.668432)
				)
			)
		)
	)
	(zone
		(layers "B.Cu" "In11.Cu" "In13.Cu" "In15.Cu")
		(hatch none 0.5)
		(connect_pads
			(clearance 0)
		)
		(min_thickness 0.25)
		(keepout
			(tracks not_allowed)
			(vias allowed)
			(pads allowed)
			(copperpour not_allowed)
			(footprints allowed)
		)
		(placement
			(enabled no)
			(sheetname "")
		)
		(fill yes
			(thermal_gap 0.5)
			(thermal_bridge_width 0.5)
			(island_removal_mode 0)
		)
		(polygon
			(pts
				(arc
					(start 409.154884 -431.889916)
					(mid 408.345132 -431.889916)
					(end 409.154884 -431.889916)
				)
			)
		)
	)
	(zone
		(layers "B.Cu" "In11.Cu" "In13.Cu" "In15.Cu")
		(hatch none 0.5)
		(connect_pads
			(clearance 0)
		)
		(min_thickness 0.25)
		(keepout
			(tracks not_allowed)
			(vias allowed)
			(pads allowed)
			(copperpour not_allowed)
			(footprints allowed)
		)
		(placement
			(enabled no)
			(sheetname "")
		)
		(fill yes
			(thermal_gap 0.5)
			(thermal_bridge_width 0.5)
			(island_removal_mode 0)
		)
		(polygon
			(pts
				(arc
					(start 375.523252 -277.522432)
					(mid 374.870472 -277.522432)
					(end 375.523252 -277.522432)
				)
			)
		)
	)
	(zone
		(layers "B.Cu" "In11.Cu" "In13.Cu" "In15.Cu")
		(hatch none 0.5)
		(connect_pads
			(clearance 0)
		)
		(min_thickness 0.25)
		(keepout
			(tracks not_allowed)
			(vias allowed)
			(pads allowed)
			(copperpour not_allowed)
			(footprints allowed)
		)
		(placement
			(enabled no)
			(sheetname "")
		)
		(fill yes
			(thermal_gap 0.5)
			(thermal_bridge_width 0.5)
			(island_removal_mode 0)
		)
		(polygon
			(pts
				(arc
					(start 376.463052 -269.38351)
					(mid 375.810272 -269.38351)
					(end 376.463052 -269.38351)
				)
			)
		)
	)
	(zone
		(layers "B.Cu" "In11.Cu" "In13.Cu" "In15.Cu")
		(hatch none 0.5)
		(connect_pads
			(clearance 0)
		)
		(min_thickness 0.25)
		(keepout
			(tracks not_allowed)
			(vias allowed)
			(pads allowed)
			(copperpour not_allowed)
			(footprints allowed)
		)
		(placement
			(enabled no)
			(sheetname "")
		)
		(fill yes
			(thermal_gap 0.5)
			(thermal_bridge_width 0.5)
			(island_removal_mode 0)
		)
		(polygon
			(pts
				(arc
					(start 374.943624 -229.272846)
					(mid 374.290844 -229.272846)
					(end 374.943624 -229.272846)
				)
			)
		)
	)
	(zone
		(layers "B.Cu" "In11.Cu" "In13.Cu" "In15.Cu")
		(hatch none 0.5)
		(connect_pads
			(clearance 0)
		)
		(min_thickness 0.25)
		(keepout
			(tracks not_allowed)
			(vias allowed)
			(pads allowed)
			(copperpour not_allowed)
			(footprints allowed)
		)
		(placement
			(enabled no)
			(sheetname "")
		)
		(fill yes
			(thermal_gap 0.5)
			(thermal_bridge_width 0.5)
			(island_removal_mode 0)
		)
		(polygon
			(pts
				(arc
					(start 32.203136 -198.166736)
					(mid 31.550356 -198.166736)
					(end 32.203136 -198.166736)
				)
			)
		)
	)
	(zone
		(layers "B.Cu" "In11.Cu" "In13.Cu" "In15.Cu")
		(hatch none 0.5)
		(connect_pads
			(clearance 0)
		)
		(min_thickness 0.25)
		(keepout
			(tracks not_allowed)
			(vias allowed)
			(pads allowed)
			(copperpour not_allowed)
			(footprints allowed)
		)
		(placement
			(enabled no)
			(sheetname "")
		)
		(fill yes
			(thermal_gap 0.5)
			(thermal_bridge_width 0.5)
			(island_removal_mode 0)
		)
		(polygon
			(pts
				(arc
					(start 343.46007 -215.436704)
					(mid 342.80729 -215.436704)
					(end 343.46007 -215.436704)
				)
			)
		)
	)
	(zone
		(layers "B.Cu" "In11.Cu" "In13.Cu" "In15.Cu")
		(hatch none 0.5)
		(connect_pads
			(clearance 0)
		)
		(min_thickness 0.25)
		(keepout
			(tracks not_allowed)
			(vias allowed)
			(pads allowed)
			(copperpour not_allowed)
			(footprints allowed)
		)
		(placement
			(enabled no)
			(sheetname "")
		)
		(fill yes
			(thermal_gap 0.5)
			(thermal_bridge_width 0.5)
			(island_removal_mode 0)
		)
		(polygon
			(pts
				(arc
					(start 86.054946 -427.089824)
					(mid 85.245194 -427.089824)
					(end 86.054946 -427.089824)
				)
			)
		)
	)
	(zone
		(layers "B.Cu" "In11.Cu" "In13.Cu" "In15.Cu")
		(hatch none 0.5)
		(connect_pads
			(clearance 0)
		)
		(min_thickness 0.25)
		(keepout
			(tracks not_allowed)
			(vias allowed)
			(pads allowed)
			(copperpour not_allowed)
			(footprints allowed)
		)
		(placement
			(enabled no)
			(sheetname "")
		)
		(fill yes
			(thermal_gap 0.5)
			(thermal_bridge_width 0.5)
			(island_removal_mode 0)
		)
		(polygon
			(pts
				(arc
					(start 284.243272 -225.36658)
					(mid 283.590492 -225.36658)
					(end 284.243272 -225.36658)
				)
			)
		)
	)
	(zone
		(layers "B.Cu" "In11.Cu" "In13.Cu" "In15.Cu")
		(hatch none 0.5)
		(connect_pads
			(clearance 0)
		)
		(min_thickness 0.25)
		(keepout
			(tracks not_allowed)
			(vias allowed)
			(pads allowed)
			(copperpour not_allowed)
			(footprints allowed)
		)
		(placement
			(enabled no)
			(sheetname "")
		)
		(fill yes
			(thermal_gap 0.5)
			(thermal_bridge_width 0.5)
			(island_removal_mode 0)
		)
		(polygon
			(pts
				(arc
					(start 138.154918 -436.889906)
					(mid 137.345166 -436.889906)
					(end 138.154918 -436.889906)
				)
			)
		)
	)
	(zone
		(layers "B.Cu" "In11.Cu" "In13.Cu" "In15.Cu")
		(hatch none 0.5)
		(connect_pads
			(clearance 0)
		)
		(min_thickness 0.25)
		(keepout
			(tracks not_allowed)
			(vias allowed)
			(pads allowed)
			(copperpour not_allowed)
			(footprints allowed)
		)
		(placement
			(enabled no)
			(sheetname "")
		)
		(fill yes
			(thermal_gap 0.5)
			(thermal_bridge_width 0.5)
			(island_removal_mode 0)
		)
		(polygon
			(pts
				(arc
					(start 280.143204 -244.066568)
					(mid 279.490424 -244.066568)
					(end 280.143204 -244.066568)
				)
			)
		)
	)
	(zone
		(layers "B.Cu" "In11.Cu" "In13.Cu" "In15.Cu")
		(hatch none 0.5)
		(connect_pads
			(clearance 0)
		)
		(min_thickness 0.25)
		(keepout
			(tracks not_allowed)
			(vias allowed)
			(pads allowed)
			(copperpour not_allowed)
			(footprints allowed)
		)
		(placement
			(enabled no)
			(sheetname "")
		)
		(fill yes
			(thermal_gap 0.5)
			(thermal_bridge_width 0.5)
			(island_removal_mode 0)
		)
		(polygon
			(pts
				(arc
					(start 363.666024 -227.64496)
					(mid 363.013244 -227.64496)
					(end 363.666024 -227.64496)
				)
			)
		)
	)
	(zone
		(layers "B.Cu" "In11.Cu" "In13.Cu" "In15.Cu")
		(hatch none 0.5)
		(connect_pads
			(clearance 0)
		)
		(min_thickness 0.25)
		(keepout
			(tracks not_allowed)
			(vias allowed)
			(pads allowed)
			(copperpour not_allowed)
			(footprints allowed)
		)
		(placement
			(enabled no)
			(sheetname "")
		)
		(fill yes
			(thermal_gap 0.5)
			(thermal_bridge_width 0.5)
			(island_removal_mode 0)
		)
		(polygon
			(pts
				(arc
					(start 88.941402 -215.436704)
					(mid 88.288622 -215.436704)
					(end 88.941402 -215.436704)
				)
			)
		)
	)
	(zone
		(layers "B.Cu" "In11.Cu" "In13.Cu" "In15.Cu")
		(hatch none 0.5)
		(connect_pads
			(clearance 0)
		)
		(min_thickness 0.25)
		(keepout
			(tracks not_allowed)
			(vias allowed)
			(pads allowed)
			(copperpour not_allowed)
			(footprints allowed)
		)
		(placement
			(enabled no)
			(sheetname "")
		)
		(fill yes
			(thermal_gap 0.5)
			(thermal_bridge_width 0.5)
			(island_removal_mode 0)
		)
		(polygon
			(pts
				(arc
					(start 412.94304 -410.030168)
					(mid 412.23946 -410.030168)
					(end 412.94304 -410.030168)
				)
			)
		)
	)
	(zone
		(layers "B.Cu" "In11.Cu" "In13.Cu" "In15.Cu")
		(hatch none 0.5)
		(connect_pads
			(clearance 0)
		)
		(min_thickness 0.25)
		(keepout
			(tracks not_allowed)
			(vias allowed)
			(pads allowed)
			(copperpour not_allowed)
			(footprints allowed)
		)
		(placement
			(enabled no)
			(sheetname "")
		)
		(fill yes
			(thermal_gap 0.5)
			(thermal_bridge_width 0.5)
			(island_removal_mode 0)
		)
		(polygon
			(pts
				(arc
					(start 17.115536 -312.91657)
					(mid 16.462756 -312.91657)
					(end 17.115536 -312.91657)
				)
			)
		)
	)
	(zone
		(layers "B.Cu" "In11.Cu" "In13.Cu" "In15.Cu")
		(hatch none 0.5)
		(connect_pads
			(clearance 0)
		)
		(min_thickness 0.25)
		(keepout
			(tracks not_allowed)
			(vias allowed)
			(pads allowed)
			(copperpour not_allowed)
			(footprints allowed)
		)
		(placement
			(enabled no)
			(sheetname "")
		)
		(fill yes
			(thermal_gap 0.5)
			(thermal_bridge_width 0.5)
			(island_removal_mode 0)
		)
		(polygon
			(pts
				(arc
					(start 109.146848 -214.622634)
					(mid 108.494068 -214.622634)
					(end 109.146848 -214.622634)
				)
			)
		)
	)
	(zone
		(layers "B.Cu" "In11.Cu" "In13.Cu" "In15.Cu")
		(hatch none 0.5)
		(connect_pads
			(clearance 0)
		)
		(min_thickness 0.25)
		(keepout
			(tracks not_allowed)
			(vias allowed)
			(pads allowed)
			(copperpour not_allowed)
			(footprints allowed)
		)
		(placement
			(enabled no)
			(sheetname "")
		)
		(fill yes
			(thermal_gap 0.5)
			(thermal_bridge_width 0.5)
			(island_removal_mode 0)
		)
		(polygon
			(pts
				(arc
					(start 325.774558 -403.883876)
					(mid 325.070978 -403.883876)
					(end 325.774558 -403.883876)
				)
			)
		)
	)
	(zone
		(layers "B.Cu" "In11.Cu" "In13.Cu" "In15.Cu")
		(hatch none 0.5)
		(connect_pads
			(clearance 0)
		)
		(min_thickness 0.25)
		(keepout
			(tracks not_allowed)
			(vias allowed)
			(pads allowed)
			(copperpour not_allowed)
			(footprints allowed)
		)
		(placement
			(enabled no)
			(sheetname "")
		)
		(fill yes
			(thermal_gap 0.5)
			(thermal_bridge_width 0.5)
			(island_removal_mode 0)
		)
		(polygon
			(pts
				(arc
					(start 188.209936 -299.316648)
					(mid 187.557156 -299.316648)
					(end 188.209936 -299.316648)
				)
			)
		)
	)
	(zone
		(layers "B.Cu" "In11.Cu" "In13.Cu" "In15.Cu")
		(hatch none 0.5)
		(connect_pads
			(clearance 0)
		)
		(min_thickness 0.25)
		(keepout
			(tracks not_allowed)
			(vias allowed)
			(pads allowed)
			(copperpour not_allowed)
			(footprints allowed)
		)
		(placement
			(enabled no)
			(sheetname "")
		)
		(fill yes
			(thermal_gap 0.5)
			(thermal_bridge_width 0.5)
			(island_removal_mode 0)
		)
		(polygon
			(pts
				(arc
					(start 188.209936 -244.066568)
					(mid 187.557156 -244.066568)
					(end 188.209936 -244.066568)
				)
			)
		)
	)
	(zone
		(layers "B.Cu" "In11.Cu" "In13.Cu" "In15.Cu")
		(hatch none 0.5)
		(connect_pads
			(clearance 0)
		)
		(min_thickness 0.25)
		(keepout
			(tracks not_allowed)
			(vias allowed)
			(pads allowed)
			(copperpour not_allowed)
			(footprints allowed)
		)
		(placement
			(enabled no)
			(sheetname "")
		)
		(fill yes
			(thermal_gap 0.5)
			(thermal_bridge_width 0.5)
			(island_removal_mode 0)
		)
		(polygon
			(pts
				(arc
					(start 128.993138 -262.058658)
					(mid 128.340358 -262.058658)
					(end 128.993138 -262.058658)
				)
			)
		)
	)
	(zone
		(layers "B.Cu" "In11.Cu" "In13.Cu" "In15.Cu")
		(hatch none 0.5)
		(connect_pads
			(clearance 0)
		)
		(min_thickness 0.25)
		(keepout
			(tracks not_allowed)
			(vias allowed)
			(pads allowed)
			(copperpour not_allowed)
			(footprints allowed)
		)
		(placement
			(enabled no)
			(sheetname "")
		)
		(fill yes
			(thermal_gap 0.5)
			(thermal_bridge_width 0.5)
			(island_removal_mode 0)
		)
		(polygon
			(pts
				(arc
					(start 54.834536 -244.066568)
					(mid 54.181756 -244.066568)
					(end 54.834536 -244.066568)
				)
			)
		)
	)
	(zone
		(layers "B.Cu" "In11.Cu" "In13.Cu" "In15.Cu")
		(hatch none 0.5)
		(connect_pads
			(clearance 0)
		)
		(min_thickness 0.25)
		(keepout
			(tracks not_allowed)
			(vias allowed)
			(pads allowed)
			(copperpour not_allowed)
			(footprints allowed)
		)
		(placement
			(enabled no)
			(sheetname "")
		)
		(fill yes
			(thermal_gap 0.5)
			(thermal_bridge_width 0.5)
			(island_removal_mode 0)
		)
		(polygon
			(pts
				(arc
					(start 343.930224 -239.0394)
					(mid 343.277444 -239.0394)
					(end 343.930224 -239.0394)
				)
			)
		)
	)
	(zone
		(layers "B.Cu" "In11.Cu" "In13.Cu" "In15.Cu")
		(hatch none 0.5)
		(connect_pads
			(clearance 0)
		)
		(min_thickness 0.25)
		(keepout
			(tracks not_allowed)
			(vias allowed)
			(pads allowed)
			(copperpour not_allowed)
			(footprints allowed)
		)
		(placement
			(enabled no)
			(sheetname "")
		)
		(fill yes
			(thermal_gap 0.5)
			(thermal_bridge_width 0.5)
			(island_removal_mode 0)
		)
		(polygon
			(pts
				(arc
					(start 375.41327 -236.597952)
					(mid 374.76049 -236.597952)
					(end 375.41327 -236.597952)
				)
			)
		)
	)
	(zone
		(layers "B.Cu" "In11.Cu" "In13.Cu" "In15.Cu")
		(hatch none 0.5)
		(connect_pads
			(clearance 0)
		)
		(min_thickness 0.25)
		(keepout
			(tracks not_allowed)
			(vias allowed)
			(pads allowed)
			(copperpour not_allowed)
			(footprints allowed)
		)
		(placement
			(enabled no)
			(sheetname "")
		)
		(fill yes
			(thermal_gap 0.5)
			(thermal_bridge_width 0.5)
			(island_removal_mode 0)
		)
		(polygon
			(pts
				(arc
					(start 265.055604 -213.46668)
					(mid 264.402824 -213.46668)
					(end 265.055604 -213.46668)
				)
			)
		)
	)
	(zone
		(layers "B.Cu" "In11.Cu" "In13.Cu" "In15.Cu")
		(hatch none 0.5)
		(connect_pads
			(clearance 0)
		)
		(min_thickness 0.25)
		(keepout
			(tracks not_allowed)
			(vias allowed)
			(pads allowed)
			(copperpour not_allowed)
			(footprints allowed)
		)
		(placement
			(enabled no)
			(sheetname "")
		)
		(fill yes
			(thermal_gap 0.5)
			(thermal_bridge_width 0.5)
			(island_removal_mode 0)
		)
		(polygon
			(pts
				(arc
					(start 96.929956 -230.900478)
					(mid 96.277176 -230.900478)
					(end 96.929956 -230.900478)
				)
			)
		)
	)
	(zone
		(layers "B.Cu" "In11.Cu" "In13.Cu" "In15.Cu")
		(hatch none 0.5)
		(connect_pads
			(clearance 0)
		)
		(min_thickness 0.25)
		(keepout
			(tracks not_allowed)
			(vias allowed)
			(pads allowed)
			(copperpour not_allowed)
			(footprints allowed)
		)
		(placement
			(enabled no)
			(sheetname "")
		)
		(fill yes
			(thermal_gap 0.5)
			(thermal_bridge_width 0.5)
			(island_removal_mode 0)
		)
		(polygon
			(pts
				(arc
					(start 143.154908 -436.889906)
					(mid 142.345156 -436.889906)
					(end 143.154908 -436.889906)
				)
			)
		)
	)
	(zone
		(layers "B.Cu" "In11.Cu" "In13.Cu" "In15.Cu")
		(hatch none 0.5)
		(connect_pads
			(clearance 0)
		)
		(min_thickness 0.25)
		(keepout
			(tracks not_allowed)
			(vias allowed)
			(pads allowed)
			(copperpour not_allowed)
			(footprints allowed)
		)
		(placement
			(enabled no)
			(sheetname "")
		)
		(fill yes
			(thermal_gap 0.5)
			(thermal_bridge_width 0.5)
			(island_removal_mode 0)
		)
		(polygon
			(pts
				(arc
					(start 128.154938 -430.689766)
					(mid 127.345186 -430.689766)
					(end 128.154938 -430.689766)
				)
			)
		)
	)
	(zone
		(layers "B.Cu" "In11.Cu" "In13.Cu" "In15.Cu")
		(hatch none 0.5)
		(connect_pads
			(clearance 0)
		)
		(min_thickness 0.25)
		(keepout
			(tracks not_allowed)
			(vias allowed)
			(pads allowed)
			(copperpour not_allowed)
			(footprints allowed)
		)
		(placement
			(enabled no)
			(sheetname "")
		)
		(fill yes
			(thermal_gap 0.5)
			(thermal_bridge_width 0.5)
			(island_removal_mode 0)
		)
		(polygon
			(pts
				(arc
					(start 67.054984 -427.289976)
					(mid 66.245232 -427.289976)
					(end 67.054984 -427.289976)
				)
			)
		)
	)
	(zone
		(layers "B.Cu" "In11.Cu" "In13.Cu" "In15.Cu")
		(hatch none 0.5)
		(connect_pads
			(clearance 0)
		)
		(min_thickness 0.25)
		(keepout
			(tracks not_allowed)
			(vias allowed)
			(pads allowed)
			(copperpour not_allowed)
			(footprints allowed)
		)
		(placement
			(enabled no)
			(sheetname "")
		)
		(fill yes
			(thermal_gap 0.5)
			(thermal_bridge_width 0.5)
			(island_removal_mode 0)
		)
		(polygon
			(pts
				(arc
					(start 401.1549 -430.689766)
					(mid 400.345148 -430.689766)
					(end 401.1549 -430.689766)
				)
			)
		)
	)
	(zone
		(layers "B.Cu" "In11.Cu" "In13.Cu" "In15.Cu")
		(hatch none 0.5)
		(connect_pads
			(clearance 0)
		)
		(min_thickness 0.25)
		(keepout
			(tracks not_allowed)
			(vias allowed)
			(pads allowed)
			(copperpour not_allowed)
			(footprints allowed)
		)
		(placement
			(enabled no)
			(sheetname "")
		)
		(fill yes
			(thermal_gap 0.5)
			(thermal_bridge_width 0.5)
			(island_removal_mode 0)
		)
		(polygon
			(pts
				(arc
					(start 130.154934 -429.689768)
					(mid 129.345182 -429.689768)
					(end 130.154934 -429.689768)
				)
			)
		)
	)
	(zone
		(layers "B.Cu" "In11.Cu" "In13.Cu" "In15.Cu")
		(hatch none 0.5)
		(connect_pads
			(clearance 0)
		)
		(min_thickness 0.25)
		(keepout
			(tracks not_allowed)
			(vias allowed)
			(pads allowed)
			(copperpour not_allowed)
			(footprints allowed)
		)
		(placement
			(enabled no)
			(sheetname "")
		)
		(fill yes
			(thermal_gap 0.5)
			(thermal_bridge_width 0.5)
			(island_removal_mode 0)
		)
		(polygon
			(pts
				(arc
					(start 96.100138 -262.058658)
					(mid 95.447358 -262.058658)
					(end 96.100138 -262.058658)
				)
			)
		)
	)
	(zone
		(layers "B.Cu" "In11.Cu" "In13.Cu" "In15.Cu")
		(hatch none 0.5)
		(connect_pads
			(clearance 0)
		)
		(min_thickness 0.25)
		(keepout
			(tracks not_allowed)
			(vias allowed)
			(pads allowed)
			(copperpour not_allowed)
			(footprints allowed)
		)
		(placement
			(enabled no)
			(sheetname "")
		)
		(fill yes
			(thermal_gap 0.5)
			(thermal_bridge_width 0.5)
			(island_removal_mode 0)
		)
		(polygon
			(pts
				(arc
					(start 377.29287 -234.970066)
					(mid 376.64009 -234.970066)
					(end 377.29287 -234.970066)
				)
			)
		)
	)
	(zone
		(layers "B.Cu" "In11.Cu" "In13.Cu" "In15.Cu")
		(hatch none 0.5)
		(connect_pads
			(clearance 0)
		)
		(min_thickness 0.25)
		(keepout
			(tracks not_allowed)
			(vias allowed)
			(pads allowed)
			(copperpour not_allowed)
			(footprints allowed)
		)
		(placement
			(enabled no)
			(sheetname "")
		)
		(fill yes
			(thermal_gap 0.5)
			(thermal_bridge_width 0.5)
			(island_removal_mode 0)
		)
		(polygon
			(pts
				(arc
					(start 76.054966 -427.289976)
					(mid 75.245214 -427.289976)
					(end 76.054966 -427.289976)
				)
			)
		)
	)
	(zone
		(layers "B.Cu" "In11.Cu" "In13.Cu" "In15.Cu")
		(hatch none 0.5)
		(connect_pads
			(clearance 0)
		)
		(min_thickness 0.25)
		(keepout
			(tracks not_allowed)
			(vias allowed)
			(pads allowed)
			(copperpour not_allowed)
			(footprints allowed)
		)
		(placement
			(enabled no)
			(sheetname "")
		)
		(fill yes
			(thermal_gap 0.5)
			(thermal_bridge_width 0.5)
			(island_removal_mode 0)
		)
		(polygon
			(pts
				(arc
					(start 39.746936 -243.216684)
					(mid 39.094156 -243.216684)
					(end 39.746936 -243.216684)
				)
			)
		)
	)
	(zone
		(layers "B.Cu" "In11.Cu" "In13.Cu" "In15.Cu")
		(hatch none 0.5)
		(connect_pads
			(clearance 0)
		)
		(min_thickness 0.25)
		(keepout
			(tracks not_allowed)
			(vias allowed)
			(pads allowed)
			(copperpour not_allowed)
			(footprints allowed)
		)
		(placement
			(enabled no)
			(sheetname "")
		)
		(fill yes
			(thermal_gap 0.5)
			(thermal_bridge_width 0.5)
			(island_removal_mode 0)
		)
		(polygon
			(pts
				(arc
					(start 350.280478 -403.883876)
					(mid 349.576898 -403.883876)
					(end 350.280478 -403.883876)
				)
			)
		)
	)
	(zone
		(layers "B.Cu" "In11.Cu" "In13.Cu" "In15.Cu")
		(hatch none 0.5)
		(connect_pads
			(clearance 0)
		)
		(min_thickness 0.25)
		(keepout
			(tracks not_allowed)
			(vias allowed)
			(pads allowed)
			(copperpour not_allowed)
			(footprints allowed)
		)
		(placement
			(enabled no)
			(sheetname "")
		)
		(fill yes
			(thermal_gap 0.5)
			(thermal_bridge_width 0.5)
			(island_removal_mode 0)
		)
		(polygon
			(pts
				(arc
					(start 21.215604 -312.066686)
					(mid 20.562824 -312.066686)
					(end 21.215604 -312.066686)
				)
			)
		)
	)
	(zone
		(layers "B.Cu" "In11.Cu" "In13.Cu" "In15.Cu")
		(hatch none 0.5)
		(connect_pads
			(clearance 0)
		)
		(min_thickness 0.25)
		(keepout
			(tracks not_allowed)
			(vias allowed)
			(pads allowed)
			(copperpour not_allowed)
			(footprints allowed)
		)
		(placement
			(enabled no)
			(sheetname "")
		)
		(fill yes
			(thermal_gap 0.5)
			(thermal_bridge_width 0.5)
			(island_removal_mode 0)
		)
		(polygon
			(pts
				(arc
					(start 353.438206 -279.964134)
					(mid 352.785426 -279.964134)
					(end 353.438206 -279.964134)
				)
			)
		)
	)
	(zone
		(layers "B.Cu" "In11.Cu" "In13.Cu" "In15.Cu")
		(hatch none 0.5)
		(connect_pads
			(clearance 0)
		)
		(min_thickness 0.25)
		(keepout
			(tracks not_allowed)
			(vias allowed)
			(pads allowed)
			(copperpour not_allowed)
			(footprints allowed)
		)
		(placement
			(enabled no)
			(sheetname "")
		)
		(fill yes
			(thermal_gap 0.5)
			(thermal_bridge_width 0.5)
			(island_removal_mode 0)
		)
		(polygon
			(pts
				(arc
					(start 135.931656 -217.064336)
					(mid 135.278876 -217.064336)
					(end 135.931656 -217.064336)
				)
			)
		)
	)
	(zone
		(layers "B.Cu" "In11.Cu" "In13.Cu" "In15.Cu")
		(hatch none 0.5)
		(connect_pads
			(clearance 0)
		)
		(min_thickness 0.25)
		(keepout
			(tracks not_allowed)
			(vias allowed)
			(pads allowed)
			(copperpour not_allowed)
			(footprints allowed)
		)
		(placement
			(enabled no)
			(sheetname "")
		)
		(fill yes
			(thermal_gap 0.5)
			(thermal_bridge_width 0.5)
			(island_removal_mode 0)
		)
		(polygon
			(pts
				(arc
					(start 384.154934 -431.889916)
					(mid 383.345182 -431.889916)
					(end 384.154934 -431.889916)
				)
			)
		)
	)
	(zone
		(layers "B.Cu" "In11.Cu" "In13.Cu" "In15.Cu")
		(hatch none 0.5)
		(connect_pads
			(clearance 0)
		)
		(min_thickness 0.25)
		(keepout
			(tracks not_allowed)
			(vias allowed)
			(pads allowed)
			(copperpour not_allowed)
			(footprints allowed)
		)
		(placement
			(enabled no)
			(sheetname "")
		)
		(fill yes
			(thermal_gap 0.5)
			(thermal_bridge_width 0.5)
			(island_removal_mode 0)
		)
		(polygon
			(pts
				(arc
					(start 365.07547 -226.831144)
					(mid 364.42269 -226.831144)
					(end 365.07547 -226.831144)
				)
			)
		)
	)
	(zone
		(layers "B.Cu" "In11.Cu" "In13.Cu" "In15.Cu")
		(hatch none 0.5)
		(connect_pads
			(clearance 0)
		)
		(min_thickness 0.25)
		(keepout
			(tracks not_allowed)
			(vias allowed)
			(pads allowed)
			(copperpour not_allowed)
			(footprints allowed)
		)
		(placement
			(enabled no)
			(sheetname "")
		)
		(fill yes
			(thermal_gap 0.5)
			(thermal_bridge_width 0.5)
			(island_removal_mode 0)
		)
		(polygon
			(pts
				(arc
					(start 95.520002 -246.364506)
					(mid 94.867222 -246.364506)
					(end 95.520002 -246.364506)
				)
			)
		)
	)
	(zone
		(layers "B.Cu" "In11.Cu" "In13.Cu" "In15.Cu")
		(hatch none 0.5)
		(connect_pads
			(clearance 0)
		)
		(min_thickness 0.25)
		(keepout
			(tracks not_allowed)
			(vias allowed)
			(pads allowed)
			(copperpour not_allowed)
			(footprints allowed)
		)
		(placement
			(enabled no)
			(sheetname "")
		)
		(fill yes
			(thermal_gap 0.5)
			(thermal_bridge_width 0.5)
			(island_removal_mode 0)
		)
		(polygon
			(pts
				(arc
					(start 265.055604 -316.316614)
					(mid 264.402824 -316.316614)
					(end 265.055604 -316.316614)
				)
			)
		)
	)
	(zone
		(layers "B.Cu" "In11.Cu" "In13.Cu" "In15.Cu")
		(hatch none 0.5)
		(connect_pads
			(clearance 0)
		)
		(min_thickness 0.25)
		(keepout
			(tracks not_allowed)
			(vias allowed)
			(pads allowed)
			(copperpour not_allowed)
			(footprints allowed)
		)
		(placement
			(enabled no)
			(sheetname "")
		)
		(fill yes
			(thermal_gap 0.5)
			(thermal_bridge_width 0.5)
			(island_removal_mode 0)
		)
		(polygon
			(pts
				(arc
					(start 9.571736 -243.216684)
					(mid 8.918956 -243.216684)
					(end 9.571736 -243.216684)
				)
			)
		)
	)
	(zone
		(layers "B.Cu" "In11.Cu" "In13.Cu" "In15.Cu")
		(hatch none 0.5)
		(connect_pads
			(clearance 0)
		)
		(min_thickness 0.25)
		(keepout
			(tracks not_allowed)
			(vias allowed)
			(pads allowed)
			(copperpour not_allowed)
			(footprints allowed)
		)
		(placement
			(enabled no)
			(sheetname "")
		)
		(fill yes
			(thermal_gap 0.5)
			(thermal_bridge_width 0.5)
			(island_removal_mode 0)
		)
		(polygon
			(pts
				(arc
					(start 317.054992 -434.289962)
					(mid 316.24524 -434.289962)
					(end 317.054992 -434.289962)
				)
			)
		)
	)
	(zone
		(layers "B.Cu" "In11.Cu" "In13.Cu" "In15.Cu")
		(hatch none 0.5)
		(connect_pads
			(clearance 0)
		)
		(min_thickness 0.25)
		(keepout
			(tracks not_allowed)
			(vias allowed)
			(pads allowed)
			(copperpour not_allowed)
			(footprints allowed)
		)
		(placement
			(enabled no)
			(sheetname "")
		)
		(fill yes
			(thermal_gap 0.5)
			(thermal_bridge_width 0.5)
			(island_removal_mode 0)
		)
		(polygon
			(pts
				(arc
					(start 284.243272 -221.96679)
					(mid 283.590492 -221.96679)
					(end 284.243272 -221.96679)
				)
			)
		)
	)
	(zone
		(layers "B.Cu" "In11.Cu" "In13.Cu" "In15.Cu")
		(hatch none 0.5)
		(connect_pads
			(clearance 0)
		)
		(min_thickness 0.25)
		(keepout
			(tracks not_allowed)
			(vias allowed)
			(pads allowed)
			(copperpour not_allowed)
			(footprints allowed)
		)
		(placement
			(enabled no)
			(sheetname "")
		)
		(fill yes
			(thermal_gap 0.5)
			(thermal_bridge_width 0.5)
			(island_removal_mode 0)
		)
		(polygon
			(pts
				(arc
					(start 95.629984 -271.011396)
					(mid 94.977204 -271.011396)
					(end 95.629984 -271.011396)
				)
			)
		)
	)
	(zone
		(layers "B.Cu" "In11.Cu" "In13.Cu" "In15.Cu")
		(hatch none 0.5)
		(connect_pads
			(clearance 0)
		)
		(min_thickness 0.25)
		(keepout
			(tracks not_allowed)
			(vias allowed)
			(pads allowed)
			(copperpour not_allowed)
			(footprints allowed)
		)
		(placement
			(enabled no)
			(sheetname "")
		)
		(fill yes
			(thermal_gap 0.5)
			(thermal_bridge_width 0.5)
			(island_removal_mode 0)
		)
		(polygon
			(pts
				(arc
					(start 325.054976 -427.089824)
					(mid 324.245224 -427.089824)
					(end 325.054976 -427.089824)
				)
			)
		)
	)
	(zone
		(layers "B.Cu" "In11.Cu" "In13.Cu" "In15.Cu")
		(hatch none 0.5)
		(connect_pads
			(clearance 0)
		)
		(min_thickness 0.25)
		(keepout
			(tracks not_allowed)
			(vias allowed)
			(pads allowed)
			(copperpour not_allowed)
			(footprints allowed)
		)
		(placement
			(enabled no)
			(sheetname "")
		)
		(fill yes
			(thermal_gap 0.5)
			(thermal_bridge_width 0.5)
			(island_removal_mode 0)
		)
		(polygon
			(pts
				(arc
					(start 192.310004 -214.316564)
					(mid 191.657224 -214.316564)
					(end 192.310004 -214.316564)
				)
			)
		)
	)
	(zone
		(layers "B.Cu" "In11.Cu" "In13.Cu" "In15.Cu")
		(hatch none 0.5)
		(connect_pads
			(clearance 0)
		)
		(min_thickness 0.25)
		(keepout
			(tracks not_allowed)
			(vias allowed)
			(pads allowed)
			(copperpour not_allowed)
			(footprints allowed)
		)
		(placement
			(enabled no)
			(sheetname "")
		)
		(fill yes
			(thermal_gap 0.5)
			(thermal_bridge_width 0.5)
			(island_removal_mode 0)
		)
		(polygon
			(pts
				(arc
					(start 352.55581 -61.480954)
					(mid 351.85223 -61.480954)
					(end 352.55581 -61.480954)
				)
			)
		)
	)
	(zone
		(layers "B.Cu" "In11.Cu" "In13.Cu" "In15.Cu")
		(hatch none 0.5)
		(connect_pads
			(clearance 0)
		)
		(min_thickness 0.25)
		(keepout
			(tracks not_allowed)
			(vias allowed)
			(pads allowed)
			(copperpour not_allowed)
			(footprints allowed)
		)
		(placement
			(enabled no)
			(sheetname "")
		)
		(fill yes
			(thermal_gap 0.5)
			(thermal_bridge_width 0.5)
			(island_removal_mode 0)
		)
		(polygon
			(pts
				(arc
					(start 394.154914 -430.889918)
					(mid 393.345162 -430.889918)
					(end 394.154914 -430.889918)
				)
			)
		)
	)
	(zone
		(layers "B.Cu" "In11.Cu" "In13.Cu" "In15.Cu")
		(hatch none 0.5)
		(connect_pads
			(clearance 0)
		)
		(min_thickness 0.25)
		(keepout
			(tracks not_allowed)
			(vias allowed)
			(pads allowed)
			(copperpour not_allowed)
			(footprints allowed)
		)
		(placement
			(enabled no)
			(sheetname "")
		)
		(fill yes
			(thermal_gap 0.5)
			(thermal_bridge_width 0.5)
			(island_removal_mode 0)
		)
		(polygon
			(pts
				(arc
					(start 153.154888 -430.689766)
					(mid 152.345136 -430.689766)
					(end 153.154888 -430.689766)
				)
			)
		)
	)
	(zone
		(layers "B.Cu" "In11.Cu" "In13.Cu" "In15.Cu")
		(hatch none 0.5)
		(connect_pads
			(clearance 0)
		)
		(min_thickness 0.25)
		(keepout
			(tracks not_allowed)
			(vias allowed)
			(pads allowed)
			(copperpour not_allowed)
			(footprints allowed)
		)
		(placement
			(enabled no)
			(sheetname "")
		)
		(fill yes
			(thermal_gap 0.5)
			(thermal_bridge_width 0.5)
			(island_removal_mode 0)
		)
		(polygon
			(pts
				(arc
					(start 440.250072 -298.466764)
					(mid 439.597292 -298.466764)
					(end 440.250072 -298.466764)
				)
			)
		)
	)
	(zone
		(layers "B.Cu" "In11.Cu" "In13.Cu" "In15.Cu")
		(hatch none 0.5)
		(connect_pads
			(clearance 0)
		)
		(min_thickness 0.25)
		(keepout
			(tracks not_allowed)
			(vias allowed)
			(pads allowed)
			(copperpour not_allowed)
			(footprints allowed)
		)
		(placement
			(enabled no)
			(sheetname "")
		)
		(fill yes
			(thermal_gap 0.5)
			(thermal_bridge_width 0.5)
			(island_removal_mode 0)
		)
		(polygon
			(pts
				(arc
					(start 352.028252 -279.150318)
					(mid 351.375472 -279.150318)
					(end 352.028252 -279.150318)
				)
			)
		)
	)
	(zone
		(layers "B.Cu" "In11.Cu" "In13.Cu" "In15.Cu")
		(hatch none 0.5)
		(connect_pads
			(clearance 0)
		)
		(min_thickness 0.25)
		(keepout
			(tracks not_allowed)
			(vias allowed)
			(pads allowed)
			(copperpour not_allowed)
			(footprints allowed)
		)
		(placement
			(enabled no)
			(sheetname "")
		)
		(fill yes
			(thermal_gap 0.5)
			(thermal_bridge_width 0.5)
			(island_removal_mode 0)
		)
		(polygon
			(pts
				(arc
					(start 436.150004 -228.766624)
					(mid 435.497224 -228.766624)
					(end 436.150004 -228.766624)
				)
			)
		)
	)
	(zone
		(layers "B.Cu" "In11.Cu" "In13.Cu" "In15.Cu")
		(hatch none 0.5)
		(connect_pads
			(clearance 0)
		)
		(min_thickness 0.25)
		(keepout
			(tracks not_allowed)
			(vias allowed)
			(pads allowed)
			(copperpour not_allowed)
			(footprints allowed)
		)
		(placement
			(enabled no)
			(sheetname "")
		)
		(fill yes
			(thermal_gap 0.5)
			(thermal_bridge_width 0.5)
			(island_removal_mode 0)
		)
		(polygon
			(pts
				(arc
					(start 203.297536 -213.46668)
					(mid 202.644756 -213.46668)
					(end 203.297536 -213.46668)
				)
			)
		)
	)
	(zone
		(layers "B.Cu" "In11.Cu" "In13.Cu" "In15.Cu")
		(hatch none 0.5)
		(connect_pads
			(clearance 0)
		)
		(min_thickness 0.25)
		(keepout
			(tracks not_allowed)
			(vias allowed)
			(pads allowed)
			(copperpour not_allowed)
			(footprints allowed)
		)
		(placement
			(enabled no)
			(sheetname "")
		)
		(fill yes
			(thermal_gap 0.5)
			(thermal_bridge_width 0.5)
			(island_removal_mode 0)
		)
		(polygon
			(pts
				(arc
					(start 440.250072 -225.36658)
					(mid 439.597292 -225.36658)
					(end 440.250072 -225.36658)
				)
			)
		)
	)
	(zone
		(layers "B.Cu" "In11.Cu" "In13.Cu" "In15.Cu")
		(hatch none 0.5)
		(connect_pads
			(clearance 0)
		)
		(min_thickness 0.25)
		(keepout
			(tracks not_allowed)
			(vias allowed)
			(pads allowed)
			(copperpour not_allowed)
			(footprints allowed)
		)
		(placement
			(enabled no)
			(sheetname "")
		)
		(fill yes
			(thermal_gap 0.5)
			(thermal_bridge_width 0.5)
			(island_removal_mode 0)
		)
		(polygon
			(pts
				(arc
					(start 357.197152 -273.453098)
					(mid 356.544372 -273.453098)
					(end 357.197152 -273.453098)
				)
			)
		)
	)
	(zone
		(layers "B.Cu" "In11.Cu" "In13.Cu" "In15.Cu")
		(hatch none 0.5)
		(connect_pads
			(clearance 0)
		)
		(min_thickness 0.25)
		(keepout
			(tracks not_allowed)
			(vias allowed)
			(pads allowed)
			(copperpour not_allowed)
			(footprints allowed)
		)
		(placement
			(enabled no)
			(sheetname "")
		)
		(fill yes
			(thermal_gap 0.5)
			(thermal_bridge_width 0.5)
			(island_removal_mode 0)
		)
		(polygon
			(pts
				(arc
					(start 188.209936 -196.466714)
					(mid 187.557156 -196.466714)
					(end 188.209936 -196.466714)
				)
			)
		)
	)
	(zone
		(layers "B.Cu" "In11.Cu" "In13.Cu" "In15.Cu")
		(hatch none 0.5)
		(connect_pads
			(clearance 0)
		)
		(min_thickness 0.25)
		(keepout
			(tracks not_allowed)
			(vias allowed)
			(pads allowed)
			(copperpour not_allowed)
			(footprints allowed)
		)
		(placement
			(enabled no)
			(sheetname "")
		)
		(fill yes
			(thermal_gap 0.5)
			(thermal_bridge_width 0.5)
			(island_removal_mode 0)
		)
		(polygon
			(pts
				(arc
					(start 21.215604 -315.46673)
					(mid 20.562824 -315.46673)
					(end 21.215604 -315.46673)
				)
			)
		)
	)
	(zone
		(layers "B.Cu" "In11.Cu" "In13.Cu" "In15.Cu")
		(hatch none 0.5)
		(connect_pads
			(clearance 0)
		)
		(min_thickness 0.25)
		(keepout
			(tracks not_allowed)
			(vias allowed)
			(pads allowed)
			(copperpour not_allowed)
			(footprints allowed)
		)
		(placement
			(enabled no)
			(sheetname "")
		)
		(fill yes
			(thermal_gap 0.5)
			(thermal_bridge_width 0.5)
			(island_removal_mode 0)
		)
		(polygon
			(pts
				(arc
					(start 61.054996 -427.089824)
					(mid 60.245244 -427.089824)
					(end 61.054996 -427.089824)
				)
			)
		)
	)
	(zone
		(layers "B.Cu" "In11.Cu" "In13.Cu" "In15.Cu")
		(hatch none 0.5)
		(connect_pads
			(clearance 0)
		)
		(min_thickness 0.25)
		(keepout
			(tracks not_allowed)
			(vias allowed)
			(pads allowed)
			(copperpour not_allowed)
			(footprints allowed)
		)
		(placement
			(enabled no)
			(sheetname "")
		)
		(fill yes
			(thermal_gap 0.5)
			(thermal_bridge_width 0.5)
			(island_removal_mode 0)
		)
		(polygon
			(pts
				(arc
					(start 284.243272 -223.666558)
					(mid 283.590492 -223.666558)
					(end 284.243272 -223.666558)
				)
			)
		)
	)
	(zone
		(layers "B.Cu" "In11.Cu" "In13.Cu" "In15.Cu")
		(hatch none 0.5)
		(connect_pads
			(clearance 0)
		)
		(min_thickness 0.25)
		(keepout
			(tracks not_allowed)
			(vias allowed)
			(pads allowed)
			(copperpour not_allowed)
			(footprints allowed)
		)
		(placement
			(enabled no)
			(sheetname "")
		)
		(fill yes
			(thermal_gap 0.5)
			(thermal_bridge_width 0.5)
			(island_removal_mode 0)
		)
		(polygon
			(pts
				(arc
					(start 130.154934 -438.089802)
					(mid 129.345182 -438.089802)
					(end 130.154934 -438.089802)
				)
			)
		)
	)
	(zone
		(layers "B.Cu" "In11.Cu" "In13.Cu" "In15.Cu")
		(hatch none 0.5)
		(connect_pads
			(clearance 0)
		)
		(min_thickness 0.25)
		(keepout
			(tracks not_allowed)
			(vias allowed)
			(pads allowed)
			(copperpour not_allowed)
			(footprints allowed)
		)
		(placement
			(enabled no)
			(sheetname "")
		)
		(fill yes
			(thermal_gap 0.5)
			(thermal_bridge_width 0.5)
			(island_removal_mode 0)
		)
		(polygon
			(pts
				(arc
					(start 386.15493 -436.889906)
					(mid 385.345178 -436.889906)
					(end 386.15493 -436.889906)
				)
			)
		)
	)
	(zone
		(layers "B.Cu" "In11.Cu" "In13.Cu" "In15.Cu")
		(hatch none 0.5)
		(connect_pads
			(clearance 0)
		)
		(min_thickness 0.25)
		(keepout
			(tracks not_allowed)
			(vias allowed)
			(pads allowed)
			(copperpour not_allowed)
			(footprints allowed)
		)
		(placement
			(enabled no)
			(sheetname "")
		)
		(fill yes
			(thermal_gap 0.5)
			(thermal_bridge_width 0.5)
			(island_removal_mode 0)
		)
		(polygon
			(pts
				(arc
					(start 451.237604 -316.316614)
					(mid 450.584824 -316.316614)
					(end 451.237604 -316.316614)
				)
			)
		)
	)
	(zone
		(layers "B.Cu" "In11.Cu" "In13.Cu" "In15.Cu")
		(hatch none 0.5)
		(connect_pads
			(clearance 0)
		)
		(min_thickness 0.25)
		(keepout
			(tracks not_allowed)
			(vias allowed)
			(pads allowed)
			(copperpour not_allowed)
			(footprints allowed)
		)
		(placement
			(enabled no)
			(sheetname "")
		)
		(fill yes
			(thermal_gap 0.5)
			(thermal_bridge_width 0.5)
			(island_removal_mode 0)
		)
		(polygon
			(pts
				(arc
					(start 17.115536 -205.816708)
					(mid 16.462756 -205.816708)
					(end 17.115536 -205.816708)
				)
			)
		)
	)
	(zone
		(layers "B.Cu" "In11.Cu" "In13.Cu" "In15.Cu")
		(hatch none 0.5)
		(connect_pads
			(clearance 0)
		)
		(min_thickness 0.25)
		(keepout
			(tracks not_allowed)
			(vias allowed)
			(pads allowed)
			(copperpour not_allowed)
			(footprints allowed)
		)
		(placement
			(enabled no)
			(sheetname "")
		)
		(fill yes
			(thermal_gap 0.5)
			(thermal_bridge_width 0.5)
			(island_removal_mode 0)
		)
		(polygon
			(pts
				(arc
					(start 269.155672 -208.366614)
					(mid 268.502892 -208.366614)
					(end 269.155672 -208.366614)
				)
			)
		)
	)
	(zone
		(layers "B.Cu" "In11.Cu" "In13.Cu" "In15.Cu")
		(hatch none 0.5)
		(connect_pads
			(clearance 0)
		)
		(min_thickness 0.25)
		(keepout
			(tracks not_allowed)
			(vias allowed)
			(pads allowed)
			(copperpour not_allowed)
			(footprints allowed)
		)
		(placement
			(enabled no)
			(sheetname "")
		)
		(fill yes
			(thermal_gap 0.5)
			(thermal_bridge_width 0.5)
			(island_removal_mode 0)
		)
		(polygon
			(pts
				(arc
					(start 348.739206 -281.59202)
					(mid 348.086426 -281.59202)
					(end 348.739206 -281.59202)
				)
			)
		)
	)
	(zone
		(layers "B.Cu" "In11.Cu" "In13.Cu" "In15.Cu")
		(hatch none 0.5)
		(connect_pads
			(clearance 0)
		)
		(min_thickness 0.25)
		(keepout
			(tracks not_allowed)
			(vias allowed)
			(pads allowed)
			(copperpour not_allowed)
			(footprints allowed)
		)
		(placement
			(enabled no)
			(sheetname "")
		)
		(fill yes
			(thermal_gap 0.5)
			(thermal_bridge_width 0.5)
			(island_removal_mode 0)
		)
		(polygon
			(pts
				(arc
					(start 129.462784 -277.522432)
					(mid 128.810004 -277.522432)
					(end 129.462784 -277.522432)
				)
			)
		)
	)
	(zone
		(layers "B.Cu" "In11.Cu" "In13.Cu" "In15.Cu")
		(hatch none 0.5)
		(connect_pads
			(clearance 0)
		)
		(min_thickness 0.25)
		(keepout
			(tracks not_allowed)
			(vias allowed)
			(pads allowed)
			(copperpour not_allowed)
			(footprints allowed)
		)
		(placement
			(enabled no)
			(sheetname "")
		)
		(fill yes
			(thermal_gap 0.5)
			(thermal_bridge_width 0.5)
			(island_removal_mode 0)
		)
		(polygon
			(pts
				(arc
					(start 436.150004 -274.66671)
					(mid 435.497224 -274.66671)
					(end 436.150004 -274.66671)
				)
			)
		)
	)
	(zone
		(layers "B.Cu" "In11.Cu" "In13.Cu" "In15.Cu")
		(hatch none 0.5)
		(connect_pads
			(clearance 0)
		)
		(min_thickness 0.25)
		(keepout
			(tracks not_allowed)
			(vias allowed)
			(pads allowed)
			(copperpour not_allowed)
			(footprints allowed)
		)
		(placement
			(enabled no)
			(sheetname "")
		)
		(fill yes
			(thermal_gap 0.5)
			(thermal_bridge_width 0.5)
			(island_removal_mode 0)
		)
		(polygon
			(pts
				(arc
					(start 344.870024 -235.783882)
					(mid 344.217244 -235.783882)
					(end 344.870024 -235.783882)
				)
			)
		)
	)
	(zone
		(layers "B.Cu" "In11.Cu" "In13.Cu" "In15.Cu")
		(hatch none 0.5)
		(connect_pads
			(clearance 0)
		)
		(min_thickness 0.25)
		(keepout
			(tracks not_allowed)
			(vias allowed)
			(pads allowed)
			(copperpour not_allowed)
			(footprints allowed)
		)
		(placement
			(enabled no)
			(sheetname "")
		)
		(fill yes
			(thermal_gap 0.5)
			(thermal_bridge_width 0.5)
			(island_removal_mode 0)
		)
		(polygon
			(pts
				(arc
					(start 440.250072 -285.716726)
					(mid 439.597292 -285.716726)
					(end 440.250072 -285.716726)
				)
			)
		)
	)
	(zone
		(layers "B.Cu" "In11.Cu" "In13.Cu" "In15.Cu")
		(hatch none 0.5)
		(connect_pads
			(clearance 0)
		)
		(min_thickness 0.25)
		(keepout
			(tracks not_allowed)
			(vias allowed)
			(pads allowed)
			(copperpour not_allowed)
			(footprints allowed)
		)
		(placement
			(enabled no)
			(sheetname "")
		)
		(fill yes
			(thermal_gap 0.5)
			(thermal_bridge_width 0.5)
			(island_removal_mode 0)
		)
		(polygon
			(pts
				(arc
					(start 86.054946 -434.289962)
					(mid 85.245194 -434.289962)
					(end 86.054946 -434.289962)
				)
			)
		)
	)
	(zone
		(layers "B.Cu" "In11.Cu" "In13.Cu" "In15.Cu")
		(hatch none 0.5)
		(connect_pads
			(clearance 0)
		)
		(min_thickness 0.25)
		(keepout
			(tracks not_allowed)
			(vias allowed)
			(pads allowed)
			(copperpour not_allowed)
			(footprints allowed)
		)
		(placement
			(enabled no)
			(sheetname "")
		)
		(fill yes
			(thermal_gap 0.5)
			(thermal_bridge_width 0.5)
			(island_removal_mode 0)
		)
		(polygon
			(pts
				(arc
					(start 95.049848 -214.622634)
					(mid 94.397068 -214.622634)
					(end 95.049848 -214.622634)
				)
			)
		)
	)
	(zone
		(layers "B.Cu" "In11.Cu" "In13.Cu" "In15.Cu")
		(hatch none 0.5)
		(connect_pads
			(clearance 0)
		)
		(min_thickness 0.25)
		(keepout
			(tracks not_allowed)
			(vias allowed)
			(pads allowed)
			(copperpour not_allowed)
			(footprints allowed)
		)
		(placement
			(enabled no)
			(sheetname "")
		)
		(fill yes
			(thermal_gap 0.5)
			(thermal_bridge_width 0.5)
			(island_removal_mode 0)
		)
		(polygon
			(pts
				(arc
					(start 95.629984 -274.266914)
					(mid 94.977204 -274.266914)
					(end 95.629984 -274.266914)
				)
			)
		)
	)
	(zone
		(layers "B.Cu" "In11.Cu" "In13.Cu" "In15.Cu")
		(hatch none 0.5)
		(connect_pads
			(clearance 0)
		)
		(min_thickness 0.25)
		(keepout
			(tracks not_allowed)
			(vias allowed)
			(pads allowed)
			(copperpour not_allowed)
			(footprints allowed)
		)
		(placement
			(enabled no)
			(sheetname "")
		)
		(fill yes
			(thermal_gap 0.5)
			(thermal_bridge_width 0.5)
			(island_removal_mode 0)
		)
		(polygon
			(pts
				(arc
					(start 97.979738 -275.08073)
					(mid 97.326958 -275.08073)
					(end 97.979738 -275.08073)
				)
			)
		)
	)
	(zone
		(layers "B.Cu" "In11.Cu" "In13.Cu" "In15.Cu")
		(hatch none 0.5)
		(connect_pads
			(clearance 0)
		)
		(min_thickness 0.25)
		(keepout
			(tracks not_allowed)
			(vias allowed)
			(pads allowed)
			(copperpour not_allowed)
			(footprints allowed)
		)
		(placement
			(enabled no)
			(sheetname "")
		)
		(fill yes
			(thermal_gap 0.5)
			(thermal_bridge_width 0.5)
			(island_removal_mode 0)
		)
		(polygon
			(pts
				(arc
					(start 84.05495 -434.48986)
					(mid 83.245198 -434.48986)
					(end 84.05495 -434.48986)
				)
			)
		)
	)
	(zone
		(layers "B.Cu" "In11.Cu" "In13.Cu" "In15.Cu")
		(hatch none 0.5)
		(connect_pads
			(clearance 0)
		)
		(min_thickness 0.25)
		(keepout
			(tracks not_allowed)
			(vias allowed)
			(pads allowed)
			(copperpour not_allowed)
			(footprints allowed)
		)
		(placement
			(enabled no)
			(sheetname "")
		)
		(fill yes
			(thermal_gap 0.5)
			(thermal_bridge_width 0.5)
			(island_removal_mode 0)
		)
		(polygon
			(pts
				(arc
					(start 350.441514 -182.272432)
					(mid 349.737934 -182.272432)
					(end 350.441514 -182.272432)
				)
			)
		)
	)
	(zone
		(layers "B.Cu" "In11.Cu" "In13.Cu" "In15.Cu")
		(hatch none 0.5)
		(connect_pads
			(clearance 0)
		)
		(min_thickness 0.25)
		(keepout
			(tracks not_allowed)
			(vias allowed)
			(pads allowed)
			(copperpour not_allowed)
			(footprints allowed)
		)
		(placement
			(enabled no)
			(sheetname "")
		)
		(fill yes
			(thermal_gap 0.5)
			(thermal_bridge_width 0.5)
			(island_removal_mode 0)
		)
		(polygon
			(pts
				(arc
					(start 455.337672 -311.216802)
					(mid 454.684892 -311.216802)
					(end 455.337672 -311.216802)
				)
			)
		)
	)
	(zone
		(layers "B.Cu" "In11.Cu" "In13.Cu" "In15.Cu")
		(hatch none 0.5)
		(connect_pads
			(clearance 0)
		)
		(min_thickness 0.25)
		(keepout
			(tracks not_allowed)
			(vias allowed)
			(pads allowed)
			(copperpour not_allowed)
			(footprints allowed)
		)
		(placement
			(enabled no)
			(sheetname "")
		)
		(fill yes
			(thermal_gap 0.5)
			(thermal_bridge_width 0.5)
			(island_removal_mode 0)
		)
		(polygon
			(pts
				(arc
					(start 95.520002 -236.597952)
					(mid 94.867222 -236.597952)
					(end 95.520002 -236.597952)
				)
			)
		)
	)
	(zone
		(layers "B.Cu" "In11.Cu" "In13.Cu" "In15.Cu")
		(hatch none 0.5)
		(connect_pads
			(clearance 0)
		)
		(min_thickness 0.25)
		(keepout
			(tracks not_allowed)
			(vias allowed)
			(pads allowed)
			(copperpour not_allowed)
			(footprints allowed)
		)
		(placement
			(enabled no)
			(sheetname "")
		)
		(fill yes
			(thermal_gap 0.5)
			(thermal_bridge_width 0.5)
			(island_removal_mode 0)
		)
		(polygon
			(pts
				(arc
					(start 345.449652 -264.50036)
					(mid 344.796872 -264.50036)
					(end 345.449652 -264.50036)
				)
			)
		)
	)
	(zone
		(layers "B.Cu" "In11.Cu" "In13.Cu" "In15.Cu")
		(hatch none 0.5)
		(connect_pads
			(clearance 0)
		)
		(min_thickness 0.25)
		(keepout
			(tracks not_allowed)
			(vias allowed)
			(pads allowed)
			(copperpour not_allowed)
			(footprints allowed)
		)
		(placement
			(enabled no)
			(sheetname "")
		)
		(fill yes
			(thermal_gap 0.5)
			(thermal_bridge_width 0.5)
			(island_removal_mode 0)
		)
		(polygon
			(pts
				(arc
					(start 376.35307 -228.45903)
					(mid 375.70029 -228.45903)
					(end 376.35307 -228.45903)
				)
			)
		)
	)
	(zone
		(layers "B.Cu" "In11.Cu" "In13.Cu" "In15.Cu")
		(hatch none 0.5)
		(connect_pads
			(clearance 0)
		)
		(min_thickness 0.25)
		(keepout
			(tracks not_allowed)
			(vias allowed)
			(pads allowed)
			(copperpour not_allowed)
			(footprints allowed)
		)
		(placement
			(enabled no)
			(sheetname "")
		)
		(fill yes
			(thermal_gap 0.5)
			(thermal_bridge_width 0.5)
			(island_removal_mode 0)
		)
		(polygon
			(pts
				(arc
					(start 344.040206 -266.941808)
					(mid 343.387426 -266.941808)
					(end 344.040206 -266.941808)
				)
			)
		)
	)
	(zone
		(layers "B.Cu" "In11.Cu" "In13.Cu" "In15.Cu")
		(hatch none 0.5)
		(connect_pads
			(clearance 0)
		)
		(min_thickness 0.25)
		(keepout
			(tracks not_allowed)
			(vias allowed)
			(pads allowed)
			(copperpour not_allowed)
			(footprints allowed)
		)
		(placement
			(enabled no)
			(sheetname "")
		)
		(fill yes
			(thermal_gap 0.5)
			(thermal_bridge_width 0.5)
			(island_removal_mode 0)
		)
		(polygon
			(pts
				(arc
					(start 132.15493 -431.889916)
					(mid 131.345178 -431.889916)
					(end 132.15493 -431.889916)
				)
			)
		)
	)
	(zone
		(layers "B.Cu" "In11.Cu" "In13.Cu" "In15.Cu")
		(hatch none 0.5)
		(connect_pads
			(clearance 0)
		)
		(min_thickness 0.25)
		(keepout
			(tracks not_allowed)
			(vias allowed)
			(pads allowed)
			(copperpour not_allowed)
			(footprints allowed)
		)
		(placement
			(enabled no)
			(sheetname "")
		)
		(fill yes
			(thermal_gap 0.5)
			(thermal_bridge_width 0.5)
			(island_removal_mode 0)
		)
		(polygon
			(pts
				(arc
					(start 284.243272 -287.416748)
					(mid 283.590492 -287.416748)
					(end 284.243272 -287.416748)
				)
			)
		)
	)
	(zone
		(layers "B.Cu" "In11.Cu" "In13.Cu" "In15.Cu")
		(hatch none 0.5)
		(connect_pads
			(clearance 0)
		)
		(min_thickness 0.25)
		(keepout
			(tracks not_allowed)
			(vias allowed)
			(pads allowed)
			(copperpour not_allowed)
			(footprints allowed)
		)
		(placement
			(enabled no)
			(sheetname "")
		)
		(fill yes
			(thermal_gap 0.5)
			(thermal_bridge_width 0.5)
			(island_removal_mode 0)
		)
		(polygon
			(pts
				(arc
					(start 192.310004 -304.416714)
					(mid 191.657224 -304.416714)
					(end 192.310004 -304.416714)
				)
			)
		)
	)
	(zone
		(layers "B.Cu" "In11.Cu" "In13.Cu" "In15.Cu")
		(hatch none 0.5)
		(connect_pads
			(clearance 0)
		)
		(min_thickness 0.25)
		(keepout
			(tracks not_allowed)
			(vias allowed)
			(pads allowed)
			(copperpour not_allowed)
			(footprints allowed)
		)
		(placement
			(enabled no)
			(sheetname "")
		)
		(fill yes
			(thermal_gap 0.5)
			(thermal_bridge_width 0.5)
			(island_removal_mode 0)
		)
		(polygon
			(pts
				(arc
					(start 352.028252 -282.405836)
					(mid 351.375472 -282.405836)
					(end 352.028252 -282.405836)
				)
			)
		)
	)
	(zone
		(layers "B.Cu" "In11.Cu" "In13.Cu" "In15.Cu")
		(hatch none 0.5)
		(connect_pads
			(clearance 0)
		)
		(min_thickness 0.25)
		(keepout
			(tracks not_allowed)
			(vias allowed)
			(pads allowed)
			(copperpour not_allowed)
			(footprints allowed)
		)
		(placement
			(enabled no)
			(sheetname "")
		)
		(fill yes
			(thermal_gap 0.5)
			(thermal_bridge_width 0.5)
			(island_removal_mode 0)
		)
		(polygon
			(pts
				(arc
					(start 151.154892 -438.089802)
					(mid 150.34514 -438.089802)
					(end 151.154892 -438.089802)
				)
			)
		)
	)
	(zone
		(layers "B.Cu" "In11.Cu" "In13.Cu" "In15.Cu")
		(hatch none 0.5)
		(connect_pads
			(clearance 0)
		)
		(min_thickness 0.25)
		(keepout
			(tracks not_allowed)
			(vias allowed)
			(pads allowed)
			(copperpour not_allowed)
			(footprints allowed)
		)
		(placement
			(enabled no)
			(sheetname "")
		)
		(fill yes
			(thermal_gap 0.5)
			(thermal_bridge_width 0.5)
			(island_removal_mode 0)
		)
		(polygon
			(pts
				(arc
					(start 378.812806 -253.919736)
					(mid 378.160026 -253.919736)
					(end 378.812806 -253.919736)
				)
			)
		)
	)
	(zone
		(layers "B.Cu" "In11.Cu" "In13.Cu" "In15.Cu")
		(hatch none 0.5)
		(connect_pads
			(clearance 0)
		)
		(min_thickness 0.25)
		(keepout
			(tracks not_allowed)
			(vias allowed)
			(pads allowed)
			(copperpour not_allowed)
			(footprints allowed)
		)
		(placement
			(enabled no)
			(sheetname "")
		)
		(fill yes
			(thermal_gap 0.5)
			(thermal_bridge_width 0.5)
			(island_removal_mode 0)
		)
		(polygon
			(pts
				(arc
					(start 192.310004 -285.716726)
					(mid 191.657224 -285.716726)
					(end 192.310004 -285.716726)
				)
			)
		)
	)
	(zone
		(layers "B.Cu" "In11.Cu" "In13.Cu" "In15.Cu")
		(hatch none 0.5)
		(connect_pads
			(clearance 0)
		)
		(min_thickness 0.25)
		(keepout
			(tracks not_allowed)
			(vias allowed)
			(pads allowed)
			(copperpour not_allowed)
			(footprints allowed)
		)
		(placement
			(enabled no)
			(sheetname "")
		)
		(fill yes
			(thermal_gap 0.5)
			(thermal_bridge_width 0.5)
			(island_removal_mode 0)
		)
		(polygon
			(pts
				(arc
					(start 127.473202 -215.436704)
					(mid 126.820422 -215.436704)
					(end 127.473202 -215.436704)
				)
			)
		)
	)
	(zone
		(layers "B.Cu" "In11.Cu" "In13.Cu" "In15.Cu")
		(hatch none 0.5)
		(connect_pads
			(clearance 0)
		)
		(min_thickness 0.25)
		(keepout
			(tracks not_allowed)
			(vias allowed)
			(pads allowed)
			(copperpour not_allowed)
			(footprints allowed)
		)
		(placement
			(enabled no)
			(sheetname "")
		)
		(fill yes
			(thermal_gap 0.5)
			(thermal_bridge_width 0.5)
			(island_removal_mode 0)
		)
		(polygon
			(pts
				(arc
					(start 134.051802 -215.436704)
					(mid 133.399022 -215.436704)
					(end 134.051802 -215.436704)
				)
			)
		)
	)
	(zone
		(layers "B.Cu" "In11.Cu" "In13.Cu" "In15.Cu")
		(hatch none 0.5)
		(connect_pads
			(clearance 0)
		)
		(min_thickness 0.25)
		(keepout
			(tracks not_allowed)
			(vias allowed)
			(pads allowed)
			(copperpour not_allowed)
			(footprints allowed)
		)
		(placement
			(enabled no)
			(sheetname "")
		)
		(fill yes
			(thermal_gap 0.5)
			(thermal_bridge_width 0.5)
			(island_removal_mode 0)
		)
		(polygon
			(pts
				(arc
					(start 188.209936 -288.266632)
					(mid 187.557156 -288.266632)
					(end 188.209936 -288.266632)
				)
			)
		)
	)
	(zone
		(layers "B.Cu" "In11.Cu" "In13.Cu" "In15.Cu")
		(hatch none 0.5)
		(connect_pads
			(clearance 0)
		)
		(min_thickness 0.25)
		(keepout
			(tracks not_allowed)
			(vias allowed)
			(pads allowed)
			(copperpour not_allowed)
			(footprints allowed)
		)
		(placement
			(enabled no)
			(sheetname "")
		)
		(fill yes
			(thermal_gap 0.5)
			(thermal_bridge_width 0.5)
			(island_removal_mode 0)
		)
		(polygon
			(pts
				(arc
					(start 345.33967 -215.436704)
					(mid 344.68689 -215.436704)
					(end 345.33967 -215.436704)
				)
			)
		)
	)
	(zone
		(layers "B.Cu" "In11.Cu" "In13.Cu" "In15.Cu")
		(hatch none 0.5)
		(connect_pads
			(clearance 0)
		)
		(min_thickness 0.25)
		(keepout
			(tracks not_allowed)
			(vias allowed)
			(pads allowed)
			(copperpour not_allowed)
			(footprints allowed)
		)
		(placement
			(enabled no)
			(sheetname "")
		)
		(fill yes
			(thermal_gap 0.5)
			(thermal_bridge_width 0.5)
			(island_removal_mode 0)
		)
		(polygon
			(pts
				(arc
					(start 95.520002 -243.108988)
					(mid 94.867222 -243.108988)
					(end 95.520002 -243.108988)
				)
			)
		)
	)
	(zone
		(layers "B.Cu" "In11.Cu" "In13.Cu" "In15.Cu")
		(hatch none 0.5)
		(connect_pads
			(clearance 0)
		)
		(min_thickness 0.25)
		(keepout
			(tracks not_allowed)
			(vias allowed)
			(pads allowed)
			(copperpour not_allowed)
			(footprints allowed)
		)
		(placement
			(enabled no)
			(sheetname "")
		)
		(fill yes
			(thermal_gap 0.5)
			(thermal_bridge_width 0.5)
			(island_removal_mode 0)
		)
		(polygon
			(pts
				(arc
					(start 376.463052 -272.639282)
					(mid 375.810272 -272.639282)
					(end 376.463052 -272.639282)
				)
			)
		)
	)
	(zone
		(layers "B.Cu" "In11.Cu" "In13.Cu" "In15.Cu")
		(hatch none 0.5)
		(connect_pads
			(clearance 0)
		)
		(min_thickness 0.25)
		(keepout
			(tracks not_allowed)
			(vias allowed)
			(pads allowed)
			(copperpour not_allowed)
			(footprints allowed)
		)
		(placement
			(enabled no)
			(sheetname "")
		)
		(fill yes
			(thermal_gap 0.5)
			(thermal_bridge_width 0.5)
			(island_removal_mode 0)
		)
		(polygon
			(pts
				(arc
					(start 345.33967 -241.481102)
					(mid 344.68689 -241.481102)
					(end 345.33967 -241.481102)
				)
			)
		)
	)
	(zone
		(layers "B.Cu" "In11.Cu" "In13.Cu" "In15.Cu")
		(hatch none 0.5)
		(connect_pads
			(clearance 0)
		)
		(min_thickness 0.25)
		(keepout
			(tracks not_allowed)
			(vias allowed)
			(pads allowed)
			(copperpour not_allowed)
			(footprints allowed)
		)
		(placement
			(enabled no)
			(sheetname "")
		)
		(fill yes
			(thermal_gap 0.5)
			(thermal_bridge_width 0.5)
			(island_removal_mode 0)
		)
		(polygon
			(pts
				(arc
					(start 342.160352 -281.59202)
					(mid 341.507572 -281.59202)
					(end 342.160352 -281.59202)
				)
			)
		)
	)
	(zone
		(layers "B.Cu" "In11.Cu" "In13.Cu" "In15.Cu")
		(hatch none 0.5)
		(connect_pads
			(clearance 0)
		)
		(min_thickness 0.25)
		(keepout
			(tracks not_allowed)
			(vias allowed)
			(pads allowed)
			(copperpour not_allowed)
			(footprints allowed)
		)
		(placement
			(enabled no)
			(sheetname "")
		)
		(fill yes
			(thermal_gap 0.5)
			(thermal_bridge_width 0.5)
			(island_removal_mode 0)
		)
		(polygon
			(pts
				(arc
					(start 340.054946 -427.289976)
					(mid 339.245194 -427.289976)
					(end 340.054946 -427.289976)
				)
			)
		)
	)
	(zone
		(layers "B.Cu" "In11.Cu" "In13.Cu" "In15.Cu")
		(hatch none 0.5)
		(connect_pads
			(clearance 0)
		)
		(min_thickness 0.25)
		(keepout
			(tracks not_allowed)
			(vias allowed)
			(pads allowed)
			(copperpour not_allowed)
			(footprints allowed)
		)
		(placement
			(enabled no)
			(sheetname "")
		)
		(fill yes
			(thermal_gap 0.5)
			(thermal_bridge_width 0.5)
			(island_removal_mode 0)
		)
		(polygon
			(pts
				(arc
					(start 440.250072 -306.116736)
					(mid 439.597292 -306.116736)
					(end 440.250072 -306.116736)
				)
			)
		)
	)
	(zone
		(layers "B.Cu" "In11.Cu" "In13.Cu" "In15.Cu")
		(hatch none 0.5)
		(connect_pads
			(clearance 0)
		)
		(min_thickness 0.25)
		(keepout
			(tracks not_allowed)
			(vias allowed)
			(pads allowed)
			(copperpour not_allowed)
			(footprints allowed)
		)
		(placement
			(enabled no)
			(sheetname "")
		)
		(fill yes
			(thermal_gap 0.5)
			(thermal_bridge_width 0.5)
			(island_removal_mode 0)
		)
		(polygon
			(pts
				(arc
					(start 188.209936 -286.56661)
					(mid 187.557156 -286.56661)
					(end 188.209936 -286.56661)
				)
			)
		)
	)
	(zone
		(layers "B.Cu" "In11.Cu" "In13.Cu" "In15.Cu")
		(hatch none 0.5)
		(connect_pads
			(clearance 0)
		)
		(min_thickness 0.25)
		(keepout
			(tracks not_allowed)
			(vias allowed)
			(pads allowed)
			(copperpour not_allowed)
			(footprints allowed)
		)
		(placement
			(enabled no)
			(sheetname "")
		)
		(fill yes
			(thermal_gap 0.5)
			(thermal_bridge_width 0.5)
			(island_removal_mode 0)
		)
		(polygon
			(pts
				(arc
					(start 95.990156 -240.667286)
					(mid 95.337376 -240.667286)
					(end 95.990156 -240.667286)
				)
			)
		)
	)
	(zone
		(layers "B.Cu" "In11.Cu" "In13.Cu" "In15.Cu")
		(hatch none 0.5)
		(connect_pads
			(clearance 0)
		)
		(min_thickness 0.25)
		(keepout
			(tracks not_allowed)
			(vias allowed)
			(pads allowed)
			(copperpour not_allowed)
			(footprints allowed)
		)
		(placement
			(enabled no)
			(sheetname "")
		)
		(fill yes
			(thermal_gap 0.5)
			(thermal_bridge_width 0.5)
			(island_removal_mode 0)
		)
		(polygon
			(pts
				(arc
					(start 188.209936 -218.566746)
					(mid 187.557156 -218.566746)
					(end 188.209936 -218.566746)
				)
			)
		)
	)
	(zone
		(layers "B.Cu" "In11.Cu" "In13.Cu" "In15.Cu")
		(hatch none 0.5)
		(connect_pads
			(clearance 0)
		)
		(min_thickness 0.25)
		(keepout
			(tracks not_allowed)
			(vias allowed)
			(pads allowed)
			(copperpour not_allowed)
			(footprints allowed)
		)
		(placement
			(enabled no)
			(sheetname "")
		)
		(fill yes
			(thermal_gap 0.5)
			(thermal_bridge_width 0.5)
			(island_removal_mode 0)
		)
		(polygon
			(pts
				(arc
					(start 377.402852 -272.639282)
					(mid 376.750072 -272.639282)
					(end 377.402852 -272.639282)
				)
			)
		)
	)
	(zone
		(layers "B.Cu" "In11.Cu" "In13.Cu" "In15.Cu")
		(hatch none 0.5)
		(connect_pads
			(clearance 0)
		)
		(min_thickness 0.25)
		(keepout
			(tracks not_allowed)
			(vias allowed)
			(pads allowed)
			(copperpour not_allowed)
			(footprints allowed)
		)
		(placement
			(enabled no)
			(sheetname "")
		)
		(fill yes
			(thermal_gap 0.5)
			(thermal_bridge_width 0.5)
			(island_removal_mode 0)
		)
		(polygon
			(pts
				(arc
					(start 344.980006 -268.569694)
					(mid 344.327226 -268.569694)
					(end 344.980006 -268.569694)
				)
			)
		)
	)
	(zone
		(layers "B.Cu" "In11.Cu" "In13.Cu" "In15.Cu")
		(hatch none 0.5)
		(connect_pads
			(clearance 0)
		)
		(min_thickness 0.25)
		(keepout
			(tracks not_allowed)
			(vias allowed)
			(pads allowed)
			(copperpour not_allowed)
			(footprints allowed)
		)
		(placement
			(enabled no)
			(sheetname "")
		)
		(fill yes
			(thermal_gap 0.5)
			(thermal_bridge_width 0.5)
			(island_removal_mode 0)
		)
		(polygon
			(pts
				(arc
					(start 375.41327 -238.225584)
					(mid 374.76049 -238.225584)
					(end 375.41327 -238.225584)
				)
			)
		)
	)
	(zone
		(layers "B.Cu" "In11.Cu" "In13.Cu" "In15.Cu")
		(hatch none 0.5)
		(connect_pads
			(clearance 0)
		)
		(min_thickness 0.25)
		(keepout
			(tracks not_allowed)
			(vias allowed)
			(pads allowed)
			(copperpour not_allowed)
			(footprints allowed)
		)
		(placement
			(enabled no)
			(sheetname "")
		)
		(fill yes
			(thermal_gap 0.5)
			(thermal_bridge_width 0.5)
			(island_removal_mode 0)
		)
		(polygon
			(pts
				(arc
					(start 405.154892 -439.0898)
					(mid 404.34514 -439.0898)
					(end 405.154892 -439.0898)
				)
			)
		)
	)
	(zone
		(layers "B.Cu" "In11.Cu" "In13.Cu" "In15.Cu")
		(hatch none 0.5)
		(connect_pads
			(clearance 0)
		)
		(min_thickness 0.25)
		(keepout
			(tracks not_allowed)
			(vias allowed)
			(pads allowed)
			(copperpour not_allowed)
			(footprints allowed)
		)
		(placement
			(enabled no)
			(sheetname "")
		)
		(fill yes
			(thermal_gap 0.5)
			(thermal_bridge_width 0.5)
			(island_removal_mode 0)
		)
		(polygon
			(pts
				(arc
					(start 370.474494 -172.971968)
					(mid 369.770914 -172.971968)
					(end 370.474494 -172.971968)
				)
			)
		)
	)
	(zone
		(layers "B.Cu" "In11.Cu" "In13.Cu" "In15.Cu")
		(hatch none 0.5)
		(connect_pads
			(clearance 0)
		)
		(min_thickness 0.25)
		(keepout
			(tracks not_allowed)
			(vias allowed)
			(pads allowed)
			(copperpour not_allowed)
			(footprints allowed)
		)
		(placement
			(enabled no)
			(sheetname "")
		)
		(fill yes
			(thermal_gap 0.5)
			(thermal_bridge_width 0.5)
			(island_removal_mode 0)
		)
		(polygon
			(pts
				(arc
					(start 387.16077 -219.506038)
					(mid 386.50799 -219.506038)
					(end 387.16077 -219.506038)
				)
			)
		)
	)
	(zone
		(layers "B.Cu" "In11.Cu" "In13.Cu" "In15.Cu")
		(hatch none 0.5)
		(connect_pads
			(clearance 0)
		)
		(min_thickness 0.25)
		(keepout
			(tracks not_allowed)
			(vias allowed)
			(pads allowed)
			(copperpour not_allowed)
			(footprints allowed)
		)
		(placement
			(enabled no)
			(sheetname "")
		)
		(fill yes
			(thermal_gap 0.5)
			(thermal_bridge_width 0.5)
			(island_removal_mode 0)
		)
		(polygon
			(pts
				(arc
					(start 121.364248 -214.622634)
					(mid 120.711468 -214.622634)
					(end 121.364248 -214.622634)
				)
			)
		)
	)
	(zone
		(layers "B.Cu" "In11.Cu" "In13.Cu" "In15.Cu")
		(hatch none 0.5)
		(connect_pads
			(clearance 0)
		)
		(min_thickness 0.25)
		(keepout
			(tracks not_allowed)
			(vias allowed)
			(pads allowed)
			(copperpour not_allowed)
			(footprints allowed)
		)
		(placement
			(enabled no)
			(sheetname "")
		)
		(fill yes
			(thermal_gap 0.5)
			(thermal_bridge_width 0.5)
			(island_removal_mode 0)
		)
		(polygon
			(pts
				(arc
					(start 336.521552 -284.847538)
					(mid 335.868772 -284.847538)
					(end 336.521552 -284.847538)
				)
			)
		)
	)
	(zone
		(layers "B.Cu" "In11.Cu" "In13.Cu" "In15.Cu")
		(hatch none 0.5)
		(connect_pads
			(clearance 0)
		)
		(min_thickness 0.25)
		(keepout
			(tracks not_allowed)
			(vias allowed)
			(pads allowed)
			(copperpour not_allowed)
			(footprints allowed)
		)
		(placement
			(enabled no)
			(sheetname "")
		)
		(fill yes
			(thermal_gap 0.5)
			(thermal_bridge_width 0.5)
			(island_removal_mode 0)
		)
		(polygon
			(pts
				(arc
					(start 334.054958 -428.28972)
					(mid 333.245206 -428.28972)
					(end 334.054958 -428.28972)
				)
			)
		)
	)
	(zone
		(layers "B.Cu" "In11.Cu" "In13.Cu" "In15.Cu")
		(hatch none 0.5)
		(connect_pads
			(clearance 0)
		)
		(min_thickness 0.25)
		(keepout
			(tracks not_allowed)
			(vias allowed)
			(pads allowed)
			(copperpour not_allowed)
			(footprints allowed)
		)
		(placement
			(enabled no)
			(sheetname "")
		)
		(fill yes
			(thermal_gap 0.5)
			(thermal_bridge_width 0.5)
			(island_removal_mode 0)
		)
		(polygon
			(pts
				(arc
					(start 36.303204 -302.716692)
					(mid 35.650424 -302.716692)
					(end 36.303204 -302.716692)
				)
			)
		)
	)
	(zone
		(layers "B.Cu" "In11.Cu" "In13.Cu" "In15.Cu")
		(hatch none 0.5)
		(connect_pads
			(clearance 0)
		)
		(min_thickness 0.25)
		(keepout
			(tracks not_allowed)
			(vias allowed)
			(pads allowed)
			(copperpour not_allowed)
			(footprints allowed)
		)
		(placement
			(enabled no)
			(sheetname "")
		)
		(fill yes
			(thermal_gap 0.5)
			(thermal_bridge_width 0.5)
			(island_removal_mode 0)
		)
		(polygon
			(pts
				(arc
					(start 375.053606 -253.919736)
					(mid 374.400826 -253.919736)
					(end 375.053606 -253.919736)
				)
			)
		)
	)
	(zone
		(layers "B.Cu" "In11.Cu" "In13.Cu" "In15.Cu")
		(hatch none 0.5)
		(connect_pads
			(clearance 0)
		)
		(min_thickness 0.25)
		(keepout
			(tracks not_allowed)
			(vias allowed)
			(pads allowed)
			(copperpour not_allowed)
			(footprints allowed)
		)
		(placement
			(enabled no)
			(sheetname "")
		)
		(fill yes
			(thermal_gap 0.5)
			(thermal_bridge_width 0.5)
			(island_removal_mode 0)
		)
		(polygon
			(pts
				(arc
					(start 440.250072 -302.716692)
					(mid 439.597292 -302.716692)
					(end 440.250072 -302.716692)
				)
			)
		)
	)
	(zone
		(layers "B.Cu" "In11.Cu" "In13.Cu" "In15.Cu")
		(hatch none 0.5)
		(connect_pads
			(clearance 0)
		)
		(min_thickness 0.25)
		(keepout
			(tracks not_allowed)
			(vias allowed)
			(pads allowed)
			(copperpour not_allowed)
			(footprints allowed)
		)
		(placement
			(enabled no)
			(sheetname "")
		)
		(fill yes
			(thermal_gap 0.5)
			(thermal_bridge_width 0.5)
			(island_removal_mode 0)
		)
		(polygon
			(pts
				(arc
					(start 349.568516 -214.622634)
					(mid 348.915736 -214.622634)
					(end 349.568516 -214.622634)
				)
			)
		)
	)
	(zone
		(layers "B.Cu" "In11.Cu" "In13.Cu" "In15.Cu")
		(hatch none 0.5)
		(connect_pads
			(clearance 0)
		)
		(min_thickness 0.25)
		(keepout
			(tracks not_allowed)
			(vias allowed)
			(pads allowed)
			(copperpour not_allowed)
			(footprints allowed)
		)
		(placement
			(enabled no)
			(sheetname "")
		)
		(fill yes
			(thermal_gap 0.5)
			(thermal_bridge_width 0.5)
			(island_removal_mode 0)
		)
		(polygon
			(pts
				(arc
					(start 131.812284 -253.919736)
					(mid 131.159504 -253.919736)
					(end 131.812284 -253.919736)
				)
			)
		)
	)
	(zone
		(layers "B.Cu" "In11.Cu" "In13.Cu" "In15.Cu")
		(hatch none 0.5)
		(connect_pads
			(clearance 0)
		)
		(min_thickness 0.25)
		(keepout
			(tracks not_allowed)
			(vias allowed)
			(pads allowed)
			(copperpour not_allowed)
			(footprints allowed)
		)
		(placement
			(enabled no)
			(sheetname "")
		)
		(fill yes
			(thermal_gap 0.5)
			(thermal_bridge_width 0.5)
			(island_removal_mode 0)
		)
		(polygon
			(pts
				(arc
					(start 13.671804 -244.916706)
					(mid 13.019024 -244.916706)
					(end 13.671804 -244.916706)
				)
			)
		)
	)
	(zone
		(layers "B.Cu" "In11.Cu" "In13.Cu" "In15.Cu")
		(hatch none 0.5)
		(connect_pads
			(clearance 0)
		)
		(min_thickness 0.25)
		(keepout
			(tracks not_allowed)
			(vias allowed)
			(pads allowed)
			(copperpour not_allowed)
			(footprints allowed)
		)
		(placement
			(enabled no)
			(sheetname "")
		)
		(fill yes
			(thermal_gap 0.5)
			(thermal_bridge_width 0.5)
			(island_removal_mode 0)
		)
		(polygon
			(pts
				(arc
					(start 95.520002 -215.436704)
					(mid 94.867222 -215.436704)
					(end 95.520002 -215.436704)
				)
			)
		)
	)
	(zone
		(layers "B.Cu" "In11.Cu" "In13.Cu" "In15.Cu")
		(hatch none 0.5)
		(connect_pads
			(clearance 0)
		)
		(min_thickness 0.25)
		(keepout
			(tracks not_allowed)
			(vias allowed)
			(pads allowed)
			(copperpour not_allowed)
			(footprints allowed)
		)
		(placement
			(enabled no)
			(sheetname "")
		)
		(fill yes
			(thermal_gap 0.5)
			(thermal_bridge_width 0.5)
			(island_removal_mode 0)
		)
		(polygon
			(pts
				(arc
					(start 147.1549 -430.889918)
					(mid 146.345148 -430.889918)
					(end 147.1549 -430.889918)
				)
			)
		)
	)
	(zone
		(layers "B.Cu" "In11.Cu" "In13.Cu" "In15.Cu")
		(hatch none 0.5)
		(connect_pads
			(clearance 0)
		)
		(min_thickness 0.25)
		(keepout
			(tracks not_allowed)
			(vias allowed)
			(pads allowed)
			(copperpour not_allowed)
			(footprints allowed)
		)
		(placement
			(enabled no)
			(sheetname "")
		)
		(fill yes
			(thermal_gap 0.5)
			(thermal_bridge_width 0.5)
			(island_removal_mode 0)
		)
		(polygon
			(pts
				(arc
					(start 17.115536 -308.666642)
					(mid 16.462756 -308.666642)
					(end 17.115536 -308.666642)
				)
			)
		)
	)
	(zone
		(layers "B.Cu" "In11.Cu" "In13.Cu" "In15.Cu")
		(hatch none 0.5)
		(connect_pads
			(clearance 0)
		)
		(min_thickness 0.25)
		(keepout
			(tracks not_allowed)
			(vias allowed)
			(pads allowed)
			(copperpour not_allowed)
			(footprints allowed)
		)
		(placement
			(enabled no)
			(sheetname "")
		)
		(fill yes
			(thermal_gap 0.5)
			(thermal_bridge_width 0.5)
			(island_removal_mode 0)
		)
		(polygon
			(pts
				(arc
					(start 374.259094 -170.660568)
					(mid 373.555514 -170.660568)
					(end 374.259094 -170.660568)
				)
			)
		)
	)
	(zone
		(layers "B.Cu" "In11.Cu" "In13.Cu" "In15.Cu")
		(hatch none 0.5)
		(connect_pads
			(clearance 0)
		)
		(min_thickness 0.25)
		(keepout
			(tracks not_allowed)
			(vias allowed)
			(pads allowed)
			(copperpour not_allowed)
			(footprints allowed)
		)
		(placement
			(enabled no)
			(sheetname "")
		)
		(fill yes
			(thermal_gap 0.5)
			(thermal_bridge_width 0.5)
			(island_removal_mode 0)
		)
		(polygon
			(pts
				(arc
					(start 317.448438 -403.883876)
					(mid 316.744858 -403.883876)
					(end 317.448438 -403.883876)
				)
			)
		)
	)
	(zone
		(layers "B.Cu" "In11.Cu" "In13.Cu" "In15.Cu")
		(hatch none 0.5)
		(connect_pads
			(clearance 0)
		)
		(min_thickness 0.25)
		(keepout
			(tracks not_allowed)
			(vias allowed)
			(pads allowed)
			(copperpour not_allowed)
			(footprints allowed)
		)
		(placement
			(enabled no)
			(sheetname "")
		)
		(fill yes
			(thermal_gap 0.5)
			(thermal_bridge_width 0.5)
			(island_removal_mode 0)
		)
		(polygon
			(pts
				(arc
					(start 374.259094 -166.977568)
					(mid 373.555514 -166.977568)
					(end 374.259094 -166.977568)
				)
			)
		)
	)
	(zone
		(layers "B.Cu" "In11.Cu" "In13.Cu" "In15.Cu")
		(hatch none 0.5)
		(connect_pads
			(clearance 0)
		)
		(min_thickness 0.25)
		(keepout
			(tracks not_allowed)
			(vias allowed)
			(pads allowed)
			(copperpour not_allowed)
			(footprints allowed)
		)
		(placement
			(enabled no)
			(sheetname "")
		)
		(fill yes
			(thermal_gap 0.5)
			(thermal_bridge_width 0.5)
			(island_removal_mode 0)
		)
		(polygon
			(pts
				(arc
					(start 36.303204 -199.866758)
					(mid 35.650424 -199.866758)
					(end 36.303204 -199.866758)
				)
			)
		)
	)
	(zone
		(layers "B.Cu" "In11.Cu" "In13.Cu" "In15.Cu")
		(hatch none 0.5)
		(connect_pads
			(clearance 0)
		)
		(min_thickness 0.25)
		(keepout
			(tracks not_allowed)
			(vias allowed)
			(pads allowed)
			(copperpour not_allowed)
			(footprints allowed)
		)
		(placement
			(enabled no)
			(sheetname "")
		)
		(fill yes
			(thermal_gap 0.5)
			(thermal_bridge_width 0.5)
			(island_removal_mode 0)
		)
		(polygon
			(pts
				(arc
					(start 353.327716 -214.622634)
					(mid 352.674936 -214.622634)
					(end 353.327716 -214.622634)
				)
			)
		)
	)
	(zone
		(layers "B.Cu" "In11.Cu" "In13.Cu" "In15.Cu")
		(hatch none 0.5)
		(connect_pads
			(clearance 0)
		)
		(min_thickness 0.25)
		(keepout
			(tracks not_allowed)
			(vias allowed)
			(pads allowed)
			(copperpour not_allowed)
			(footprints allowed)
		)
		(placement
			(enabled no)
			(sheetname "")
		)
		(fill yes
			(thermal_gap 0.5)
			(thermal_bridge_width 0.5)
			(island_removal_mode 0)
		)
		(polygon
			(pts
				(arc
					(start 342.054942 -435.489858)
					(mid 341.24519 -435.489858)
					(end 342.054942 -435.489858)
				)
			)
		)
	)
	(zone
		(layers "B.Cu" "In11.Cu" "In13.Cu" "In15.Cu")
		(hatch none 0.5)
		(connect_pads
			(clearance 0)
		)
		(min_thickness 0.25)
		(keepout
			(tracks not_allowed)
			(vias allowed)
			(pads allowed)
			(copperpour not_allowed)
			(footprints allowed)
		)
		(placement
			(enabled no)
			(sheetname "")
		)
		(fill yes
			(thermal_gap 0.5)
			(thermal_bridge_width 0.5)
			(island_removal_mode 0)
		)
		(polygon
			(pts
				(arc
					(start 375.523252 -264.50036)
					(mid 374.870472 -264.50036)
					(end 375.523252 -264.50036)
				)
			)
		)
	)
	(zone
		(layers "B.Cu" "In11.Cu" "In13.Cu" "In15.Cu")
		(hatch none 0.5)
		(connect_pads
			(clearance 0)
		)
		(min_thickness 0.25)
		(keepout
			(tracks not_allowed)
			(vias allowed)
			(pads allowed)
			(copperpour not_allowed)
			(footprints allowed)
		)
		(placement
			(enabled no)
			(sheetname "")
		)
		(fill yes
			(thermal_gap 0.5)
			(thermal_bridge_width 0.5)
			(island_removal_mode 0)
		)
		(polygon
			(pts
				(arc
					(start 112.906048 -214.546434)
					(mid 112.253268 -214.546434)
					(end 112.906048 -214.546434)
				)
			)
		)
	)
	(zone
		(layers "B.Cu" "In11.Cu" "In13.Cu" "In15.Cu")
		(hatch none 0.5)
		(connect_pads
			(clearance 0)
		)
		(min_thickness 0.25)
		(keepout
			(tracks not_allowed)
			(vias allowed)
			(pads allowed)
			(copperpour not_allowed)
			(footprints allowed)
		)
		(placement
			(enabled no)
			(sheetname "")
		)
		(fill yes
			(thermal_gap 0.5)
			(thermal_bridge_width 0.5)
			(island_removal_mode 0)
		)
		(polygon
			(pts
				(arc
					(start 335.581752 -286.475424)
					(mid 334.928972 -286.475424)
					(end 335.581752 -286.475424)
				)
			)
		)
	)
	(zone
		(layers "B.Cu" "In11.Cu" "In13.Cu" "In15.Cu")
		(hatch none 0.5)
		(connect_pads
			(clearance 0)
		)
		(min_thickness 0.25)
		(keepout
			(tracks not_allowed)
			(vias allowed)
			(pads allowed)
			(copperpour not_allowed)
			(footprints allowed)
		)
		(placement
			(enabled no)
			(sheetname "")
		)
		(fill yes
			(thermal_gap 0.5)
			(thermal_bridge_width 0.5)
			(island_removal_mode 0)
		)
		(polygon
			(pts
				(arc
					(start 451.237604 -244.066568)
					(mid 450.584824 -244.066568)
					(end 451.237604 -244.066568)
				)
			)
		)
	)
	(zone
		(layers "B.Cu" "In11.Cu" "In13.Cu" "In15.Cu")
		(hatch none 0.5)
		(connect_pads
			(clearance 0)
		)
		(min_thickness 0.25)
		(keepout
			(tracks not_allowed)
			(vias allowed)
			(pads allowed)
			(copperpour not_allowed)
			(footprints allowed)
		)
		(placement
			(enabled no)
			(sheetname "")
		)
		(fill yes
			(thermal_gap 0.5)
			(thermal_bridge_width 0.5)
			(island_removal_mode 0)
		)
		(polygon
			(pts
				(arc
					(start 80.310228 -410.030168)
					(mid 79.606648 -410.030168)
					(end 80.310228 -410.030168)
				)
			)
		)
	)
	(zone
		(layers "B.Cu" "In11.Cu" "In13.Cu" "In15.Cu")
		(hatch none 0.5)
		(connect_pads
			(clearance 0)
		)
		(min_thickness 0.25)
		(keepout
			(tracks not_allowed)
			(vias allowed)
			(pads allowed)
			(copperpour not_allowed)
			(footprints allowed)
		)
		(placement
			(enabled no)
			(sheetname "")
		)
		(fill yes
			(thermal_gap 0.5)
			(thermal_bridge_width 0.5)
			(island_removal_mode 0)
		)
		(polygon
			(pts
				(arc
					(start 436.150004 -226.216718)
					(mid 435.497224 -226.216718)
					(end 436.150004 -226.216718)
				)
			)
		)
	)
	(zone
		(layers "B.Cu" "In11.Cu" "In13.Cu" "In15.Cu")
		(hatch none 0.5)
		(connect_pads
			(clearance 0)
		)
		(min_thickness 0.25)
		(keepout
			(tracks not_allowed)
			(vias allowed)
			(pads allowed)
			(copperpour not_allowed)
			(footprints allowed)
		)
		(placement
			(enabled no)
			(sheetname "")
		)
		(fill yes
			(thermal_gap 0.5)
			(thermal_bridge_width 0.5)
			(island_removal_mode 0)
		)
		(polygon
			(pts
				(arc
					(start 348.269052 -282.405836)
					(mid 347.616272 -282.405836)
					(end 348.269052 -282.405836)
				)
			)
		)
	)
	(zone
		(layers "B.Cu" "In11.Cu" "In13.Cu" "In15.Cu")
		(hatch none 0.5)
		(connect_pads
			(clearance 0)
		)
		(min_thickness 0.25)
		(keepout
			(tracks not_allowed)
			(vias allowed)
			(pads allowed)
			(copperpour not_allowed)
			(footprints allowed)
		)
		(placement
			(enabled no)
			(sheetname "")
		)
		(fill yes
			(thermal_gap 0.5)
			(thermal_bridge_width 0.5)
			(island_removal_mode 0)
		)
		(polygon
			(pts
				(arc
					(start 451.237604 -211.766658)
					(mid 450.584824 -211.766658)
					(end 451.237604 -211.766658)
				)
			)
		)
	)
	(zone
		(layers "B.Cu" "In11.Cu" "In13.Cu" "In15.Cu")
		(hatch none 0.5)
		(connect_pads
			(clearance 0)
		)
		(min_thickness 0.25)
		(keepout
			(tracks not_allowed)
			(vias allowed)
			(pads allowed)
			(copperpour not_allowed)
			(footprints allowed)
		)
		(placement
			(enabled no)
			(sheetname "")
		)
		(fill yes
			(thermal_gap 0.5)
			(thermal_bridge_width 0.5)
			(island_removal_mode 0)
		)
		(polygon
			(pts
				(arc
					(start 346.749116 -214.622634)
					(mid 346.096336 -214.622634)
					(end 346.749116 -214.622634)
				)
			)
		)
	)
	(zone
		(layers "B.Cu" "In11.Cu" "In13.Cu" "In15.Cu")
		(hatch none 0.5)
		(connect_pads
			(clearance 0)
		)
		(min_thickness 0.25)
		(keepout
			(tracks not_allowed)
			(vias allowed)
			(pads allowed)
			(copperpour not_allowed)
			(footprints allowed)
		)
		(placement
			(enabled no)
			(sheetname "")
		)
		(fill yes
			(thermal_gap 0.5)
			(thermal_bridge_width 0.5)
			(island_removal_mode 0)
		)
		(polygon
			(pts
				(arc
					(start 350.618806 -283.219906)
					(mid 349.966026 -283.219906)
					(end 350.618806 -283.219906)
				)
			)
		)
	)
	(zone
		(layers "B.Cu" "In11.Cu" "In13.Cu" "In15.Cu")
		(hatch none 0.5)
		(connect_pads
			(clearance 0)
		)
		(min_thickness 0.25)
		(keepout
			(tracks not_allowed)
			(vias allowed)
			(pads allowed)
			(copperpour not_allowed)
			(footprints allowed)
		)
		(placement
			(enabled no)
			(sheetname "")
		)
		(fill yes
			(thermal_gap 0.5)
			(thermal_bridge_width 0.5)
			(island_removal_mode 0)
		)
		(polygon
			(pts
				(arc
					(start 345.449652 -259.616956)
					(mid 344.796872 -259.616956)
					(end 345.449652 -259.616956)
				)
			)
		)
	)
	(zone
		(layers "B.Cu" "In11.Cu" "In13.Cu" "In15.Cu")
		(hatch none 0.5)
		(connect_pads
			(clearance 0)
		)
		(min_thickness 0.25)
		(keepout
			(tracks not_allowed)
			(vias allowed)
			(pads allowed)
			(copperpour not_allowed)
			(footprints allowed)
		)
		(placement
			(enabled no)
			(sheetname "")
		)
		(fill yes
			(thermal_gap 0.5)
			(thermal_bridge_width 0.5)
			(island_removal_mode 0)
		)
		(polygon
			(pts
				(arc
					(start 192.310004 -229.616762)
					(mid 191.657224 -229.616762)
					(end 192.310004 -229.616762)
				)
			)
		)
	)
	(zone
		(layers "B.Cu" "In11.Cu" "In13.Cu" "In15.Cu")
		(hatch none 0.5)
		(connect_pads
			(clearance 0)
		)
		(min_thickness 0.25)
		(keepout
			(tracks not_allowed)
			(vias allowed)
			(pads allowed)
			(copperpour not_allowed)
			(footprints allowed)
		)
		(placement
			(enabled no)
			(sheetname "")
		)
		(fill yes
			(thermal_gap 0.5)
			(thermal_bridge_width 0.5)
			(island_removal_mode 0)
		)
		(polygon
			(pts
				(arc
					(start 339.811106 -282.405836)
					(mid 339.158326 -282.405836)
					(end 339.811106 -282.405836)
				)
			)
		)
	)
	(zone
		(layers "B.Cu" "In11.Cu" "In13.Cu" "In15.Cu")
		(hatch none 0.5)
		(connect_pads
			(clearance 0)
		)
		(min_thickness 0.25)
		(keepout
			(tracks not_allowed)
			(vias allowed)
			(pads allowed)
			(copperpour not_allowed)
			(footprints allowed)
		)
		(placement
			(enabled no)
			(sheetname "")
		)
		(fill yes
			(thermal_gap 0.5)
			(thermal_bridge_width 0.5)
			(island_removal_mode 0)
		)
		(polygon
			(pts
				(arc
					(start 32.203136 -219.41663)
					(mid 31.550356 -219.41663)
					(end 32.203136 -219.41663)
				)
			)
		)
	)
	(zone
		(layers "B.Cu" "In11.Cu" "In13.Cu" "In15.Cu")
		(hatch none 0.5)
		(connect_pads
			(clearance 0)
		)
		(min_thickness 0.25)
		(keepout
			(tracks not_allowed)
			(vias allowed)
			(pads allowed)
			(copperpour not_allowed)
			(footprints allowed)
		)
		(placement
			(enabled no)
			(sheetname "")
		)
		(fill yes
			(thermal_gap 0.5)
			(thermal_bridge_width 0.5)
			(island_removal_mode 0)
		)
		(polygon
			(pts
				(arc
					(start 392.154918 -437.889904)
					(mid 391.345166 -437.889904)
					(end 392.154918 -437.889904)
				)
			)
		)
	)
	(zone
		(layers "B.Cu" "In11.Cu" "In13.Cu" "In15.Cu")
		(hatch none 0.5)
		(connect_pads
			(clearance 0)
		)
		(min_thickness 0.25)
		(keepout
			(tracks not_allowed)
			(vias allowed)
			(pads allowed)
			(copperpour not_allowed)
			(footprints allowed)
		)
		(placement
			(enabled no)
			(sheetname "")
		)
		(fill yes
			(thermal_gap 0.5)
			(thermal_bridge_width 0.5)
			(island_removal_mode 0)
		)
		(polygon
			(pts
				(arc
					(start 341.954358 -403.883876)
					(mid 341.250778 -403.883876)
					(end 341.954358 -403.883876)
				)
			)
		)
	)
	(zone
		(layers "B.Cu" "In11.Cu" "In13.Cu" "In15.Cu")
		(hatch none 0.5)
		(connect_pads
			(clearance 0)
		)
		(min_thickness 0.25)
		(keepout
			(tracks not_allowed)
			(vias allowed)
			(pads allowed)
			(copperpour not_allowed)
			(footprints allowed)
		)
		(placement
			(enabled no)
			(sheetname "")
		)
		(fill yes
			(thermal_gap 0.5)
			(thermal_bridge_width 0.5)
			(island_removal_mode 0)
		)
		(polygon
			(pts
				(arc
					(start 341.110316 -214.622634)
					(mid 340.457536 -214.622634)
					(end 341.110316 -214.622634)
				)
			)
		)
	)
	(zone
		(layers "B.Cu" "In11.Cu" "In13.Cu" "In15.Cu")
		(hatch none 0.5)
		(connect_pads
			(clearance 0)
		)
		(min_thickness 0.25)
		(keepout
			(tracks not_allowed)
			(vias allowed)
			(pads allowed)
			(copperpour not_allowed)
			(footprints allowed)
		)
		(placement
			(enabled no)
			(sheetname "")
		)
		(fill yes
			(thermal_gap 0.5)
			(thermal_bridge_width 0.5)
			(island_removal_mode 0)
		)
		(polygon
			(pts
				(arc
					(start 207.397604 -315.46673)
					(mid 206.744824 -315.46673)
					(end 207.397604 -315.46673)
				)
			)
		)
	)
	(zone
		(layers "B.Cu" "In11.Cu" "In13.Cu" "In15.Cu")
		(hatch none 0.5)
		(connect_pads
			(clearance 0)
		)
		(min_thickness 0.25)
		(keepout
			(tracks not_allowed)
			(vias allowed)
			(pads allowed)
			(copperpour not_allowed)
			(footprints allowed)
		)
		(placement
			(enabled no)
			(sheetname "")
		)
		(fill yes
			(thermal_gap 0.5)
			(thermal_bridge_width 0.5)
			(island_removal_mode 0)
		)
		(polygon
			(pts
				(arc
					(start 284.243272 -283.166566)
					(mid 283.590492 -283.166566)
					(end 284.243272 -283.166566)
				)
			)
		)
	)
	(zone
		(layers "B.Cu" "In11.Cu" "In13.Cu" "In15.Cu")
		(hatch none 0.5)
		(connect_pads
			(clearance 0)
		)
		(min_thickness 0.25)
		(keepout
			(tracks not_allowed)
			(vias allowed)
			(pads allowed)
			(copperpour not_allowed)
			(footprints allowed)
		)
		(placement
			(enabled no)
			(sheetname "")
		)
		(fill yes
			(thermal_gap 0.5)
			(thermal_bridge_width 0.5)
			(island_removal_mode 0)
		)
		(polygon
			(pts
				(arc
					(start 375.523252 -262.872474)
					(mid 374.870472 -262.872474)
					(end 375.523252 -262.872474)
				)
			)
		)
	)
	(zone
		(layers "B.Cu" "In11.Cu" "In13.Cu" "In15.Cu")
		(hatch none 0.5)
		(connect_pads
			(clearance 0)
		)
		(min_thickness 0.25)
		(keepout
			(tracks not_allowed)
			(vias allowed)
			(pads allowed)
			(copperpour not_allowed)
			(footprints allowed)
		)
		(placement
			(enabled no)
			(sheetname "")
		)
		(fill yes
			(thermal_gap 0.5)
			(thermal_bridge_width 0.5)
			(island_removal_mode 0)
		)
		(polygon
			(pts
				(arc
					(start 149.154896 -437.889904)
					(mid 148.345144 -437.889904)
					(end 149.154896 -437.889904)
				)
			)
		)
	)
	(zone
		(layers "B.Cu" "In11.Cu" "In13.Cu" "In15.Cu")
		(hatch none 0.5)
		(connect_pads
			(clearance 0)
		)
		(min_thickness 0.25)
		(keepout
			(tracks not_allowed)
			(vias allowed)
			(pads allowed)
			(copperpour not_allowed)
			(footprints allowed)
		)
		(placement
			(enabled no)
			(sheetname "")
		)
		(fill yes
			(thermal_gap 0.5)
			(thermal_bridge_width 0.5)
			(island_removal_mode 0)
		)
		(polygon
			(pts
				(arc
					(start 376.35307 -231.714548)
					(mid 375.70029 -231.714548)
					(end 376.35307 -231.714548)
				)
			)
		)
	)
	(zone
		(layers "B.Cu" "In11.Cu" "In13.Cu" "In15.Cu")
		(hatch none 0.5)
		(connect_pads
			(clearance 0)
		)
		(min_thickness 0.25)
		(keepout
			(tracks not_allowed)
			(vias allowed)
			(pads allowed)
			(copperpour not_allowed)
			(footprints allowed)
		)
		(placement
			(enabled no)
			(sheetname "")
		)
		(fill yes
			(thermal_gap 0.5)
			(thermal_bridge_width 0.5)
			(island_removal_mode 0)
		)
		(polygon
			(pts
				(arc
					(start 350.441514 -167.032432)
					(mid 349.737934 -167.032432)
					(end 350.441514 -167.032432)
				)
			)
		)
	)
	(zone
		(layers "B.Cu" "In11.Cu" "In13.Cu" "In15.Cu")
		(hatch none 0.5)
		(connect_pads
			(clearance 0)
		)
		(min_thickness 0.25)
		(keepout
			(tracks not_allowed)
			(vias allowed)
			(pads allowed)
			(copperpour not_allowed)
			(footprints allowed)
		)
		(placement
			(enabled no)
			(sheetname "")
		)
		(fill yes
			(thermal_gap 0.5)
			(thermal_bridge_width 0.5)
			(island_removal_mode 0)
		)
		(polygon
			(pts
				(arc
					(start 376.463052 -274.266914)
					(mid 375.810272 -274.266914)
					(end 376.463052 -274.266914)
				)
			)
		)
	)
	(zone
		(layers "B.Cu" "In11.Cu" "In13.Cu" "In15.Cu")
		(hatch none 0.5)
		(connect_pads
			(clearance 0)
		)
		(min_thickness 0.25)
		(keepout
			(tracks not_allowed)
			(vias allowed)
			(pads allowed)
			(copperpour not_allowed)
			(footprints allowed)
		)
		(placement
			(enabled no)
			(sheetname "")
		)
		(fill yes
			(thermal_gap 0.5)
			(thermal_bridge_width 0.5)
			(island_removal_mode 0)
		)
		(polygon
			(pts
				(arc
					(start 142.22984 -18.144744)
					(mid 141.52626 -18.144744)
					(end 142.22984 -18.144744)
				)
			)
		)
	)
	(zone
		(layers "B.Cu" "In11.Cu" "In13.Cu" "In15.Cu")
		(hatch none 0.5)
		(connect_pads
			(clearance 0)
		)
		(min_thickness 0.25)
		(keepout
			(tracks not_allowed)
			(vias allowed)
			(pads allowed)
			(copperpour not_allowed)
			(footprints allowed)
		)
		(placement
			(enabled no)
			(sheetname "")
		)
		(fill yes
			(thermal_gap 0.5)
			(thermal_bridge_width 0.5)
			(island_removal_mode 0)
		)
		(polygon
			(pts
				(arc
					(start 315.054996 -426.089826)
					(mid 314.245244 -426.089826)
					(end 315.054996 -426.089826)
				)
			)
		)
	)
	(zone
		(layers "B.Cu" "In11.Cu" "In13.Cu" "In15.Cu")
		(hatch none 0.5)
		(connect_pads
			(clearance 0)
		)
		(min_thickness 0.25)
		(keepout
			(tracks not_allowed)
			(vias allowed)
			(pads allowed)
			(copperpour not_allowed)
			(footprints allowed)
		)
		(placement
			(enabled no)
			(sheetname "")
		)
		(fill yes
			(thermal_gap 0.5)
			(thermal_bridge_width 0.5)
			(island_removal_mode 0)
		)
		(polygon
			(pts
				(arc
					(start 192.310004 -274.66671)
					(mid 191.657224 -274.66671)
					(end 192.310004 -274.66671)
				)
			)
		)
	)
	(zone
		(layers "B.Cu" "In11.Cu" "In13.Cu" "In15.Cu")
		(hatch none 0.5)
		(connect_pads
			(clearance 0)
		)
		(min_thickness 0.25)
		(keepout
			(tracks not_allowed)
			(vias allowed)
			(pads allowed)
			(copperpour not_allowed)
			(footprints allowed)
		)
		(placement
			(enabled no)
			(sheetname "")
		)
		(fill yes
			(thermal_gap 0.5)
			(thermal_bridge_width 0.5)
			(island_removal_mode 0)
		)
		(polygon
			(pts
				(arc
					(start 108.787438 -275.8948)
					(mid 108.134658 -275.8948)
					(end 108.787438 -275.8948)
				)
			)
		)
	)
	(zone
		(layers "B.Cu" "In11.Cu" "In13.Cu" "In15.Cu")
		(hatch none 0.5)
		(connect_pads
			(clearance 0)
		)
		(min_thickness 0.25)
		(keepout
			(tracks not_allowed)
			(vias allowed)
			(pads allowed)
			(copperpour not_allowed)
			(footprints allowed)
		)
		(placement
			(enabled no)
			(sheetname "")
		)
		(fill yes
			(thermal_gap 0.5)
			(thermal_bridge_width 0.5)
			(island_removal_mode 0)
		)
		(polygon
			(pts
				(arc
					(start 127.113538 -271.825212)
					(mid 126.460758 -271.825212)
					(end 127.113538 -271.825212)
				)
			)
		)
	)
	(zone
		(layers "B.Cu" "In11.Cu" "In13.Cu" "In15.Cu")
		(hatch none 0.5)
		(connect_pads
			(clearance 0)
		)
		(min_thickness 0.25)
		(keepout
			(tracks not_allowed)
			(vias allowed)
			(pads allowed)
			(copperpour not_allowed)
			(footprints allowed)
		)
		(placement
			(enabled no)
			(sheetname "")
		)
		(fill yes
			(thermal_gap 0.5)
			(thermal_bridge_width 0.5)
			(island_removal_mode 0)
		)
		(polygon
			(pts
				(arc
					(start 128.993138 -276.708616)
					(mid 128.340358 -276.708616)
					(end 128.993138 -276.708616)
				)
			)
		)
	)
	(zone
		(layers "B.Cu" "In11.Cu" "In13.Cu" "In15.Cu")
		(hatch none 0.5)
		(connect_pads
			(clearance 0)
		)
		(min_thickness 0.25)
		(keepout
			(tracks not_allowed)
			(vias allowed)
			(pads allowed)
			(copperpour not_allowed)
			(footprints allowed)
		)
		(placement
			(enabled no)
			(sheetname "")
		)
		(fill yes
			(thermal_gap 0.5)
			(thermal_bridge_width 0.5)
			(island_removal_mode 0)
		)
		(polygon
			(pts
				(arc
					(start 342.989916 -214.622634)
					(mid 342.337136 -214.622634)
					(end 342.989916 -214.622634)
				)
			)
		)
	)
	(zone
		(layers "B.Cu" "In11.Cu" "In13.Cu" "In15.Cu")
		(hatch none 0.5)
		(connect_pads
			(clearance 0)
		)
		(min_thickness 0.25)
		(keepout
			(tracks not_allowed)
			(vias allowed)
			(pads allowed)
			(copperpour not_allowed)
			(footprints allowed)
		)
		(placement
			(enabled no)
			(sheetname "")
		)
		(fill yes
			(thermal_gap 0.5)
			(thermal_bridge_width 0.5)
			(island_removal_mode 0)
		)
		(polygon
			(pts
				(arc
					(start 21.215604 -313.766708)
					(mid 20.562824 -313.766708)
					(end 21.215604 -313.766708)
				)
			)
		)
	)
	(zone
		(layers "B.Cu" "In11.Cu" "In13.Cu" "In15.Cu")
		(hatch none 0.5)
		(connect_pads
			(clearance 0)
		)
		(min_thickness 0.25)
		(keepout
			(tracks not_allowed)
			(vias allowed)
			(pads allowed)
			(copperpour not_allowed)
			(footprints allowed)
		)
		(placement
			(enabled no)
			(sheetname "")
		)
		(fill yes
			(thermal_gap 0.5)
			(thermal_bridge_width 0.5)
			(island_removal_mode 0)
		)
		(polygon
			(pts
				(arc
					(start 128.522984 -271.011396)
					(mid 127.870204 -271.011396)
					(end 128.522984 -271.011396)
				)
			)
		)
	)
	(zone
		(layers "B.Cu" "In11.Cu" "In13.Cu" "In15.Cu")
		(hatch none 0.5)
		(connect_pads
			(clearance 0)
		)
		(min_thickness 0.25)
		(keepout
			(tracks not_allowed)
			(vias allowed)
			(pads allowed)
			(copperpour not_allowed)
			(footprints allowed)
		)
		(placement
			(enabled no)
			(sheetname "")
		)
		(fill yes
			(thermal_gap 0.5)
			(thermal_bridge_width 0.5)
			(island_removal_mode 0)
		)
		(polygon
			(pts
				(arc
					(start 370.474494 -176.019968)
					(mid 369.770914 -176.019968)
					(end 370.474494 -176.019968)
				)
			)
		)
	)
	(zone
		(layers "B.Cu" "In11.Cu" "In13.Cu" "In15.Cu")
		(hatch none 0.5)
		(connect_pads
			(clearance 0)
		)
		(min_thickness 0.25)
		(keepout
			(tracks not_allowed)
			(vias allowed)
			(pads allowed)
			(copperpour not_allowed)
			(footprints allowed)
		)
		(placement
			(enabled no)
			(sheetname "")
		)
		(fill yes
			(thermal_gap 0.5)
			(thermal_bridge_width 0.5)
			(island_removal_mode 0)
		)
		(polygon
			(pts
				(arc
					(start 377.873006 -278.336502)
					(mid 377.220226 -278.336502)
					(end 377.873006 -278.336502)
				)
			)
		)
	)
	(zone
		(layers "B.Cu" "In11.Cu" "In13.Cu" "In15.Cu")
		(hatch none 0.5)
		(connect_pads
			(clearance 0)
		)
		(min_thickness 0.25)
		(keepout
			(tracks not_allowed)
			(vias allowed)
			(pads allowed)
			(copperpour not_allowed)
			(footprints allowed)
		)
		(placement
			(enabled no)
			(sheetname "")
		)
		(fill yes
			(thermal_gap 0.5)
			(thermal_bridge_width 0.5)
			(island_removal_mode 0)
		)
		(polygon
			(pts
				(arc
					(start 345.809824 -242.294918)
					(mid 345.157044 -242.294918)
					(end 345.809824 -242.294918)
				)
			)
		)
	)
	(zone
		(layers "B.Cu" "In11.Cu" "In13.Cu" "In15.Cu")
		(hatch none 0.5)
		(connect_pads
			(clearance 0)
		)
		(min_thickness 0.25)
		(keepout
			(tracks not_allowed)
			(vias allowed)
			(pads allowed)
			(copperpour not_allowed)
			(footprints allowed)
		)
		(placement
			(enabled no)
			(sheetname "")
		)
		(fill yes
			(thermal_gap 0.5)
			(thermal_bridge_width 0.5)
			(island_removal_mode 0)
		)
		(polygon
			(pts
				(arc
					(start 388.154926 -437.889904)
					(mid 387.345174 -437.889904)
					(end 388.154926 -437.889904)
				)
			)
		)
	)
	(zone
		(layers "B.Cu" "In11.Cu" "In13.Cu" "In15.Cu")
		(hatch none 0.5)
		(connect_pads
			(clearance 0)
		)
		(min_thickness 0.25)
		(keepout
			(tracks not_allowed)
			(vias allowed)
			(pads allowed)
			(copperpour not_allowed)
			(footprints allowed)
		)
		(placement
			(enabled no)
			(sheetname "")
		)
		(fill yes
			(thermal_gap 0.5)
			(thermal_bridge_width 0.5)
			(island_removal_mode 0)
		)
		(polygon
			(pts
				(arc
					(start 84.05495 -426.089826)
					(mid 83.245198 -426.089826)
					(end 84.05495 -426.089826)
				)
			)
		)
	)
	(zone
		(layers "B.Cu" "In11.Cu" "In13.Cu" "In15.Cu")
		(hatch none 0.5)
		(connect_pads
			(clearance 0)
		)
		(min_thickness 0.25)
		(keepout
			(tracks not_allowed)
			(vias allowed)
			(pads allowed)
			(copperpour not_allowed)
			(footprints allowed)
		)
		(placement
			(enabled no)
			(sheetname "")
		)
		(fill yes
			(thermal_gap 0.5)
			(thermal_bridge_width 0.5)
			(island_removal_mode 0)
		)
		(polygon
			(pts
				(arc
					(start 90.363548 -410.030168)
					(mid 89.659968 -410.030168)
					(end 90.363548 -410.030168)
				)
			)
		)
	)
	(zone
		(layers "B.Cu" "In11.Cu" "In13.Cu" "In15.Cu")
		(hatch none 0.5)
		(connect_pads
			(clearance 0)
		)
		(min_thickness 0.25)
		(keepout
			(tracks not_allowed)
			(vias allowed)
			(pads allowed)
			(copperpour not_allowed)
			(footprints allowed)
		)
		(placement
			(enabled no)
			(sheetname "")
		)
		(fill yes
			(thermal_gap 0.5)
			(thermal_bridge_width 0.5)
			(island_removal_mode 0)
		)
		(polygon
			(pts
				(arc
					(start 284.243272 -218.566746)
					(mid 283.590492 -218.566746)
					(end 284.243272 -218.566746)
				)
			)
		)
	)
	(zone
		(layers "B.Cu" "In11.Cu" "In13.Cu" "In15.Cu")
		(hatch none 0.5)
		(connect_pads
			(clearance 0)
		)
		(min_thickness 0.25)
		(keepout
			(tracks not_allowed)
			(vias allowed)
			(pads allowed)
			(copperpour not_allowed)
			(footprints allowed)
		)
		(placement
			(enabled no)
			(sheetname "")
		)
		(fill yes
			(thermal_gap 0.5)
			(thermal_bridge_width 0.5)
			(island_removal_mode 0)
		)
		(polygon
			(pts
				(arc
					(start 350.441514 -170.080432)
					(mid 349.737934 -170.080432)
					(end 350.441514 -170.080432)
				)
			)
		)
	)
	(zone
		(layers "B.Cu" "In11.Cu" "In13.Cu" "In15.Cu")
		(hatch none 0.5)
		(connect_pads
			(clearance 0)
		)
		(min_thickness 0.25)
		(keepout
			(tracks not_allowed)
			(vias allowed)
			(pads allowed)
			(copperpour not_allowed)
			(footprints allowed)
		)
		(placement
			(enabled no)
			(sheetname "")
		)
		(fill yes
			(thermal_gap 0.5)
			(thermal_bridge_width 0.5)
			(island_removal_mode 0)
		)
		(polygon
			(pts
				(arc
					(start 360.37647 -228.45903)
					(mid 359.72369 -228.45903)
					(end 360.37647 -228.45903)
				)
			)
		)
	)
	(zone
		(layers "B.Cu" "In11.Cu" "In13.Cu" "In15.Cu")
		(hatch none 0.5)
		(connect_pads
			(clearance 0)
		)
		(min_thickness 0.25)
		(keepout
			(tracks not_allowed)
			(vias allowed)
			(pads allowed)
			(copperpour not_allowed)
			(footprints allowed)
		)
		(placement
			(enabled no)
			(sheetname "")
		)
		(fill yes
			(thermal_gap 0.5)
			(thermal_bridge_width 0.5)
			(island_removal_mode 0)
		)
		(polygon
			(pts
				(arc
					(start 210.841336 -243.216684)
					(mid 210.188556 -243.216684)
					(end 210.841336 -243.216684)
				)
			)
		)
	)
	(zone
		(layers "B.Cu" "In11.Cu" "In13.Cu" "In15.Cu")
		(hatch none 0.5)
		(connect_pads
			(clearance 0)
		)
		(min_thickness 0.25)
		(keepout
			(tracks not_allowed)
			(vias allowed)
			(pads allowed)
			(copperpour not_allowed)
			(footprints allowed)
		)
		(placement
			(enabled no)
			(sheetname "")
		)
		(fill yes
			(thermal_gap 0.5)
			(thermal_bridge_width 0.5)
			(island_removal_mode 0)
		)
		(polygon
			(pts
				(arc
					(start 159.51835 -47.943008)
					(mid 158.81477 -47.943008)
					(end 159.51835 -47.943008)
				)
			)
		)
	)
	(zone
		(layers "B.Cu" "In11.Cu" "In13.Cu" "In15.Cu")
		(hatch none 0.5)
		(connect_pads
			(clearance 0)
		)
		(min_thickness 0.25)
		(keepout
			(tracks not_allowed)
			(vias allowed)
			(pads allowed)
			(copperpour not_allowed)
			(footprints allowed)
		)
		(placement
			(enabled no)
			(sheetname "")
		)
		(fill yes
			(thermal_gap 0.5)
			(thermal_bridge_width 0.5)
			(island_removal_mode 0)
		)
		(polygon
			(pts
				(arc
					(start 207.397604 -210.916774)
					(mid 206.744824 -210.916774)
					(end 207.397604 -210.916774)
				)
			)
		)
	)
	(zone
		(layers "B.Cu" "In11.Cu" "In13.Cu" "In15.Cu")
		(hatch none 0.5)
		(connect_pads
			(clearance 0)
		)
		(min_thickness 0.25)
		(keepout
			(tracks not_allowed)
			(vias allowed)
			(pads allowed)
			(copperpour not_allowed)
			(footprints allowed)
		)
		(placement
			(enabled no)
			(sheetname "")
		)
		(fill yes
			(thermal_gap 0.5)
			(thermal_bridge_width 0.5)
			(island_removal_mode 0)
		)
		(polygon
			(pts
				(arc
					(start 343.100406 -270.19758)
					(mid 342.447626 -270.19758)
					(end 343.100406 -270.19758)
				)
			)
		)
	)
	(zone
		(layers "B.Cu" "In11.Cu" "In13.Cu" "In15.Cu")
		(hatch none 0.5)
		(connect_pads
			(clearance 0)
		)
		(min_thickness 0.25)
		(keepout
			(tracks not_allowed)
			(vias allowed)
			(pads allowed)
			(copperpour not_allowed)
			(footprints allowed)
		)
		(placement
			(enabled no)
			(sheetname "")
		)
		(fill yes
			(thermal_gap 0.5)
			(thermal_bridge_width 0.5)
			(island_removal_mode 0)
		)
		(polygon
			(pts
				(arc
					(start 192.310004 -225.36658)
					(mid 191.657224 -225.36658)
					(end 192.310004 -225.36658)
				)
			)
		)
	)
	(zone
		(layers "B.Cu" "In11.Cu" "In13.Cu" "In15.Cu")
		(hatch none 0.5)
		(connect_pads
			(clearance 0)
		)
		(min_thickness 0.25)
		(keepout
			(tracks not_allowed)
			(vias allowed)
			(pads allowed)
			(copperpour not_allowed)
			(footprints allowed)
		)
		(placement
			(enabled no)
			(sheetname "")
		)
		(fill yes
			(thermal_gap 0.5)
			(thermal_bridge_width 0.5)
			(island_removal_mode 0)
		)
		(polygon
			(pts
				(arc
					(start 315.054996 -434.48986)
					(mid 314.245244 -434.48986)
					(end 315.054996 -434.48986)
				)
			)
		)
	)
	(zone
		(layers "B.Cu" "In11.Cu" "In13.Cu" "In15.Cu")
		(hatch none 0.5)
		(connect_pads
			(clearance 0)
		)
		(min_thickness 0.25)
		(keepout
			(tracks not_allowed)
			(vias allowed)
			(pads allowed)
			(copperpour not_allowed)
			(footprints allowed)
		)
		(placement
			(enabled no)
			(sheetname "")
		)
		(fill yes
			(thermal_gap 0.5)
			(thermal_bridge_width 0.5)
			(island_removal_mode 0)
		)
		(polygon
			(pts
				(arc
					(start 440.250072 -203.266802)
					(mid 439.597292 -203.266802)
					(end 440.250072 -203.266802)
				)
			)
		)
	)
	(zone
		(layers "B.Cu" "In11.Cu" "In13.Cu" "In15.Cu")
		(hatch none 0.5)
		(connect_pads
			(clearance 0)
		)
		(min_thickness 0.25)
		(keepout
			(tracks not_allowed)
			(vias allowed)
			(pads allowed)
			(copperpour not_allowed)
			(footprints allowed)
		)
		(placement
			(enabled no)
			(sheetname "")
		)
		(fill yes
			(thermal_gap 0.5)
			(thermal_bridge_width 0.5)
			(island_removal_mode 0)
		)
		(polygon
			(pts
				(arc
					(start 284.243272 -279.766776)
					(mid 283.590492 -279.766776)
					(end 284.243272 -279.766776)
				)
			)
		)
	)
	(zone
		(layers "B.Cu" "In11.Cu" "In13.Cu" "In15.Cu")
		(hatch none 0.5)
		(connect_pads
			(clearance 0)
		)
		(min_thickness 0.25)
		(keepout
			(tracks not_allowed)
			(vias allowed)
			(pads allowed)
			(copperpour not_allowed)
			(footprints allowed)
		)
		(placement
			(enabled no)
			(sheetname "")
		)
		(fill yes
			(thermal_gap 0.5)
			(thermal_bridge_width 0.5)
			(island_removal_mode 0)
		)
		(polygon
			(pts
				(arc
					(start 138.281156 -216.25052)
					(mid 137.628376 -216.25052)
					(end 138.281156 -216.25052)
				)
			)
		)
	)
	(zone
		(layers "B.Cu" "In11.Cu" "In13.Cu" "In15.Cu")
		(hatch none 0.5)
		(connect_pads
			(clearance 0)
		)
		(min_thickness 0.25)
		(keepout
			(tracks not_allowed)
			(vias allowed)
			(pads allowed)
			(copperpour not_allowed)
			(footprints allowed)
		)
		(placement
			(enabled no)
			(sheetname "")
		)
		(fill yes
			(thermal_gap 0.5)
			(thermal_bridge_width 0.5)
			(island_removal_mode 0)
		)
		(polygon
			(pts
				(arc
					(start 21.215604 -204.96657)
					(mid 20.562824 -204.96657)
					(end 21.215604 -204.96657)
				)
			)
		)
	)
	(zone
		(layers "B.Cu" "In11.Cu" "In13.Cu" "In15.Cu")
		(hatch none 0.5)
		(connect_pads
			(clearance 0)
		)
		(min_thickness 0.25)
		(keepout
			(tracks not_allowed)
			(vias allowed)
			(pads allowed)
			(copperpour not_allowed)
			(footprints allowed)
		)
		(placement
			(enabled no)
			(sheetname "")
		)
		(fill yes
			(thermal_gap 0.5)
			(thermal_bridge_width 0.5)
			(island_removal_mode 0)
		)
		(polygon
			(pts
				(arc
					(start 353.302062 -168.302432)
					(mid 352.598482 -168.302432)
					(end 353.302062 -168.302432)
				)
			)
		)
	)
	(zone
		(layers "B.Cu" "In11.Cu" "In13.Cu" "In15.Cu")
		(hatch none 0.5)
		(connect_pads
			(clearance 0)
		)
		(min_thickness 0.25)
		(keepout
			(tracks not_allowed)
			(vias allowed)
			(pads allowed)
			(copperpour not_allowed)
			(footprints allowed)
		)
		(placement
			(enabled no)
			(sheetname "")
		)
		(fill yes
			(thermal_gap 0.5)
			(thermal_bridge_width 0.5)
			(island_removal_mode 0)
		)
		(polygon
			(pts
				(arc
					(start 344.980006 -270.19758)
					(mid 344.327226 -270.19758)
					(end 344.980006 -270.19758)
				)
			)
		)
	)
	(zone
		(layers "B.Cu" "In11.Cu" "In13.Cu" "In15.Cu")
		(hatch none 0.5)
		(connect_pads
			(clearance 0)
		)
		(min_thickness 0.25)
		(keepout
			(tracks not_allowed)
			(vias allowed)
			(pads allowed)
			(copperpour not_allowed)
			(footprints allowed)
		)
		(placement
			(enabled no)
			(sheetname "")
		)
		(fill yes
			(thermal_gap 0.5)
			(thermal_bridge_width 0.5)
			(island_removal_mode 0)
		)
		(polygon
			(pts
				(arc
					(start 322.711318 -403.883876)
					(mid 322.007738 -403.883876)
					(end 322.711318 -403.883876)
				)
			)
		)
	)
	(zone
		(layers "B.Cu" "In11.Cu" "In13.Cu" "In15.Cu")
		(hatch none 0.5)
		(connect_pads
			(clearance 0)
		)
		(min_thickness 0.25)
		(keepout
			(tracks not_allowed)
			(vias allowed)
			(pads allowed)
			(copperpour not_allowed)
			(footprints allowed)
		)
		(placement
			(enabled no)
			(sheetname "")
		)
		(fill yes
			(thermal_gap 0.5)
			(thermal_bridge_width 0.5)
			(island_removal_mode 0)
		)
		(polygon
			(pts
				(arc
					(start 382.101852 -254.733552)
					(mid 381.449072 -254.733552)
					(end 382.101852 -254.733552)
				)
			)
		)
	)
	(zone
		(layers "B.Cu" "In11.Cu" "In13.Cu" "In15.Cu")
		(hatch none 0.5)
		(connect_pads
			(clearance 0)
		)
		(min_thickness 0.25)
		(keepout
			(tracks not_allowed)
			(vias allowed)
			(pads allowed)
			(copperpour not_allowed)
			(footprints allowed)
		)
		(placement
			(enabled no)
			(sheetname "")
		)
		(fill yes
			(thermal_gap 0.5)
			(thermal_bridge_width 0.5)
			(island_removal_mode 0)
		)
		(polygon
			(pts
				(arc
					(start 287.687004 -243.216684)
					(mid 287.034224 -243.216684)
					(end 287.687004 -243.216684)
				)
			)
		)
	)
	(zone
		(layers "B.Cu" "In11.Cu" "In13.Cu" "In15.Cu")
		(hatch none 0.5)
		(connect_pads
			(clearance 0)
		)
		(min_thickness 0.25)
		(keepout
			(tracks not_allowed)
			(vias allowed)
			(pads allowed)
			(copperpour not_allowed)
			(footprints allowed)
		)
		(placement
			(enabled no)
			(sheetname "")
		)
		(fill yes
			(thermal_gap 0.5)
			(thermal_bridge_width 0.5)
			(island_removal_mode 0)
		)
		(polygon
			(pts
				(arc
					(start 407.154888 -429.689768)
					(mid 406.345136 -429.689768)
					(end 407.154888 -429.689768)
				)
			)
		)
	)
	(zone
		(layers "B.Cu" "In11.Cu" "In13.Cu" "In15.Cu")
		(hatch none 0.5)
		(connect_pads
			(clearance 0)
		)
		(min_thickness 0.25)
		(keepout
			(tracks not_allowed)
			(vias allowed)
			(pads allowed)
			(copperpour not_allowed)
			(footprints allowed)
		)
		(placement
			(enabled no)
			(sheetname "")
		)
		(fill yes
			(thermal_gap 0.5)
			(thermal_bridge_width 0.5)
			(island_removal_mode 0)
		)
		(polygon
			(pts
				(arc
					(start 88.581484 -283.219906)
					(mid 87.928704 -283.219906)
					(end 88.581484 -283.219906)
				)
			)
		)
	)
	(zone
		(layers "B.Cu" "In11.Cu" "In13.Cu" "In15.Cu")
		(hatch none 0.5)
		(connect_pads
			(clearance 0)
		)
		(min_thickness 0.25)
		(keepout
			(tracks not_allowed)
			(vias allowed)
			(pads allowed)
			(copperpour not_allowed)
			(footprints allowed)
		)
		(placement
			(enabled no)
			(sheetname "")
		)
		(fill yes
			(thermal_gap 0.5)
			(thermal_bridge_width 0.5)
			(island_removal_mode 0)
		)
		(polygon
			(pts
				(arc
					(start 17.115536 -312.066686)
					(mid 16.462756 -312.066686)
					(end 17.115536 -312.066686)
				)
			)
		)
	)
	(zone
		(layers "B.Cu" "In11.Cu" "In13.Cu" "In15.Cu")
		(hatch none 0.5)
		(connect_pads
			(clearance 0)
		)
		(min_thickness 0.25)
		(keepout
			(tracks not_allowed)
			(vias allowed)
			(pads allowed)
			(copperpour not_allowed)
			(footprints allowed)
		)
		(placement
			(enabled no)
			(sheetname "")
		)
		(fill yes
			(thermal_gap 0.5)
			(thermal_bridge_width 0.5)
			(island_removal_mode 0)
		)
		(polygon
			(pts
				(arc
					(start 336.054954 -427.289976)
					(mid 335.245202 -427.289976)
					(end 336.054954 -427.289976)
				)
			)
		)
	)
	(zone
		(layers "B.Cu" "In11.Cu" "In13.Cu" "In15.Cu")
		(hatch none 0.5)
		(connect_pads
			(clearance 0)
		)
		(min_thickness 0.25)
		(keepout
			(tracks not_allowed)
			(vias allowed)
			(pads allowed)
			(copperpour not_allowed)
			(footprints allowed)
		)
		(placement
			(enabled no)
			(sheetname "")
		)
		(fill yes
			(thermal_gap 0.5)
			(thermal_bridge_width 0.5)
			(island_removal_mode 0)
		)
		(polygon
			(pts
				(arc
					(start 107.737656 -213.732618)
					(mid 107.084876 -213.732618)
					(end 107.737656 -213.732618)
				)
			)
		)
	)
	(zone
		(layers "B.Cu" "In11.Cu" "In13.Cu" "In15.Cu")
		(hatch none 0.5)
		(connect_pads
			(clearance 0)
		)
		(min_thickness 0.25)
		(keepout
			(tracks not_allowed)
			(vias allowed)
			(pads allowed)
			(copperpour not_allowed)
			(footprints allowed)
		)
		(placement
			(enabled no)
			(sheetname "")
		)
		(fill yes
			(thermal_gap 0.5)
			(thermal_bridge_width 0.5)
			(island_removal_mode 0)
		)
		(polygon
			(pts
				(arc
					(start 284.243272 -231.316784)
					(mid 283.590492 -231.316784)
					(end 284.243272 -231.316784)
				)
			)
		)
	)
	(zone
		(layers "B.Cu" "In11.Cu" "In13.Cu" "In15.Cu")
		(hatch none 0.5)
		(connect_pads
			(clearance 0)
		)
		(min_thickness 0.25)
		(keepout
			(tracks not_allowed)
			(vias allowed)
			(pads allowed)
			(copperpour not_allowed)
			(footprints allowed)
		)
		(placement
			(enabled no)
			(sheetname "")
		)
		(fill yes
			(thermal_gap 0.5)
			(thermal_bridge_width 0.5)
			(island_removal_mode 0)
		)
		(polygon
			(pts
				(arc
					(start 334.054958 -435.489858)
					(mid 333.245206 -435.489858)
					(end 334.054958 -435.489858)
				)
			)
		)
	)
	(zone
		(layers "B.Cu" "In11.Cu" "In13.Cu" "In15.Cu")
		(hatch none 0.5)
		(connect_pads
			(clearance 0)
		)
		(min_thickness 0.25)
		(keepout
			(tracks not_allowed)
			(vias allowed)
			(pads allowed)
			(copperpour not_allowed)
			(footprints allowed)
		)
		(placement
			(enabled no)
			(sheetname "")
		)
		(fill yes
			(thermal_gap 0.5)
			(thermal_bridge_width 0.5)
			(island_removal_mode 0)
		)
		(polygon
			(pts
				(arc
					(start 127.473202 -238.225584)
					(mid 126.820422 -238.225584)
					(end 127.473202 -238.225584)
				)
			)
		)
	)
	(zone
		(layers "B.Cu" "In11.Cu" "In13.Cu" "In15.Cu")
		(hatch none 0.5)
		(connect_pads
			(clearance 0)
		)
		(min_thickness 0.25)
		(keepout
			(tracks not_allowed)
			(vias allowed)
			(pads allowed)
			(copperpour not_allowed)
			(footprints allowed)
		)
		(placement
			(enabled no)
			(sheetname "")
		)
		(fill yes
			(thermal_gap 0.5)
			(thermal_bridge_width 0.5)
			(island_removal_mode 0)
		)
		(polygon
			(pts
				(arc
					(start 332.764638 -403.883876)
					(mid 332.061058 -403.883876)
					(end 332.764638 -403.883876)
				)
			)
		)
	)
	(zone
		(layers "B.Cu" "In11.Cu" "In13.Cu" "In15.Cu")
		(hatch none 0.5)
		(connect_pads
			(clearance 0)
		)
		(min_thickness 0.25)
		(keepout
			(tracks not_allowed)
			(vias allowed)
			(pads allowed)
			(copperpour not_allowed)
			(footprints allowed)
		)
		(placement
			(enabled no)
			(sheetname "")
		)
		(fill yes
			(thermal_gap 0.5)
			(thermal_bridge_width 0.5)
			(island_removal_mode 0)
		)
		(polygon
			(pts
				(arc
					(start 342.054942 -434.289962)
					(mid 341.24519 -434.289962)
					(end 342.054942 -434.289962)
				)
			)
		)
	)
	(zone
		(layers "B.Cu" "In11.Cu" "In13.Cu" "In15.Cu")
		(hatch none 0.5)
		(connect_pads
			(clearance 0)
		)
		(min_thickness 0.25)
		(keepout
			(tracks not_allowed)
			(vias allowed)
			(pads allowed)
			(copperpour not_allowed)
			(footprints allowed)
		)
		(placement
			(enabled no)
			(sheetname "")
		)
		(fill yes
			(thermal_gap 0.5)
			(thermal_bridge_width 0.5)
			(island_removal_mode 0)
		)
		(polygon
			(pts
				(arc
					(start 351.004378 -66.963544)
					(mid 350.300798 -66.963544)
					(end 351.004378 -66.963544)
				)
			)
		)
	)
	(zone
		(layers "B.Cu" "In11.Cu" "In13.Cu" "In15.Cu")
		(hatch none 0.5)
		(connect_pads
			(clearance 0)
		)
		(min_thickness 0.25)
		(keepout
			(tracks not_allowed)
			(vias allowed)
			(pads allowed)
			(copperpour not_allowed)
			(footprints allowed)
		)
		(placement
			(enabled no)
			(sheetname "")
		)
		(fill yes
			(thermal_gap 0.5)
			(thermal_bridge_width 0.5)
			(island_removal_mode 0)
		)
		(polygon
			(pts
				(arc
					(start 32.203136 -306.96662)
					(mid 31.550356 -306.96662)
					(end 32.203136 -306.96662)
				)
			)
		)
	)
	(zone
		(layers "B.Cu" "In11.Cu" "In13.Cu" "In15.Cu")
		(hatch none 0.5)
		(connect_pads
			(clearance 0)
		)
		(min_thickness 0.25)
		(keepout
			(tracks not_allowed)
			(vias allowed)
			(pads allowed)
			(copperpour not_allowed)
			(footprints allowed)
		)
		(placement
			(enabled no)
			(sheetname "")
		)
		(fill yes
			(thermal_gap 0.5)
			(thermal_bridge_width 0.5)
			(island_removal_mode 0)
		)
		(polygon
			(pts
				(arc
					(start 188.209936 -302.716692)
					(mid 187.557156 -302.716692)
					(end 188.209936 -302.716692)
				)
			)
		)
	)
	(zone
		(layers "B.Cu" "In11.Cu" "In13.Cu" "In15.Cu")
		(hatch none 0.5)
		(connect_pads
			(clearance 0)
		)
		(min_thickness 0.25)
		(keepout
			(tracks not_allowed)
			(vias allowed)
			(pads allowed)
			(copperpour not_allowed)
			(footprints allowed)
		)
		(placement
			(enabled no)
			(sheetname "")
		)
		(fill yes
			(thermal_gap 0.5)
			(thermal_bridge_width 0.5)
			(island_removal_mode 0)
		)
		(polygon
			(pts
				(arc
					(start 280.143204 -216.866724)
					(mid 279.490424 -216.866724)
					(end 280.143204 -216.866724)
				)
			)
		)
	)
	(zone
		(layers "B.Cu" "In11.Cu" "In13.Cu" "In15.Cu")
		(hatch none 0.5)
		(connect_pads
			(clearance 0)
		)
		(min_thickness 0.25)
		(keepout
			(tracks not_allowed)
			(vias allowed)
			(pads allowed)
			(copperpour not_allowed)
			(footprints allowed)
		)
		(placement
			(enabled no)
			(sheetname "")
		)
		(fill yes
			(thermal_gap 0.5)
			(thermal_bridge_width 0.5)
			(island_removal_mode 0)
		)
		(polygon
			(pts
				(arc
					(start 188.209936 -200.716642)
					(mid 187.557156 -200.716642)
					(end 188.209936 -200.716642)
				)
			)
		)
	)
	(zone
		(layers "B.Cu" "In11.Cu" "In13.Cu" "In15.Cu")
		(hatch none 0.5)
		(connect_pads
			(clearance 0)
		)
		(min_thickness 0.25)
		(keepout
			(tracks not_allowed)
			(vias allowed)
			(pads allowed)
			(copperpour not_allowed)
			(footprints allowed)
		)
		(placement
			(enabled no)
			(sheetname "")
		)
		(fill yes
			(thermal_gap 0.5)
			(thermal_bridge_width 0.5)
			(island_removal_mode 0)
		)
		(polygon
			(pts
				(arc
					(start 136.154922 -437.889904)
					(mid 135.34517 -437.889904)
					(end 136.154922 -437.889904)
				)
			)
		)
	)
	(zone
		(layers "B.Cu" "In11.Cu" "In13.Cu" "In15.Cu")
		(hatch none 0.5)
		(connect_pads
			(clearance 0)
		)
		(min_thickness 0.25)
		(keepout
			(tracks not_allowed)
			(vias allowed)
			(pads allowed)
			(copperpour not_allowed)
			(footprints allowed)
		)
		(placement
			(enabled no)
			(sheetname "")
		)
		(fill yes
			(thermal_gap 0.5)
			(thermal_bridge_width 0.5)
			(island_removal_mode 0)
		)
		(polygon
			(pts
				(arc
					(start 96.929956 -235.783882)
					(mid 96.277176 -235.783882)
					(end 96.929956 -235.783882)
				)
			)
		)
	)
	(zone
		(layers "B.Cu" "In11.Cu" "In13.Cu" "In15.Cu")
		(hatch none 0.5)
		(connect_pads
			(clearance 0)
		)
		(min_thickness 0.25)
		(keepout
			(tracks not_allowed)
			(vias allowed)
			(pads allowed)
			(copperpour not_allowed)
			(footprints allowed)
		)
		(placement
			(enabled no)
			(sheetname "")
		)
		(fill yes
			(thermal_gap 0.5)
			(thermal_bridge_width 0.5)
			(island_removal_mode 0)
		)
		(polygon
			(pts
				(arc
					(start 386.22097 -219.506038)
					(mid 385.56819 -219.506038)
					(end 386.22097 -219.506038)
				)
			)
		)
	)
	(zone
		(layers "B.Cu" "In11.Cu" "In13.Cu" "In15.Cu")
		(hatch none 0.5)
		(connect_pads
			(clearance 0)
		)
		(min_thickness 0.25)
		(keepout
			(tracks not_allowed)
			(vias allowed)
			(pads allowed)
			(copperpour not_allowed)
			(footprints allowed)
		)
		(placement
			(enabled no)
			(sheetname "")
		)
		(fill yes
			(thermal_gap 0.5)
			(thermal_bridge_width 0.5)
			(island_removal_mode 0)
		)
		(polygon
			(pts
				(arc
					(start 451.237604 -314.616592)
					(mid 450.584824 -314.616592)
					(end 451.237604 -314.616592)
				)
			)
		)
	)
	(zone
		(layers "B.Cu" "In11.Cu" "In13.Cu" "In15.Cu")
		(hatch none 0.5)
		(connect_pads
			(clearance 0)
		)
		(min_thickness 0.25)
		(keepout
			(tracks not_allowed)
			(vias allowed)
			(pads allowed)
			(copperpour not_allowed)
			(footprints allowed)
		)
		(placement
			(enabled no)
			(sheetname "")
		)
		(fill yes
			(thermal_gap 0.5)
			(thermal_bridge_width 0.5)
			(island_removal_mode 0)
		)
		(polygon
			(pts
				(arc
					(start 377.29287 -230.086662)
					(mid 376.64009 -230.086662)
					(end 377.29287 -230.086662)
				)
			)
		)
	)
	(zone
		(layers "B.Cu" "In11.Cu" "In13.Cu" "In15.Cu")
		(hatch none 0.5)
		(connect_pads
			(clearance 0)
		)
		(min_thickness 0.25)
		(keepout
			(tracks not_allowed)
			(vias allowed)
			(pads allowed)
			(copperpour not_allowed)
			(footprints allowed)
		)
		(placement
			(enabled no)
			(sheetname "")
		)
		(fill yes
			(thermal_gap 0.5)
			(thermal_bridge_width 0.5)
			(island_removal_mode 0)
		)
		(polygon
			(pts
				(arc
					(start 354.226114 -172.518832)
					(mid 353.522534 -172.518832)
					(end 354.226114 -172.518832)
				)
			)
		)
	)
	(zone
		(layers "B.Cu" "In11.Cu" "In13.Cu" "In15.Cu")
		(hatch none 0.5)
		(connect_pads
			(clearance 0)
		)
		(min_thickness 0.25)
		(keepout
			(tracks not_allowed)
			(vias allowed)
			(pads allowed)
			(copperpour not_allowed)
			(footprints allowed)
		)
		(placement
			(enabled no)
			(sheetname "")
		)
		(fill yes
			(thermal_gap 0.5)
			(thermal_bridge_width 0.5)
			(island_removal_mode 0)
		)
		(polygon
			(pts
				(arc
					(start 128.883156 -240.667286)
					(mid 128.230376 -240.667286)
					(end 128.883156 -240.667286)
				)
			)
		)
	)
	(zone
		(layers "B.Cu" "In11.Cu" "In13.Cu" "In15.Cu")
		(hatch none 0.5)
		(connect_pads
			(clearance 0)
		)
		(min_thickness 0.25)
		(keepout
			(tracks not_allowed)
			(vias allowed)
			(pads allowed)
			(copperpour not_allowed)
			(footprints allowed)
		)
		(placement
			(enabled no)
			(sheetname "")
		)
		(fill yes
			(thermal_gap 0.5)
			(thermal_bridge_width 0.5)
			(island_removal_mode 0)
		)
		(polygon
			(pts
				(arc
					(start 59.731148 -410.030168)
					(mid 59.027568 -410.030168)
					(end 59.731148 -410.030168)
				)
			)
		)
	)
	(zone
		(layers "B.Cu" "In11.Cu" "In13.Cu" "In15.Cu")
		(hatch none 0.5)
		(connect_pads
			(clearance 0)
		)
		(min_thickness 0.25)
		(keepout
			(tracks not_allowed)
			(vias allowed)
			(pads allowed)
			(copperpour not_allowed)
			(footprints allowed)
		)
		(placement
			(enabled no)
			(sheetname "")
		)
		(fill yes
			(thermal_gap 0.5)
			(thermal_bridge_width 0.5)
			(island_removal_mode 0)
		)
		(polygon
			(pts
				(arc
					(start 128.522984 -267.755878)
					(mid 127.870204 -267.755878)
					(end 128.522984 -267.755878)
				)
			)
		)
	)
	(zone
		(layers "B.Cu" "In11.Cu" "In13.Cu" "In15.Cu")
		(hatch none 0.5)
		(connect_pads
			(clearance 0)
		)
		(min_thickness 0.25)
		(keepout
			(tracks not_allowed)
			(vias allowed)
			(pads allowed)
			(copperpour not_allowed)
			(footprints allowed)
		)
		(placement
			(enabled no)
			(sheetname "")
		)
		(fill yes
			(thermal_gap 0.5)
			(thermal_bridge_width 0.5)
			(island_removal_mode 0)
		)
		(polygon
			(pts
				(arc
					(start 135.101584 -254.733552)
					(mid 134.448804 -254.733552)
					(end 135.101584 -254.733552)
				)
			)
		)
	)
	(zone
		(layers "B.Cu" "In11.Cu" "In13.Cu" "In15.Cu")
		(hatch none 0.5)
		(connect_pads
			(clearance 0)
		)
		(min_thickness 0.25)
		(keepout
			(tracks not_allowed)
			(vias allowed)
			(pads allowed)
			(copperpour not_allowed)
			(footprints allowed)
		)
		(placement
			(enabled no)
			(sheetname "")
		)
		(fill yes
			(thermal_gap 0.5)
			(thermal_bridge_width 0.5)
			(island_removal_mode 0)
		)
		(polygon
			(pts
				(arc
					(start 378.342652 -254.733552)
					(mid 377.689872 -254.733552)
					(end 378.342652 -254.733552)
				)
			)
		)
	)
	(zone
		(layers "B.Cu" "In11.Cu" "In13.Cu" "In15.Cu")
		(hatch none 0.5)
		(connect_pads
			(clearance 0)
		)
		(min_thickness 0.25)
		(keepout
			(tracks not_allowed)
			(vias allowed)
			(pads allowed)
			(copperpour not_allowed)
			(footprints allowed)
		)
		(placement
			(enabled no)
			(sheetname "")
		)
		(fill yes
			(thermal_gap 0.5)
			(thermal_bridge_width 0.5)
			(island_removal_mode 0)
		)
		(polygon
			(pts
				(arc
					(start 192.310004 -221.96679)
					(mid 191.657224 -221.96679)
					(end 192.310004 -221.96679)
				)
			)
		)
	)
	(zone
		(layers "B.Cu" "In11.Cu" "In13.Cu" "In15.Cu")
		(hatch none 0.5)
		(connect_pads
			(clearance 0)
		)
		(min_thickness 0.25)
		(keepout
			(tracks not_allowed)
			(vias allowed)
			(pads allowed)
			(copperpour not_allowed)
			(footprints allowed)
		)
		(placement
			(enabled no)
			(sheetname "")
		)
		(fill yes
			(thermal_gap 0.5)
			(thermal_bridge_width 0.5)
			(island_removal_mode 0)
		)
		(polygon
			(pts
				(arc
					(start 345.33967 -231.714548)
					(mid 344.68689 -231.714548)
					(end 345.33967 -231.714548)
				)
			)
		)
	)
	(zone
		(layers "B.Cu" "In11.Cu" "In13.Cu" "In15.Cu")
		(hatch none 0.5)
		(connect_pads
			(clearance 0)
		)
		(min_thickness 0.25)
		(keepout
			(tracks not_allowed)
			(vias allowed)
			(pads allowed)
			(copperpour not_allowed)
			(footprints allowed)
		)
		(placement
			(enabled no)
			(sheetname "")
		)
		(fill yes
			(thermal_gap 0.5)
			(thermal_bridge_width 0.5)
			(island_removal_mode 0)
		)
		(polygon
			(pts
				(arc
					(start 392.36396 -410.030168)
					(mid 391.66038 -410.030168)
					(end 392.36396 -410.030168)
				)
			)
		)
	)
	(zone
		(layers "B.Cu" "In11.Cu" "In13.Cu" "In15.Cu")
		(hatch none 0.5)
		(connect_pads
			(clearance 0)
		)
		(min_thickness 0.25)
		(keepout
			(tracks not_allowed)
			(vias allowed)
			(pads allowed)
			(copperpour not_allowed)
			(footprints allowed)
		)
		(placement
			(enabled no)
			(sheetname "")
		)
		(fill yes
			(thermal_gap 0.5)
			(thermal_bridge_width 0.5)
			(island_removal_mode 0)
		)
		(polygon
			(pts
				(arc
					(start 284.243272 -272.116804)
					(mid 283.590492 -272.116804)
					(end 284.243272 -272.116804)
				)
			)
		)
	)
	(zone
		(layers "B.Cu" "In11.Cu" "In13.Cu" "In15.Cu")
		(hatch none 0.5)
		(connect_pads
			(clearance 0)
		)
		(min_thickness 0.25)
		(keepout
			(tracks not_allowed)
			(vias allowed)
			(pads allowed)
			(copperpour not_allowed)
			(footprints allowed)
		)
		(placement
			(enabled no)
			(sheetname "")
		)
		(fill yes
			(thermal_gap 0.5)
			(thermal_bridge_width 0.5)
			(island_removal_mode 0)
		)
		(polygon
			(pts
				(arc
					(start 87.300308 -410.030168)
					(mid 86.596728 -410.030168)
					(end 87.300308 -410.030168)
				)
			)
		)
	)
	(zone
		(layers "B.Cu" "In11.Cu" "In13.Cu" "In15.Cu")
		(hatch none 0.5)
		(connect_pads
			(clearance 0)
		)
		(min_thickness 0.25)
		(keepout
			(tracks not_allowed)
			(vias allowed)
			(pads allowed)
			(copperpour not_allowed)
			(footprints allowed)
		)
		(placement
			(enabled no)
			(sheetname "")
		)
		(fill yes
			(thermal_gap 0.5)
			(thermal_bridge_width 0.5)
			(island_removal_mode 0)
		)
		(polygon
			(pts
				(arc
					(start 117.135656 -213.732618)
					(mid 116.482876 -213.732618)
					(end 117.135656 -213.732618)
				)
			)
		)
	)
	(zone
		(layers "B.Cu" "In11.Cu" "In13.Cu" "In15.Cu")
		(hatch none 0.5)
		(connect_pads
			(clearance 0)
		)
		(min_thickness 0.25)
		(keepout
			(tracks not_allowed)
			(vias allowed)
			(pads allowed)
			(copperpour not_allowed)
			(footprints allowed)
		)
		(placement
			(enabled no)
			(sheetname "")
		)
		(fill yes
			(thermal_gap 0.5)
			(thermal_bridge_width 0.5)
			(island_removal_mode 0)
		)
		(polygon
			(pts
				(arc
					(start 366.01527 -228.45903)
					(mid 365.36249 -228.45903)
					(end 366.01527 -228.45903)
				)
			)
		)
	)
	(zone
		(layers "B.Cu" "In11.Cu" "In13.Cu" "In15.Cu")
		(hatch none 0.5)
		(connect_pads
			(clearance 0)
		)
		(min_thickness 0.25)
		(keepout
			(tracks not_allowed)
			(vias allowed)
			(pads allowed)
			(copperpour not_allowed)
			(footprints allowed)
		)
		(placement
			(enabled no)
			(sheetname "")
		)
		(fill yes
			(thermal_gap 0.5)
			(thermal_bridge_width 0.5)
			(island_removal_mode 0)
		)
		(polygon
			(pts
				(arc
					(start 396.15491 -439.0898)
					(mid 395.345158 -439.0898)
					(end 396.15491 -439.0898)
				)
			)
		)
	)
	(zone
		(layers "B.Cu" "In11.Cu" "In13.Cu" "In15.Cu")
		(hatch none 0.5)
		(connect_pads
			(clearance 0)
		)
		(min_thickness 0.25)
		(keepout
			(tracks not_allowed)
			(vias allowed)
			(pads allowed)
			(copperpour not_allowed)
			(footprints allowed)
		)
		(placement
			(enabled no)
			(sheetname "")
		)
		(fill yes
			(thermal_gap 0.5)
			(thermal_bridge_width 0.5)
			(island_removal_mode 0)
		)
		(polygon
			(pts
				(arc
					(start 203.297536 -312.066686)
					(mid 202.644756 -312.066686)
					(end 203.297536 -312.066686)
				)
			)
		)
	)
	(zone
		(layers "B.Cu" "In11.Cu" "In13.Cu" "In15.Cu")
		(hatch none 0.5)
		(connect_pads
			(clearance 0)
		)
		(min_thickness 0.25)
		(keepout
			(tracks not_allowed)
			(vias allowed)
			(pads allowed)
			(copperpour not_allowed)
			(footprints allowed)
		)
		(placement
			(enabled no)
			(sheetname "")
		)
		(fill yes
			(thermal_gap 0.5)
			(thermal_bridge_width 0.5)
			(island_removal_mode 0)
		)
		(polygon
			(pts
				(arc
					(start 364.13567 -228.45903)
					(mid 363.48289 -228.45903)
					(end 364.13567 -228.45903)
				)
			)
		)
	)
	(zone
		(layers "B.Cu" "In11.Cu" "In13.Cu" "In15.Cu")
		(hatch none 0.5)
		(connect_pads
			(clearance 0)
		)
		(min_thickness 0.25)
		(keepout
			(tracks not_allowed)
			(vias allowed)
			(pads allowed)
			(copperpour not_allowed)
			(footprints allowed)
		)
		(placement
			(enabled no)
			(sheetname "")
		)
		(fill yes
			(thermal_gap 0.5)
			(thermal_bridge_width 0.5)
			(island_removal_mode 0)
		)
		(polygon
			(pts
				(arc
					(start 340.054946 -433.289964)
					(mid 339.245194 -433.289964)
					(end 340.054946 -433.289964)
				)
			)
		)
	)
	(zone
		(layers "B.Cu" "In11.Cu" "In13.Cu" "In15.Cu")
		(hatch none 0.5)
		(connect_pads
			(clearance 0)
		)
		(min_thickness 0.25)
		(keepout
			(tracks not_allowed)
			(vias allowed)
			(pads allowed)
			(copperpour not_allowed)
			(footprints allowed)
		)
		(placement
			(enabled no)
			(sheetname "")
		)
		(fill yes
			(thermal_gap 0.5)
			(thermal_bridge_width 0.5)
			(island_removal_mode 0)
		)
		(polygon
			(pts
				(arc
					(start 344.980006 -271.825212)
					(mid 344.327226 -271.825212)
					(end 344.980006 -271.825212)
				)
			)
		)
	)
	(zone
		(layers "B.Cu" "In11.Cu" "In13.Cu" "In15.Cu")
		(hatch none 0.5)
		(connect_pads
			(clearance 0)
		)
		(min_thickness 0.25)
		(keepout
			(tracks not_allowed)
			(vias allowed)
			(pads allowed)
			(copperpour not_allowed)
			(footprints allowed)
		)
		(placement
			(enabled no)
			(sheetname "")
		)
		(fill yes
			(thermal_gap 0.5)
			(thermal_bridge_width 0.5)
			(island_removal_mode 0)
		)
		(polygon
			(pts
				(arc
					(start 401.1549 -437.889904)
					(mid 400.345148 -437.889904)
					(end 401.1549 -437.889904)
				)
			)
		)
	)
	(zone
		(layers "B.Cu" "In11.Cu" "In13.Cu" "In15.Cu")
		(hatch none 0.5)
		(connect_pads
			(clearance 0)
		)
		(min_thickness 0.25)
		(keepout
			(tracks not_allowed)
			(vias allowed)
			(pads allowed)
			(copperpour not_allowed)
			(footprints allowed)
		)
		(placement
			(enabled no)
			(sheetname "")
		)
		(fill yes
			(thermal_gap 0.5)
			(thermal_bridge_width 0.5)
			(island_removal_mode 0)
		)
		(polygon
			(pts
				(arc
					(start 362.25607 -228.45903)
					(mid 361.60329 -228.45903)
					(end 362.25607 -228.45903)
				)
			)
		)
	)
	(zone
		(layers "B.Cu" "In11.Cu" "In13.Cu" "In15.Cu")
		(hatch none 0.5)
		(connect_pads
			(clearance 0)
		)
		(min_thickness 0.25)
		(keepout
			(tracks not_allowed)
			(vias allowed)
			(pads allowed)
			(copperpour not_allowed)
			(footprints allowed)
		)
		(placement
			(enabled no)
			(sheetname "")
		)
		(fill yes
			(thermal_gap 0.5)
			(thermal_bridge_width 0.5)
			(island_removal_mode 0)
		)
		(polygon
			(pts
				(arc
					(start 311.321958 -403.883876)
					(mid 310.618378 -403.883876)
					(end 311.321958 -403.883876)
				)
			)
		)
	)
	(zone
		(layers "B.Cu" "In11.Cu" "In13.Cu" "In15.Cu")
		(hatch none 0.5)
		(connect_pads
			(clearance 0)
		)
		(min_thickness 0.25)
		(keepout
			(tracks not_allowed)
			(vias allowed)
			(pads allowed)
			(copperpour not_allowed)
			(footprints allowed)
		)
		(placement
			(enabled no)
			(sheetname "")
		)
		(fill yes
			(thermal_gap 0.5)
			(thermal_bridge_width 0.5)
			(island_removal_mode 0)
		)
		(polygon
			(pts
				(arc
					(start 349.517462 -167.565832)
					(mid 348.813882 -167.565832)
					(end 349.517462 -167.565832)
				)
			)
		)
	)
	(zone
		(layers "B.Cu" "In11.Cu" "In13.Cu" "In15.Cu")
		(hatch none 0.5)
		(connect_pads
			(clearance 0)
		)
		(min_thickness 0.25)
		(keepout
			(tracks not_allowed)
			(vias allowed)
			(pads allowed)
			(copperpour not_allowed)
			(footprints allowed)
		)
		(placement
			(enabled no)
			(sheetname "")
		)
		(fill yes
			(thermal_gap 0.5)
			(thermal_bridge_width 0.5)
			(island_removal_mode 0)
		)
		(polygon
			(pts
				(arc
					(start 32.203136 -215.166702)
					(mid 31.550356 -215.166702)
					(end 32.203136 -215.166702)
				)
			)
		)
	)
	(zone
		(layers "B.Cu" "In11.Cu" "In13.Cu" "In15.Cu")
		(hatch none 0.5)
		(connect_pads
			(clearance 0)
		)
		(min_thickness 0.25)
		(keepout
			(tracks not_allowed)
			(vias allowed)
			(pads allowed)
			(copperpour not_allowed)
			(footprints allowed)
		)
		(placement
			(enabled no)
			(sheetname "")
		)
		(fill yes
			(thermal_gap 0.5)
			(thermal_bridge_width 0.5)
			(island_removal_mode 0)
		)
		(polygon
			(pts
				(arc
					(start 63.054992 -426.089826)
					(mid 62.24524 -426.089826)
					(end 63.054992 -426.089826)
				)
			)
		)
	)
	(zone
		(layers "B.Cu" "In11.Cu" "In13.Cu" "In15.Cu")
		(hatch none 0.5)
		(connect_pads
			(clearance 0)
		)
		(min_thickness 0.25)
		(keepout
			(tracks not_allowed)
			(vias allowed)
			(pads allowed)
			(copperpour not_allowed)
			(footprints allowed)
		)
		(placement
			(enabled no)
			(sheetname "")
		)
		(fill yes
			(thermal_gap 0.5)
			(thermal_bridge_width 0.5)
			(island_removal_mode 0)
		)
		(polygon
			(pts
				(arc
					(start 455.337672 -212.616796)
					(mid 454.684892 -212.616796)
					(end 455.337672 -212.616796)
				)
			)
		)
	)
	(zone
		(layers "B.Cu" "In11.Cu" "In13.Cu" "In15.Cu")
		(hatch none 0.5)
		(connect_pads
			(clearance 0)
		)
		(min_thickness 0.25)
		(keepout
			(tracks not_allowed)
			(vias allowed)
			(pads allowed)
			(copperpour not_allowed)
			(footprints allowed)
		)
		(placement
			(enabled no)
			(sheetname "")
		)
		(fill yes
			(thermal_gap 0.5)
			(thermal_bridge_width 0.5)
			(island_removal_mode 0)
		)
		(polygon
			(pts
				(arc
					(start 89.991438 -282.405836)
					(mid 89.338658 -282.405836)
					(end 89.991438 -282.405836)
				)
			)
		)
	)
	(zone
		(layers "B.Cu" "In11.Cu" "In13.Cu" "In15.Cu")
		(hatch none 0.5)
		(connect_pads
			(clearance 0)
		)
		(min_thickness 0.25)
		(keepout
			(tracks not_allowed)
			(vias allowed)
			(pads allowed)
			(copperpour not_allowed)
			(footprints allowed)
		)
		(placement
			(enabled no)
			(sheetname "")
		)
		(fill yes
			(thermal_gap 0.5)
			(thermal_bridge_width 0.5)
			(island_removal_mode 0)
		)
		(polygon
			(pts
				(arc
					(start 265.055604 -312.066686)
					(mid 264.402824 -312.066686)
					(end 265.055604 -312.066686)
				)
			)
		)
	)
	(zone
		(layers "B.Cu" "In11.Cu" "In13.Cu" "In15.Cu")
		(hatch none 0.5)
		(connect_pads
			(clearance 0)
		)
		(min_thickness 0.25)
		(keepout
			(tracks not_allowed)
			(vias allowed)
			(pads allowed)
			(copperpour not_allowed)
			(footprints allowed)
		)
		(placement
			(enabled no)
			(sheetname "")
		)
		(fill yes
			(thermal_gap 0.5)
			(thermal_bridge_width 0.5)
			(island_removal_mode 0)
		)
		(polygon
			(pts
				(arc
					(start 352.498406 -281.59202)
					(mid 351.845626 -281.59202)
					(end 352.498406 -281.59202)
				)
			)
		)
	)
	(zone
		(layers "B.Cu" "In11.Cu" "In13.Cu" "In15.Cu")
		(hatch none 0.5)
		(connect_pads
			(clearance 0)
		)
		(min_thickness 0.25)
		(keepout
			(tracks not_allowed)
			(vias allowed)
			(pads allowed)
			(copperpour not_allowed)
			(footprints allowed)
		)
		(placement
			(enabled no)
			(sheetname "")
		)
		(fill yes
			(thermal_gap 0.5)
			(thermal_bridge_width 0.5)
			(island_removal_mode 0)
		)
		(polygon
			(pts
				(arc
					(start 354.226114 -179.884832)
					(mid 353.522534 -179.884832)
					(end 354.226114 -179.884832)
				)
			)
		)
	)
	(zone
		(layers "B.Cu" "In11.Cu" "In13.Cu" "In15.Cu")
		(hatch none 0.5)
		(connect_pads
			(clearance 0)
		)
		(min_thickness 0.25)
		(keepout
			(tracks not_allowed)
			(vias allowed)
			(pads allowed)
			(copperpour not_allowed)
			(footprints allowed)
		)
		(placement
			(enabled no)
			(sheetname "")
		)
		(fill yes
			(thermal_gap 0.5)
			(thermal_bridge_width 0.5)
			(island_removal_mode 0)
		)
		(polygon
			(pts
				(arc
					(start 269.155672 -313.766708)
					(mid 268.502892 -313.766708)
					(end 269.155672 -313.766708)
				)
			)
		)
	)
	(zone
		(layers "B.Cu" "In11.Cu" "In13.Cu" "In15.Cu")
		(hatch none 0.5)
		(connect_pads
			(clearance 0)
		)
		(min_thickness 0.25)
		(keepout
			(tracks not_allowed)
			(vias allowed)
			(pads allowed)
			(copperpour not_allowed)
			(footprints allowed)
		)
		(placement
			(enabled no)
			(sheetname "")
		)
		(fill yes
			(thermal_gap 0.5)
			(thermal_bridge_width 0.5)
			(island_removal_mode 0)
		)
		(polygon
			(pts
				(arc
					(start 207.397604 -311.216802)
					(mid 206.744824 -311.216802)
					(end 207.397604 -311.216802)
				)
			)
		)
	)
	(zone
		(layers "B.Cu" "In11.Cu" "In13.Cu" "In15.Cu")
		(hatch none 0.5)
		(connect_pads
			(clearance 0)
		)
		(min_thickness 0.25)
		(keepout
			(tracks not_allowed)
			(vias allowed)
			(pads allowed)
			(copperpour not_allowed)
			(footprints allowed)
		)
		(placement
			(enabled no)
			(sheetname "")
		)
		(fill yes
			(thermal_gap 0.5)
			(thermal_bridge_width 0.5)
			(island_removal_mode 0)
		)
		(polygon
			(pts
				(arc
					(start 265.055604 -210.066636)
					(mid 264.402824 -210.066636)
					(end 265.055604 -210.066636)
				)
			)
		)
	)
	(zone
		(layers "B.Cu" "In11.Cu" "In13.Cu" "In15.Cu")
		(hatch none 0.5)
		(connect_pads
			(clearance 0)
		)
		(min_thickness 0.25)
		(keepout
			(tracks not_allowed)
			(vias allowed)
			(pads allowed)
			(copperpour not_allowed)
			(footprints allowed)
		)
		(placement
			(enabled no)
			(sheetname "")
		)
		(fill yes
			(thermal_gap 0.5)
			(thermal_bridge_width 0.5)
			(island_removal_mode 0)
		)
		(polygon
			(pts
				(arc
					(start 97.869756 -232.528364)
					(mid 97.216976 -232.528364)
					(end 97.869756 -232.528364)
				)
			)
		)
	)
	(zone
		(layers "B.Cu" "In11.Cu" "In13.Cu" "In15.Cu")
		(hatch none 0.5)
		(connect_pads
			(clearance 0)
		)
		(min_thickness 0.25)
		(keepout
			(tracks not_allowed)
			(vias allowed)
			(pads allowed)
			(copperpour not_allowed)
			(footprints allowed)
		)
		(placement
			(enabled no)
			(sheetname "")
		)
		(fill yes
			(thermal_gap 0.5)
			(thermal_bridge_width 0.5)
			(island_removal_mode 0)
		)
		(polygon
			(pts
				(arc
					(start 17.115536 -211.766658)
					(mid 16.462756 -211.766658)
					(end 17.115536 -211.766658)
				)
			)
		)
	)
	(zone
		(layers "B.Cu" "In11.Cu" "In13.Cu" "In15.Cu")
		(hatch none 0.5)
		(connect_pads
			(clearance 0)
		)
		(min_thickness 0.25)
		(keepout
			(tracks not_allowed)
			(vias allowed)
			(pads allowed)
			(copperpour not_allowed)
			(footprints allowed)
		)
		(placement
			(enabled no)
			(sheetname "")
		)
		(fill yes
			(thermal_gap 0.5)
			(thermal_bridge_width 0.5)
			(island_removal_mode 0)
		)
		(polygon
			(pts
				(arc
					(start 78.054962 -435.489858)
					(mid 77.24521 -435.489858)
					(end 78.054962 -435.489858)
				)
			)
		)
	)
	(zone
		(layers "B.Cu" "In11.Cu" "In13.Cu" "In15.Cu")
		(hatch none 0.5)
		(connect_pads
			(clearance 0)
		)
		(min_thickness 0.25)
		(keepout
			(tracks not_allowed)
			(vias allowed)
			(pads allowed)
			(copperpour not_allowed)
			(footprints allowed)
		)
		(placement
			(enabled no)
			(sheetname "")
		)
		(fill yes
			(thermal_gap 0.5)
			(thermal_bridge_width 0.5)
			(island_removal_mode 0)
		)
		(polygon
			(pts
				(arc
					(start 371.398546 -181.582568)
					(mid 370.694966 -181.582568)
					(end 371.398546 -181.582568)
				)
			)
		)
	)
	(zone
		(layers "B.Cu" "In11.Cu" "In13.Cu" "In15.Cu")
		(hatch none 0.5)
		(connect_pads
			(clearance 0)
		)
		(min_thickness 0.25)
		(keepout
			(tracks not_allowed)
			(vias allowed)
			(pads allowed)
			(copperpour not_allowed)
			(footprints allowed)
		)
		(placement
			(enabled no)
			(sheetname "")
		)
		(fill yes
			(thermal_gap 0.5)
			(thermal_bridge_width 0.5)
			(island_removal_mode 0)
		)
		(polygon
			(pts
				(arc
					(start 97.039938 -279.964134)
					(mid 96.387158 -279.964134)
					(end 97.039938 -279.964134)
				)
			)
		)
	)
	(zone
		(layers "B.Cu" "In11.Cu" "In13.Cu" "In15.Cu")
		(hatch none 0.5)
		(connect_pads
			(clearance 0)
		)
		(min_thickness 0.25)
		(keepout
			(tracks not_allowed)
			(vias allowed)
			(pads allowed)
			(copperpour not_allowed)
			(footprints allowed)
		)
		(placement
			(enabled no)
			(sheetname "")
		)
		(fill yes
			(thermal_gap 0.5)
			(thermal_bridge_width 0.5)
			(island_removal_mode 0)
		)
		(polygon
			(pts
				(arc
					(start 118.075202 -215.436704)
					(mid 117.422422 -215.436704)
					(end 118.075202 -215.436704)
				)
			)
		)
	)
	(zone
		(layers "B.Cu" "In11.Cu" "In13.Cu" "In15.Cu")
		(hatch none 0.5)
		(connect_pads
			(clearance 0)
		)
		(min_thickness 0.25)
		(keepout
			(tracks not_allowed)
			(vias allowed)
			(pads allowed)
			(copperpour not_allowed)
			(footprints allowed)
		)
		(placement
			(enabled no)
			(sheetname "")
		)
		(fill yes
			(thermal_gap 0.5)
			(thermal_bridge_width 0.5)
			(island_removal_mode 0)
		)
		(polygon
			(pts
				(arc
					(start 284.243272 -195.616576)
					(mid 283.590492 -195.616576)
					(end 284.243272 -195.616576)
				)
			)
		)
	)
	(zone
		(layers "B.Cu" "In11.Cu" "In13.Cu" "In15.Cu")
		(hatch none 0.5)
		(connect_pads
			(clearance 0)
		)
		(min_thickness 0.25)
		(keepout
			(tracks not_allowed)
			(vias allowed)
			(pads allowed)
			(copperpour not_allowed)
			(footprints allowed)
		)
		(placement
			(enabled no)
			(sheetname "")
		)
		(fill yes
			(thermal_gap 0.5)
			(thermal_bridge_width 0.5)
			(island_removal_mode 0)
		)
		(polygon
			(pts
				(arc
					(start 390.154922 -436.889906)
					(mid 389.34517 -436.889906)
					(end 390.154922 -436.889906)
				)
			)
		)
	)
	(zone
		(layers "B.Cu" "In11.Cu" "In13.Cu" "In15.Cu")
		(hatch none 0.5)
		(connect_pads
			(clearance 0)
		)
		(min_thickness 0.25)
		(keepout
			(tracks not_allowed)
			(vias allowed)
			(pads allowed)
			(copperpour not_allowed)
			(footprints allowed)
		)
		(placement
			(enabled no)
			(sheetname "")
		)
		(fill yes
			(thermal_gap 0.5)
			(thermal_bridge_width 0.5)
			(island_removal_mode 0)
		)
		(polygon
			(pts
				(arc
					(start 344.040206 -258.80314)
					(mid 343.387426 -258.80314)
					(end 344.040206 -258.80314)
				)
			)
		)
	)
	(zone
		(layers "B.Cu" "In11.Cu" "In13.Cu" "In15.Cu")
		(hatch none 0.5)
		(connect_pads
			(clearance 0)
		)
		(min_thickness 0.25)
		(keepout
			(tracks not_allowed)
			(vias allowed)
			(pads allowed)
			(copperpour not_allowed)
			(footprints allowed)
		)
		(placement
			(enabled no)
			(sheetname "")
		)
		(fill yes
			(thermal_gap 0.5)
			(thermal_bridge_width 0.5)
			(island_removal_mode 0)
		)
		(polygon
			(pts
				(arc
					(start 358.539034 -50.207672)
					(mid 357.835454 -50.207672)
					(end 358.539034 -50.207672)
				)
			)
		)
	)
	(zone
		(layers "B.Cu" "In11.Cu" "In13.Cu" "In15.Cu")
		(hatch none 0.5)
		(connect_pads
			(clearance 0)
		)
		(min_thickness 0.25)
		(keepout
			(tracks not_allowed)
			(vias allowed)
			(pads allowed)
			(copperpour not_allowed)
			(footprints allowed)
		)
		(placement
			(enabled no)
			(sheetname "")
		)
		(fill yes
			(thermal_gap 0.5)
			(thermal_bridge_width 0.5)
			(island_removal_mode 0)
		)
		(polygon
			(pts
				(arc
					(start 358.027224 -227.64496)
					(mid 357.374444 -227.64496)
					(end 358.027224 -227.64496)
				)
			)
		)
	)
	(zone
		(layers "B.Cu" "In11.Cu" "In13.Cu" "In15.Cu")
		(hatch none 0.5)
		(connect_pads
			(clearance 0)
		)
		(min_thickness 0.25)
		(keepout
			(tracks not_allowed)
			(vias allowed)
			(pads allowed)
			(copperpour not_allowed)
			(footprints allowed)
		)
		(placement
			(enabled no)
			(sheetname "")
		)
		(fill yes
			(thermal_gap 0.5)
			(thermal_bridge_width 0.5)
			(island_removal_mode 0)
		)
		(polygon
			(pts
				(arc
					(start 317.054992 -427.089824)
					(mid 316.24524 -427.089824)
					(end 317.054992 -427.089824)
				)
			)
		)
	)
	(zone
		(layers "B.Cu" "In11.Cu" "In13.Cu" "In15.Cu")
		(hatch none 0.5)
		(connect_pads
			(clearance 0)
		)
		(min_thickness 0.25)
		(keepout
			(tracks not_allowed)
			(vias allowed)
			(pads allowed)
			(copperpour not_allowed)
			(footprints allowed)
		)
		(placement
			(enabled no)
			(sheetname "")
		)
		(fill yes
			(thermal_gap 0.5)
			(thermal_bridge_width 0.5)
			(island_removal_mode 0)
		)
		(polygon
			(pts
				(arc
					(start 138.28141 -217.878406)
					(mid 137.62863 -217.878406)
					(end 138.28141 -217.878406)
				)
			)
		)
	)
	(zone
		(layers "B.Cu" "In11.Cu" "In13.Cu" "In15.Cu")
		(hatch none 0.5)
		(connect_pads
			(clearance 0)
		)
		(min_thickness 0.25)
		(keepout
			(tracks not_allowed)
			(vias allowed)
			(pads allowed)
			(copperpour not_allowed)
			(footprints allowed)
		)
		(placement
			(enabled no)
			(sheetname "")
		)
		(fill yes
			(thermal_gap 0.5)
			(thermal_bridge_width 0.5)
			(island_removal_mode 0)
		)
		(polygon
			(pts
				(arc
					(start 210.841336 -244.066568)
					(mid 210.188556 -244.066568)
					(end 210.841336 -244.066568)
				)
			)
		)
	)
	(zone
		(layers "B.Cu" "In11.Cu" "In13.Cu" "In15.Cu")
		(hatch none 0.5)
		(connect_pads
			(clearance 0)
		)
		(min_thickness 0.25)
		(keepout
			(tracks not_allowed)
			(vias allowed)
			(pads allowed)
			(copperpour not_allowed)
			(footprints allowed)
		)
		(placement
			(enabled no)
			(sheetname "")
		)
		(fill yes
			(thermal_gap 0.5)
			(thermal_bridge_width 0.5)
			(island_removal_mode 0)
		)
		(polygon
			(pts
				(arc
					(start 95.990156 -229.272846)
					(mid 95.337376 -229.272846)
					(end 95.990156 -229.272846)
				)
			)
		)
	)
	(zone
		(layers "B.Cu" "In11.Cu" "In13.Cu" "In15.Cu")
		(hatch none 0.5)
		(connect_pads
			(clearance 0)
		)
		(min_thickness 0.25)
		(keepout
			(tracks not_allowed)
			(vias allowed)
			(pads allowed)
			(copperpour not_allowed)
			(footprints allowed)
		)
		(placement
			(enabled no)
			(sheetname "")
		)
		(fill yes
			(thermal_gap 0.5)
			(thermal_bridge_width 0.5)
			(island_removal_mode 0)
		)
		(polygon
			(pts
				(arc
					(start 347.799406 -283.219906)
					(mid 347.146626 -283.219906)
					(end 347.799406 -283.219906)
				)
			)
		)
	)
	(zone
		(layers "B.Cu" "In11.Cu" "In13.Cu" "In15.Cu")
		(hatch none 0.5)
		(connect_pads
			(clearance 0)
		)
		(min_thickness 0.25)
		(keepout
			(tracks not_allowed)
			(vias allowed)
			(pads allowed)
			(copperpour not_allowed)
			(footprints allowed)
		)
		(placement
			(enabled no)
			(sheetname "")
		)
		(fill yes
			(thermal_gap 0.5)
			(thermal_bridge_width 0.5)
			(island_removal_mode 0)
		)
		(polygon
			(pts
				(arc
					(start 129.462784 -262.872474)
					(mid 128.810004 -262.872474)
					(end 129.462784 -262.872474)
				)
			)
		)
	)
	(zone
		(layers "B.Cu" "In11.Cu" "In13.Cu" "In15.Cu")
		(hatch none 0.5)
		(connect_pads
			(clearance 0)
		)
		(min_thickness 0.25)
		(keepout
			(tracks not_allowed)
			(vias allowed)
			(pads allowed)
			(copperpour not_allowed)
			(footprints allowed)
		)
		(placement
			(enabled no)
			(sheetname "")
		)
		(fill yes
			(thermal_gap 0.5)
			(thermal_bridge_width 0.5)
			(island_removal_mode 0)
		)
		(polygon
			(pts
				(arc
					(start 370.474494 -166.875968)
					(mid 369.770914 -166.875968)
					(end 370.474494 -166.875968)
				)
			)
		)
	)
	(zone
		(layers "B.Cu" "In11.Cu" "In13.Cu" "In15.Cu")
		(hatch none 0.5)
		(connect_pads
			(clearance 0)
		)
		(min_thickness 0.25)
		(keepout
			(tracks not_allowed)
			(vias allowed)
			(pads allowed)
			(copperpour not_allowed)
			(footprints allowed)
		)
		(placement
			(enabled no)
			(sheetname "")
		)
		(fill yes
			(thermal_gap 0.5)
			(thermal_bridge_width 0.5)
			(island_removal_mode 0)
		)
		(polygon
			(pts
				(arc
					(start 451.237604 -312.066686)
					(mid 450.584824 -312.066686)
					(end 451.237604 -312.066686)
				)
			)
		)
	)
	(zone
		(layers "B.Cu" "In11.Cu" "In13.Cu" "In15.Cu")
		(hatch none 0.5)
		(connect_pads
			(clearance 0)
		)
		(min_thickness 0.25)
		(keepout
			(tracks not_allowed)
			(vias allowed)
			(pads allowed)
			(copperpour not_allowed)
			(footprints allowed)
		)
		(placement
			(enabled no)
			(sheetname "")
		)
		(fill yes
			(thermal_gap 0.5)
			(thermal_bridge_width 0.5)
			(island_removal_mode 0)
		)
		(polygon
			(pts
				(arc
					(start 436.150004 -280.61666)
					(mid 435.497224 -280.61666)
					(end 436.150004 -280.61666)
				)
			)
		)
	)
	(zone
		(layers "B.Cu" "In11.Cu" "In13.Cu" "In15.Cu")
		(hatch none 0.5)
		(connect_pads
			(clearance 0)
		)
		(min_thickness 0.25)
		(keepout
			(tracks not_allowed)
			(vias allowed)
			(pads allowed)
			(copperpour not_allowed)
			(footprints allowed)
		)
		(placement
			(enabled no)
			(sheetname "")
		)
		(fill yes
			(thermal_gap 0.5)
			(thermal_bridge_width 0.5)
			(island_removal_mode 0)
		)
		(polygon
			(pts
				(arc
					(start 376.35307 -233.34218)
					(mid 375.70029 -233.34218)
					(end 376.35307 -233.34218)
				)
			)
		)
	)
	(zone
		(layers "B.Cu" "In11.Cu" "In13.Cu" "In15.Cu")
		(hatch none 0.5)
		(connect_pads
			(clearance 0)
		)
		(min_thickness 0.25)
		(keepout
			(tracks not_allowed)
			(vias allowed)
			(pads allowed)
			(copperpour not_allowed)
			(footprints allowed)
		)
		(placement
			(enabled no)
			(sheetname "")
		)
		(fill yes
			(thermal_gap 0.5)
			(thermal_bridge_width 0.5)
			(island_removal_mode 0)
		)
		(polygon
			(pts
				(arc
					(start 168.665144 -410.030168)
					(mid 167.961564 -410.030168)
					(end 168.665144 -410.030168)
				)
			)
		)
	)
	(zone
		(layers "B.Cu" "In11.Cu" "In13.Cu" "In15.Cu")
		(hatch none 0.5)
		(connect_pads
			(clearance 0)
		)
		(min_thickness 0.25)
		(keepout
			(tracks not_allowed)
			(vias allowed)
			(pads allowed)
			(copperpour not_allowed)
			(footprints allowed)
		)
		(placement
			(enabled no)
			(sheetname "")
		)
		(fill yes
			(thermal_gap 0.5)
			(thermal_bridge_width 0.5)
			(island_removal_mode 0)
		)
		(polygon
			(pts
				(arc
					(start 73.054972 -428.28972)
					(mid 72.24522 -428.28972)
					(end 73.054972 -428.28972)
				)
			)
		)
	)
	(zone
		(layers "B.Cu" "In11.Cu" "In13.Cu" "In15.Cu")
		(hatch none 0.5)
		(connect_pads
			(clearance 0)
		)
		(min_thickness 0.25)
		(keepout
			(tracks not_allowed)
			(vias allowed)
			(pads allowed)
			(copperpour not_allowed)
			(footprints allowed)
		)
		(placement
			(enabled no)
			(sheetname "")
		)
		(fill yes
			(thermal_gap 0.5)
			(thermal_bridge_width 0.5)
			(island_removal_mode 0)
		)
		(polygon
			(pts
				(arc
					(start 140.154914 -431.889916)
					(mid 139.345162 -431.889916)
					(end 140.154914 -431.889916)
				)
			)
		)
	)
	(zone
		(layers "B.Cu" "In11.Cu" "In13.Cu" "In15.Cu")
		(hatch none 0.5)
		(connect_pads
			(clearance 0)
		)
		(min_thickness 0.25)
		(keepout
			(tracks not_allowed)
			(vias allowed)
			(pads allowed)
			(copperpour not_allowed)
			(footprints allowed)
		)
		(placement
			(enabled no)
			(sheetname "")
		)
		(fill yes
			(thermal_gap 0.5)
			(thermal_bridge_width 0.5)
			(island_removal_mode 0)
		)
		(polygon
			(pts
				(arc
					(start 386.221224 -217.878406)
					(mid 385.568444 -217.878406)
					(end 386.221224 -217.878406)
				)
			)
		)
	)
	(zone
		(layers "B.Cu" "In11.Cu" "In13.Cu" "In15.Cu")
		(hatch none 0.5)
		(connect_pads
			(clearance 0)
		)
		(min_thickness 0.25)
		(keepout
			(tracks not_allowed)
			(vias allowed)
			(pads allowed)
			(copperpour not_allowed)
			(footprints allowed)
		)
		(placement
			(enabled no)
			(sheetname "")
		)
		(fill yes
			(thermal_gap 0.5)
			(thermal_bridge_width 0.5)
			(island_removal_mode 0)
		)
		(polygon
			(pts
				(arc
					(start 97.399602 -233.34218)
					(mid 96.746822 -233.34218)
					(end 97.399602 -233.34218)
				)
			)
		)
	)
	(zone
		(layers "B.Cu" "In11.Cu" "In13.Cu" "In15.Cu")
		(hatch none 0.5)
		(connect_pads
			(clearance 0)
		)
		(min_thickness 0.25)
		(keepout
			(tracks not_allowed)
			(vias allowed)
			(pads allowed)
			(copperpour not_allowed)
			(footprints allowed)
		)
		(placement
			(enabled no)
			(sheetname "")
		)
		(fill yes
			(thermal_gap 0.5)
			(thermal_bridge_width 0.5)
			(island_removal_mode 0)
		)
		(polygon
			(pts
				(arc
					(start 371.398546 -178.534568)
					(mid 370.694966 -178.534568)
					(end 371.398546 -178.534568)
				)
			)
		)
	)
	(zone
		(layers "B.Cu" "In11.Cu" "In13.Cu" "In15.Cu")
		(hatch none 0.5)
		(connect_pads
			(clearance 0)
		)
		(min_thickness 0.25)
		(keepout
			(tracks not_allowed)
			(vias allowed)
			(pads allowed)
			(copperpour not_allowed)
			(footprints allowed)
		)
		(placement
			(enabled no)
			(sheetname "")
		)
		(fill yes
			(thermal_gap 0.5)
			(thermal_bridge_width 0.5)
			(island_removal_mode 0)
		)
		(polygon
			(pts
				(arc
					(start 344.040206 -275.08073)
					(mid 343.387426 -275.08073)
					(end 344.040206 -275.08073)
				)
			)
		)
	)
	(zone
		(layers "B.Cu" "In11.Cu" "In13.Cu" "In15.Cu")
		(hatch none 0.5)
		(connect_pads
			(clearance 0)
		)
		(min_thickness 0.25)
		(keepout
			(tracks not_allowed)
			(vias allowed)
			(pads allowed)
			(copperpour not_allowed)
			(footprints allowed)
		)
		(placement
			(enabled no)
			(sheetname "")
		)
		(fill yes
			(thermal_gap 0.5)
			(thermal_bridge_width 0.5)
			(island_removal_mode 0)
		)
		(polygon
			(pts
				(arc
					(start 203.297536 -244.066568)
					(mid 202.644756 -244.066568)
					(end 203.297536 -244.066568)
				)
			)
		)
	)
	(zone
		(layers "B.Cu" "In11.Cu" "In13.Cu" "In15.Cu")
		(hatch none 0.5)
		(connect_pads
			(clearance 0)
		)
		(min_thickness 0.25)
		(keepout
			(tracks not_allowed)
			(vias allowed)
			(pads allowed)
			(copperpour not_allowed)
			(footprints allowed)
		)
		(placement
			(enabled no)
			(sheetname "")
		)
		(fill yes
			(thermal_gap 0.5)
			(thermal_bridge_width 0.5)
			(island_removal_mode 0)
		)
		(polygon
			(pts
				(arc
					(start 188.209936 -221.116652)
					(mid 187.557156 -221.116652)
					(end 188.209936 -221.116652)
				)
			)
		)
	)
	(zone
		(layers "B.Cu" "In11.Cu" "In13.Cu" "In15.Cu")
		(hatch none 0.5)
		(connect_pads
			(clearance 0)
		)
		(min_thickness 0.25)
		(keepout
			(tracks not_allowed)
			(vias allowed)
			(pads allowed)
			(copperpour not_allowed)
			(footprints allowed)
		)
		(placement
			(enabled no)
			(sheetname "")
		)
		(fill yes
			(thermal_gap 0.5)
			(thermal_bridge_width 0.5)
			(island_removal_mode 0)
		)
		(polygon
			(pts
				(arc
					(start 436.150004 -199.866758)
					(mid 435.497224 -199.866758)
					(end 436.150004 -199.866758)
				)
			)
		)
	)
	(zone
		(layers "B.Cu" "In11.Cu" "In13.Cu" "In15.Cu")
		(hatch none 0.5)
		(connect_pads
			(clearance 0)
		)
		(min_thickness 0.25)
		(keepout
			(tracks not_allowed)
			(vias allowed)
			(pads allowed)
			(copperpour not_allowed)
			(footprints allowed)
		)
		(placement
			(enabled no)
			(sheetname "")
		)
		(fill yes
			(thermal_gap 0.5)
			(thermal_bridge_width 0.5)
			(island_removal_mode 0)
		)
		(polygon
			(pts
				(arc
					(start 342.054942 -427.089824)
					(mid 341.24519 -427.089824)
					(end 342.054942 -427.089824)
				)
			)
		)
	)
	(zone
		(layers "B.Cu" "In11.Cu" "In13.Cu" "In15.Cu")
		(hatch none 0.5)
		(connect_pads
			(clearance 0)
		)
		(min_thickness 0.25)
		(keepout
			(tracks not_allowed)
			(vias allowed)
			(pads allowed)
			(copperpour not_allowed)
			(footprints allowed)
		)
		(placement
			(enabled no)
			(sheetname "")
		)
		(fill yes
			(thermal_gap 0.5)
			(thermal_bridge_width 0.5)
			(island_removal_mode 0)
		)
		(polygon
			(pts
				(arc
					(start 388.154926 -431.889916)
					(mid 387.345174 -431.889916)
					(end 388.154926 -431.889916)
				)
			)
		)
	)
	(zone
		(layers "B.Cu" "In11.Cu" "In13.Cu" "In15.Cu")
		(hatch none 0.5)
		(connect_pads
			(clearance 0)
		)
		(min_thickness 0.25)
		(keepout
			(tracks not_allowed)
			(vias allowed)
			(pads allowed)
			(copperpour not_allowed)
			(footprints allowed)
		)
		(placement
			(enabled no)
			(sheetname "")
		)
		(fill yes
			(thermal_gap 0.5)
			(thermal_bridge_width 0.5)
			(island_removal_mode 0)
		)
		(polygon
			(pts
				(arc
					(start 451.237604 -245.76659)
					(mid 450.584824 -245.76659)
					(end 451.237604 -245.76659)
				)
			)
		)
	)
	(zone
		(layers "B.Cu" "In11.Cu" "In13.Cu" "In15.Cu")
		(hatch none 0.5)
		(connect_pads
			(clearance 0)
		)
		(min_thickness 0.25)
		(keepout
			(tracks not_allowed)
			(vias allowed)
			(pads allowed)
			(copperpour not_allowed)
			(footprints allowed)
		)
		(placement
			(enabled no)
			(sheetname "")
		)
		(fill yes
			(thermal_gap 0.5)
			(thermal_bridge_width 0.5)
			(island_removal_mode 0)
		)
		(polygon
			(pts
				(arc
					(start 104.088184 -274.266914)
					(mid 103.435404 -274.266914)
					(end 104.088184 -274.266914)
				)
			)
		)
	)
	(zone
		(layers "B.Cu" "In11.Cu" "In13.Cu" "In15.Cu")
		(hatch none 0.5)
		(connect_pads
			(clearance 0)
		)
		(min_thickness 0.25)
		(keepout
			(tracks not_allowed)
			(vias allowed)
			(pads allowed)
			(copperpour not_allowed)
			(footprints allowed)
		)
		(placement
			(enabled no)
			(sheetname "")
		)
		(fill yes
			(thermal_gap 0.5)
			(thermal_bridge_width 0.5)
			(island_removal_mode 0)
		)
		(polygon
			(pts
				(arc
					(start 332.054962 -426.089826)
					(mid 331.24521 -426.089826)
					(end 332.054962 -426.089826)
				)
			)
		)
	)
	(zone
		(layers "B.Cu" "In11.Cu" "In13.Cu" "In15.Cu")
		(hatch none 0.5)
		(connect_pads
			(clearance 0)
		)
		(min_thickness 0.25)
		(keepout
			(tracks not_allowed)
			(vias allowed)
			(pads allowed)
			(copperpour not_allowed)
			(footprints allowed)
		)
		(placement
			(enabled no)
			(sheetname "")
		)
		(fill yes
			(thermal_gap 0.5)
			(thermal_bridge_width 0.5)
			(island_removal_mode 0)
		)
		(polygon
			(pts
				(arc
					(start 352.55581 -60.617354)
					(mid 351.85223 -60.617354)
					(end 352.55581 -60.617354)
				)
			)
		)
	)
	(zone
		(layers "B.Cu" "In11.Cu" "In13.Cu" "In15.Cu")
		(hatch none 0.5)
		(connect_pads
			(clearance 0)
		)
		(min_thickness 0.25)
		(keepout
			(tracks not_allowed)
			(vias allowed)
			(pads allowed)
			(copperpour not_allowed)
			(footprints allowed)
		)
		(placement
			(enabled no)
			(sheetname "")
		)
		(fill yes
			(thermal_gap 0.5)
			(thermal_bridge_width 0.5)
			(island_removal_mode 0)
		)
		(polygon
			(pts
				(arc
					(start 353.79787 -226.831144)
					(mid 353.14509 -226.831144)
					(end 353.79787 -226.831144)
				)
			)
		)
	)
	(zone
		(layers "B.Cu" "In11.Cu" "In13.Cu" "In15.Cu")
		(hatch none 0.5)
		(connect_pads
			(clearance 0)
		)
		(min_thickness 0.25)
		(keepout
			(tracks not_allowed)
			(vias allowed)
			(pads allowed)
			(copperpour not_allowed)
			(footprints allowed)
		)
		(placement
			(enabled no)
			(sheetname "")
		)
		(fill yes
			(thermal_gap 0.5)
			(thermal_bridge_width 0.5)
			(island_removal_mode 0)
		)
		(polygon
			(pts
				(arc
					(start 95.629984 -259.616956)
					(mid 94.977204 -259.616956)
					(end 95.629984 -259.616956)
				)
			)
		)
	)
	(zone
		(layers "B.Cu" "In11.Cu" "In13.Cu" "In15.Cu")
		(hatch none 0.5)
		(connect_pads
			(clearance 0)
		)
		(min_thickness 0.25)
		(keepout
			(tracks not_allowed)
			(vias allowed)
			(pads allowed)
			(copperpour not_allowed)
			(footprints allowed)
		)
		(placement
			(enabled no)
			(sheetname "")
		)
		(fill yes
			(thermal_gap 0.5)
			(thermal_bridge_width 0.5)
			(island_removal_mode 0)
		)
		(polygon
			(pts
				(arc
					(start 103.508048 -214.622634)
					(mid 102.855268 -214.622634)
					(end 103.508048 -214.622634)
				)
			)
		)
	)
	(zone
		(layers "B.Cu" "In11.Cu" "In13.Cu" "In15.Cu")
		(hatch none 0.5)
		(connect_pads
			(clearance 0)
		)
		(min_thickness 0.25)
		(keepout
			(tracks not_allowed)
			(vias allowed)
			(pads allowed)
			(copperpour not_allowed)
			(footprints allowed)
		)
		(placement
			(enabled no)
			(sheetname "")
		)
		(fill yes
			(thermal_gap 0.5)
			(thermal_bridge_width 0.5)
			(island_removal_mode 0)
		)
		(polygon
			(pts
				(arc
					(start 350.148652 -279.150318)
					(mid 349.495872 -279.150318)
					(end 350.148652 -279.150318)
				)
			)
		)
	)
	(zone
		(layers "B.Cu" "In11.Cu" "In13.Cu" "In15.Cu")
		(hatch none 0.5)
		(connect_pads
			(clearance 0)
		)
		(min_thickness 0.25)
		(keepout
			(tracks not_allowed)
			(vias allowed)
			(pads allowed)
			(copperpour not_allowed)
			(footprints allowed)
		)
		(placement
			(enabled no)
			(sheetname "")
		)
		(fill yes
			(thermal_gap 0.5)
			(thermal_bridge_width 0.5)
			(island_removal_mode 0)
		)
		(polygon
			(pts
				(arc
					(start 373.064024 -248.806208)
					(mid 372.411244 -248.806208)
					(end 373.064024 -248.806208)
				)
			)
		)
	)
	(zone
		(layers "B.Cu" "In11.Cu" "In13.Cu" "In15.Cu")
		(hatch none 0.5)
		(connect_pads
			(clearance 0)
		)
		(min_thickness 0.25)
		(keepout
			(tracks not_allowed)
			(vias allowed)
			(pads allowed)
			(copperpour not_allowed)
			(footprints allowed)
		)
		(placement
			(enabled no)
			(sheetname "")
		)
		(fill yes
			(thermal_gap 0.5)
			(thermal_bridge_width 0.5)
			(island_removal_mode 0)
		)
		(polygon
			(pts
				(arc
					(start 455.337672 -313.766708)
					(mid 454.684892 -313.766708)
					(end 455.337672 -313.766708)
				)
			)
		)
	)
	(zone
		(layers "B.Cu" "In11.Cu" "In13.Cu" "In15.Cu")
		(hatch none 0.5)
		(connect_pads
			(clearance 0)
		)
		(min_thickness 0.25)
		(keepout
			(tracks not_allowed)
			(vias allowed)
			(pads allowed)
			(copperpour not_allowed)
			(footprints allowed)
		)
		(placement
			(enabled no)
			(sheetname "")
		)
		(fill yes
			(thermal_gap 0.5)
			(thermal_bridge_width 0.5)
			(island_removal_mode 0)
		)
		(polygon
			(pts
				(arc
					(start 272.599404 -243.216684)
					(mid 271.946624 -243.216684)
					(end 272.599404 -243.216684)
				)
			)
		)
	)
	(zone
		(layers "B.Cu" "In11.Cu" "In13.Cu" "In15.Cu")
		(hatch none 0.5)
		(connect_pads
			(clearance 0)
		)
		(min_thickness 0.25)
		(keepout
			(tracks not_allowed)
			(vias allowed)
			(pads allowed)
			(copperpour not_allowed)
			(footprints allowed)
		)
		(placement
			(enabled no)
			(sheetname "")
		)
		(fill yes
			(thermal_gap 0.5)
			(thermal_bridge_width 0.5)
			(island_removal_mode 0)
		)
		(polygon
			(pts
				(arc
					(start 192.310004 -287.416748)
					(mid 191.657224 -287.416748)
					(end 192.310004 -287.416748)
				)
			)
		)
	)
	(zone
		(layers "B.Cu" "In11.Cu" "In13.Cu" "In15.Cu")
		(hatch none 0.5)
		(connect_pads
			(clearance 0)
		)
		(min_thickness 0.25)
		(keepout
			(tracks not_allowed)
			(vias allowed)
			(pads allowed)
			(copperpour not_allowed)
			(footprints allowed)
		)
		(placement
			(enabled no)
			(sheetname "")
		)
		(fill yes
			(thermal_gap 0.5)
			(thermal_bridge_width 0.5)
			(island_removal_mode 0)
		)
		(polygon
			(pts
				(arc
					(start 249.500136 3.3528)
					(mid 248.796556 3.3528)
					(end 249.500136 3.3528)
				)
			)
		)
	)
	(zone
		(layers "B.Cu" "In11.Cu" "In13.Cu" "In15.Cu")
		(hatch none 0.5)
		(connect_pads
			(clearance 0)
		)
		(min_thickness 0.25)
		(keepout
			(tracks not_allowed)
			(vias allowed)
			(pads allowed)
			(copperpour not_allowed)
			(footprints allowed)
		)
		(placement
			(enabled no)
			(sheetname "")
		)
		(fill yes
			(thermal_gap 0.5)
			(thermal_bridge_width 0.5)
			(island_removal_mode 0)
		)
		(polygon
			(pts
				(arc
					(start 343.099898 -260.430772)
					(mid 342.447118 -260.430772)
					(end 343.099898 -260.430772)
				)
			)
		)
	)
	(zone
		(layers "B.Cu" "In11.Cu" "In13.Cu" "In15.Cu")
		(hatch none 0.5)
		(connect_pads
			(clearance 0)
		)
		(min_thickness 0.25)
		(keepout
			(tracks not_allowed)
			(vias allowed)
			(pads allowed)
			(copperpour not_allowed)
			(footprints allowed)
		)
		(placement
			(enabled no)
			(sheetname "")
		)
		(fill yes
			(thermal_gap 0.5)
			(thermal_bridge_width 0.5)
			(island_removal_mode 0)
		)
		(polygon
			(pts
				(arc
					(start 97.509584 -280.778204)
					(mid 96.856804 -280.778204)
					(end 97.509584 -280.778204)
				)
			)
		)
	)
	(zone
		(layers "B.Cu" "In13.Cu" "In15.Cu")
		(hatch none 0.5)
		(connect_pads
			(clearance 0)
		)
		(min_thickness 0.25)
		(keepout
			(tracks not_allowed)
			(vias allowed)
			(pads allowed)
			(copperpour not_allowed)
			(footprints allowed)
		)
		(placement
			(enabled no)
			(sheetname "")
		)
		(fill yes
			(thermal_gap 0.5)
			(thermal_bridge_width 0.5)
			(island_removal_mode 0)
		)
		(polygon
			(pts
				(arc
					(start 125.703584 -269.38351)
					(mid 125.050804 -269.38351)
					(end 125.703584 -269.38351)
				)
			)
		)
	)
	(zone
		(layers "B.Cu" "In13.Cu" "In15.Cu")
		(hatch none 0.5)
		(connect_pads
			(clearance 0)
		)
		(min_thickness 0.25)
		(keepout
			(tracks not_allowed)
			(vias allowed)
			(pads allowed)
			(copperpour not_allowed)
			(footprints allowed)
		)
		(placement
			(enabled no)
			(sheetname "")
		)
		(fill yes
			(thermal_gap 0.5)
			(thermal_bridge_width 0.5)
			(island_removal_mode 0)
		)
		(polygon
			(pts
				(arc
					(start 356.257606 -275.08073)
					(mid 355.604826 -275.08073)
					(end 356.257606 -275.08073)
				)
			)
		)
	)
	(zone
		(layers "B.Cu" "In13.Cu" "In15.Cu")
		(hatch none 0.5)
		(connect_pads
			(clearance 0)
		)
		(min_thickness 0.25)
		(keepout
			(tracks not_allowed)
			(vias allowed)
			(pads allowed)
			(copperpour not_allowed)
			(footprints allowed)
		)
		(placement
			(enabled no)
			(sheetname "")
		)
		(fill yes
			(thermal_gap 0.5)
			(thermal_bridge_width 0.5)
			(island_removal_mode 0)
		)
		(polygon
			(pts
				(arc
					(start 145.154904 -428.28972)
					(mid 144.345152 -428.28972)
					(end 145.154904 -428.28972)
				)
			)
		)
	)
	(zone
		(layers "B.Cu" "In13.Cu" "In15.Cu")
		(hatch none 0.5)
		(connect_pads
			(clearance 0)
		)
		(min_thickness 0.25)
		(keepout
			(tracks not_allowed)
			(vias allowed)
			(pads allowed)
			(copperpour not_allowed)
			(footprints allowed)
		)
		(placement
			(enabled no)
			(sheetname "")
		)
		(fill yes
			(thermal_gap 0.5)
			(thermal_bridge_width 0.5)
			(island_removal_mode 0)
		)
		(polygon
			(pts
				(arc
					(start 98.339402 -244.73662)
					(mid 97.686622 -244.73662)
					(end 98.339402 -244.73662)
				)
			)
		)
	)
	(zone
		(layers "B.Cu" "In13.Cu" "In15.Cu")
		(hatch none 0.5)
		(connect_pads
			(clearance 0)
		)
		(min_thickness 0.25)
		(keepout
			(tracks not_allowed)
			(vias allowed)
			(pads allowed)
			(copperpour not_allowed)
			(footprints allowed)
		)
		(placement
			(enabled no)
			(sheetname "")
		)
		(fill yes
			(thermal_gap 0.5)
			(thermal_bridge_width 0.5)
			(island_removal_mode 0)
		)
		(polygon
			(pts
				(arc
					(start 400.20748 -403.883876)
					(mid 399.5039 -403.883876)
					(end 400.20748 -403.883876)
				)
			)
		)
	)
	(zone
		(layers "B.Cu" "In13.Cu" "In15.Cu")
		(hatch none 0.5)
		(connect_pads
			(clearance 0)
		)
		(min_thickness 0.25)
		(keepout
			(tracks not_allowed)
			(vias allowed)
			(pads allowed)
			(copperpour not_allowed)
			(footprints allowed)
		)
		(placement
			(enabled no)
			(sheetname "")
		)
		(fill yes
			(thermal_gap 0.5)
			(thermal_bridge_width 0.5)
			(island_removal_mode 0)
		)
		(polygon
			(pts
				(arc
					(start 373.174006 -270.19758)
					(mid 372.521226 -270.19758)
					(end 373.174006 -270.19758)
				)
			)
		)
	)
	(zone
		(layers "B.Cu" "In13.Cu" "In15.Cu")
		(hatch none 0.5)
		(connect_pads
			(clearance 0)
		)
		(min_thickness 0.25)
		(keepout
			(tracks not_allowed)
			(vias allowed)
			(pads allowed)
			(copperpour not_allowed)
			(footprints allowed)
		)
		(placement
			(enabled no)
			(sheetname "")
		)
		(fill yes
			(thermal_gap 0.5)
			(thermal_bridge_width 0.5)
			(island_removal_mode 0)
		)
		(polygon
			(pts
				(arc
					(start 346.389452 -277.522432)
					(mid 345.736672 -277.522432)
					(end 346.389452 -277.522432)
				)
			)
		)
	)
	(zone
		(layers "B.Cu" "In13.Cu" "In15.Cu")
		(hatch none 0.5)
		(connect_pads
			(clearance 0)
		)
		(min_thickness 0.25)
		(keepout
			(tracks not_allowed)
			(vias allowed)
			(pads allowed)
			(copperpour not_allowed)
			(footprints allowed)
		)
		(placement
			(enabled no)
			(sheetname "")
		)
		(fill yes
			(thermal_gap 0.5)
			(thermal_bridge_width 0.5)
			(island_removal_mode 0)
		)
		(polygon
			(pts
				(arc
					(start 451.237604 -286.56661)
					(mid 450.584824 -286.56661)
					(end 451.237604 -286.56661)
				)
			)
		)
	)
	(zone
		(layers "B.Cu" "In13.Cu" "In15.Cu")
		(hatch none 0.5)
		(connect_pads
			(clearance 0)
		)
		(min_thickness 0.25)
		(keepout
			(tracks not_allowed)
			(vias allowed)
			(pads allowed)
			(copperpour not_allowed)
			(footprints allowed)
		)
		(placement
			(enabled no)
			(sheetname "")
		)
		(fill yes
			(thermal_gap 0.5)
			(thermal_bridge_width 0.5)
			(island_removal_mode 0)
		)
		(polygon
			(pts
				(arc
					(start 269.155672 -292.516814)
					(mid 268.502892 -292.516814)
					(end 269.155672 -292.516814)
				)
			)
		)
	)
	(zone
		(layers "B.Cu" "In13.Cu" "In15.Cu")
		(hatch none 0.5)
		(connect_pads
			(clearance 0)
		)
		(min_thickness 0.25)
		(keepout
			(tracks not_allowed)
			(vias allowed)
			(pads allowed)
			(copperpour not_allowed)
			(footprints allowed)
		)
		(placement
			(enabled no)
			(sheetname "")
		)
		(fill yes
			(thermal_gap 0.5)
			(thermal_bridge_width 0.5)
			(island_removal_mode 0)
		)
		(polygon
			(pts
				(arc
					(start 373.643652 -254.733552)
					(mid 372.990872 -254.733552)
					(end 373.643652 -254.733552)
				)
			)
		)
	)
	(zone
		(layers "B.Cu" "In13.Cu" "In15.Cu")
		(hatch none 0.5)
		(connect_pads
			(clearance 0)
		)
		(min_thickness 0.25)
		(keepout
			(tracks not_allowed)
			(vias allowed)
			(pads allowed)
			(copperpour not_allowed)
			(footprints allowed)
		)
		(placement
			(enabled no)
			(sheetname "")
		)
		(fill yes
			(thermal_gap 0.5)
			(thermal_bridge_width 0.5)
			(island_removal_mode 0)
		)
		(polygon
			(pts
				(arc
					(start 203.297536 -261.066788)
					(mid 202.644756 -261.066788)
					(end 203.297536 -261.066788)
				)
			)
		)
	)
	(zone
		(layers "B.Cu" "In13.Cu" "In15.Cu")
		(hatch none 0.5)
		(connect_pads
			(clearance 0)
		)
		(min_thickness 0.25)
		(keepout
			(tracks not_allowed)
			(vias allowed)
			(pads allowed)
			(copperpour not_allowed)
			(footprints allowed)
		)
		(placement
			(enabled no)
			(sheetname "")
		)
		(fill yes
			(thermal_gap 0.5)
			(thermal_bridge_width 0.5)
			(island_removal_mode 0)
		)
		(polygon
			(pts
				(arc
					(start 269.155672 -287.416748)
					(mid 268.502892 -287.416748)
					(end 269.155672 -287.416748)
				)
			)
		)
	)
	(zone
		(layers "B.Cu" "In13.Cu" "In15.Cu")
		(hatch none 0.5)
		(connect_pads
			(clearance 0)
		)
		(min_thickness 0.25)
		(keepout
			(tracks not_allowed)
			(vias allowed)
			(pads allowed)
			(copperpour not_allowed)
			(footprints allowed)
		)
		(placement
			(enabled no)
			(sheetname "")
		)
		(fill yes
			(thermal_gap 0.5)
			(thermal_bridge_width 0.5)
			(island_removal_mode 0)
		)
		(polygon
			(pts
				(arc
					(start 21.215604 -197.316598)
					(mid 20.562824 -197.316598)
					(end 21.215604 -197.316598)
				)
			)
		)
	)
	(zone
		(layers "B.Cu" "In13.Cu" "In15.Cu")
		(hatch none 0.5)
		(connect_pads
			(clearance 0)
		)
		(min_thickness 0.25)
		(keepout
			(tracks not_allowed)
			(vias allowed)
			(pads allowed)
			(copperpour not_allowed)
			(footprints allowed)
		)
		(placement
			(enabled no)
			(sheetname "")
		)
		(fill yes
			(thermal_gap 0.5)
			(thermal_bridge_width 0.5)
			(island_removal_mode 0)
		)
		(polygon
			(pts
				(arc
					(start 207.397604 -240.666778)
					(mid 206.744824 -240.666778)
					(end 207.397604 -240.666778)
				)
			)
		)
	)
	(zone
		(layers "B.Cu" "In13.Cu" "In15.Cu")
		(hatch none 0.5)
		(connect_pads
			(clearance 0)
		)
		(min_thickness 0.25)
		(keepout
			(tracks not_allowed)
			(vias allowed)
			(pads allowed)
			(copperpour not_allowed)
			(footprints allowed)
		)
		(placement
			(enabled no)
			(sheetname "")
		)
		(fill yes
			(thermal_gap 0.5)
			(thermal_bridge_width 0.5)
			(island_removal_mode 0)
		)
		(polygon
			(pts
				(arc
					(start 261.611872 -267.016738)
					(mid 260.959092 -267.016738)
					(end 261.611872 -267.016738)
				)
			)
		)
	)
	(zone
		(layers "B.Cu" "In13.Cu" "In15.Cu")
		(hatch none 0.5)
		(connect_pads
			(clearance 0)
		)
		(min_thickness 0.25)
		(keepout
			(tracks not_allowed)
			(vias allowed)
			(pads allowed)
			(copperpour not_allowed)
			(footprints allowed)
		)
		(placement
			(enabled no)
			(sheetname "")
		)
		(fill yes
			(thermal_gap 0.5)
			(thermal_bridge_width 0.5)
			(island_removal_mode 0)
		)
		(polygon
			(pts
				(arc
					(start 21.215604 -306.116736)
					(mid 20.562824 -306.116736)
					(end 21.215604 -306.116736)
				)
			)
		)
	)
	(zone
		(layers "B.Cu" "In13.Cu" "In15.Cu")
		(hatch none 0.5)
		(connect_pads
			(clearance 0)
		)
		(min_thickness 0.25)
		(keepout
			(tracks not_allowed)
			(vias allowed)
			(pads allowed)
			(copperpour not_allowed)
			(footprints allowed)
		)
		(placement
			(enabled no)
			(sheetname "")
		)
		(fill yes
			(thermal_gap 0.5)
			(thermal_bridge_width 0.5)
			(island_removal_mode 0)
		)
		(polygon
			(pts
				(arc
					(start 99.859338 -281.59202)
					(mid 99.206558 -281.59202)
					(end 99.859338 -281.59202)
				)
			)
		)
	)
	(zone
		(layers "B.Cu" "In13.Cu" "In15.Cu")
		(hatch none 0.5)
		(connect_pads
			(clearance 0)
		)
		(min_thickness 0.25)
		(keepout
			(tracks not_allowed)
			(vias allowed)
			(pads allowed)
			(copperpour not_allowed)
			(footprints allowed)
		)
		(placement
			(enabled no)
			(sheetname "")
		)
		(fill yes
			(thermal_gap 0.5)
			(thermal_bridge_width 0.5)
			(island_removal_mode 0)
		)
		(polygon
			(pts
				(arc
					(start 349.09887 -234.970066)
					(mid 348.44609 -234.970066)
					(end 349.09887 -234.970066)
				)
			)
		)
	)
	(zone
		(layers "B.Cu" "In13.Cu" "In15.Cu")
		(hatch none 0.5)
		(connect_pads
			(clearance 0)
		)
		(min_thickness 0.25)
		(keepout
			(tracks not_allowed)
			(vias allowed)
			(pads allowed)
			(copperpour not_allowed)
			(footprints allowed)
		)
		(placement
			(enabled no)
			(sheetname "")
		)
		(fill yes
			(thermal_gap 0.5)
			(thermal_bridge_width 0.5)
			(island_removal_mode 0)
		)
		(polygon
			(pts
				(arc
					(start 125.123956 -229.272846)
					(mid 124.471176 -229.272846)
					(end 125.123956 -229.272846)
				)
			)
		)
	)
	(zone
		(layers "B.Cu" "In13.Cu" "In15.Cu")
		(hatch none 0.5)
		(connect_pads
			(clearance 0)
		)
		(min_thickness 0.25)
		(keepout
			(tracks not_allowed)
			(vias allowed)
			(pads allowed)
			(copperpour not_allowed)
			(footprints allowed)
		)
		(placement
			(enabled no)
			(sheetname "")
		)
		(fill yes
			(thermal_gap 0.5)
			(thermal_bridge_width 0.5)
			(island_removal_mode 0)
		)
		(polygon
			(pts
				(arc
					(start 269.155672 -251.716794)
					(mid 268.502892 -251.716794)
					(end 269.155672 -251.716794)
				)
			)
		)
	)
	(zone
		(layers "B.Cu" "In13.Cu" "In15.Cu")
		(hatch none 0.5)
		(connect_pads
			(clearance 0)
		)
		(min_thickness 0.25)
		(keepout
			(tracks not_allowed)
			(vias allowed)
			(pads allowed)
			(copperpour not_allowed)
			(footprints allowed)
		)
		(placement
			(enabled no)
			(sheetname "")
		)
		(fill yes
			(thermal_gap 0.5)
			(thermal_bridge_width 0.5)
			(island_removal_mode 0)
		)
		(polygon
			(pts
				(arc
					(start 76.054966 -429.689768)
					(mid 75.245214 -429.689768)
					(end 76.054966 -429.689768)
				)
			)
		)
	)
	(zone
		(layers "B.Cu" "In13.Cu" "In15.Cu")
		(hatch none 0.5)
		(connect_pads
			(clearance 0)
		)
		(min_thickness 0.25)
		(keepout
			(tracks not_allowed)
			(vias allowed)
			(pads allowed)
			(copperpour not_allowed)
			(footprints allowed)
		)
		(placement
			(enabled no)
			(sheetname "")
		)
		(fill yes
			(thermal_gap 0.5)
			(thermal_bridge_width 0.5)
			(island_removal_mode 0)
		)
		(polygon
			(pts
				(arc
					(start 134.154926 -426.089826)
					(mid 133.345174 -426.089826)
					(end 134.154926 -426.089826)
				)
			)
		)
	)
	(zone
		(layers "B.Cu" "In13.Cu" "In15.Cu")
		(hatch none 0.5)
		(connect_pads
			(clearance 0)
		)
		(min_thickness 0.25)
		(keepout
			(tracks not_allowed)
			(vias allowed)
			(pads allowed)
			(copperpour not_allowed)
			(footprints allowed)
		)
		(placement
			(enabled no)
			(sheetname "")
		)
		(fill yes
			(thermal_gap 0.5)
			(thermal_bridge_width 0.5)
			(island_removal_mode 0)
		)
		(polygon
			(pts
				(arc
					(start 337.931506 -282.405836)
					(mid 337.278726 -282.405836)
					(end 337.931506 -282.405836)
				)
			)
		)
	)
	(zone
		(layers "B.Cu" "In13.Cu" "In15.Cu")
		(hatch none 0.5)
		(connect_pads
			(clearance 0)
		)
		(min_thickness 0.25)
		(keepout
			(tracks not_allowed)
			(vias allowed)
			(pads allowed)
			(copperpour not_allowed)
			(footprints allowed)
		)
		(placement
			(enabled no)
			(sheetname "")
		)
		(fill yes
			(thermal_gap 0.5)
			(thermal_bridge_width 0.5)
			(island_removal_mode 0)
		)
		(polygon
			(pts
				(arc
					(start 451.237604 -302.716692)
					(mid 450.584824 -302.716692)
					(end 451.237604 -302.716692)
				)
			)
		)
	)
	(zone
		(layers "B.Cu" "In13.Cu" "In15.Cu")
		(hatch none 0.5)
		(connect_pads
			(clearance 0)
		)
		(min_thickness 0.25)
		(keepout
			(tracks not_allowed)
			(vias allowed)
			(pads allowed)
			(copperpour not_allowed)
			(footprints allowed)
		)
		(placement
			(enabled no)
			(sheetname "")
		)
		(fill yes
			(thermal_gap 0.5)
			(thermal_bridge_width 0.5)
			(island_removal_mode 0)
		)
		(polygon
			(pts
				(arc
					(start 127.473202 -246.364506)
					(mid 126.820422 -246.364506)
					(end 127.473202 -246.364506)
				)
			)
		)
	)
	(zone
		(layers "B.Cu" "In13.Cu" "In15.Cu")
		(hatch none 0.5)
		(connect_pads
			(clearance 0)
		)
		(min_thickness 0.25)
		(keepout
			(tracks not_allowed)
			(vias allowed)
			(pads allowed)
			(copperpour not_allowed)
			(footprints allowed)
		)
		(placement
			(enabled no)
			(sheetname "")
		)
		(fill yes
			(thermal_gap 0.5)
			(thermal_bridge_width 0.5)
			(island_removal_mode 0)
		)
		(polygon
			(pts
				(arc
					(start 17.115536 -295.916604)
					(mid 16.462756 -295.916604)
					(end 17.115536 -295.916604)
				)
			)
		)
	)
	(zone
		(layers "B.Cu" "In13.Cu" "In15.Cu")
		(hatch none 0.5)
		(connect_pads
			(clearance 0)
		)
		(min_thickness 0.25)
		(keepout
			(tracks not_allowed)
			(vias allowed)
			(pads allowed)
			(copperpour not_allowed)
			(footprints allowed)
		)
		(placement
			(enabled no)
			(sheetname "")
		)
		(fill yes
			(thermal_gap 0.5)
			(thermal_bridge_width 0.5)
			(island_removal_mode 0)
		)
		(polygon
			(pts
				(arc
					(start 95.050356 -247.178322)
					(mid 94.397576 -247.178322)
					(end 95.050356 -247.178322)
				)
			)
		)
	)
	(zone
		(layers "B.Cu" "In13.Cu" "In15.Cu")
		(hatch none 0.5)
		(connect_pads
			(clearance 0)
		)
		(min_thickness 0.25)
		(keepout
			(tracks not_allowed)
			(vias allowed)
			(pads allowed)
			(copperpour not_allowed)
			(footprints allowed)
		)
		(placement
			(enabled no)
			(sheetname "")
		)
		(fill yes
			(thermal_gap 0.5)
			(thermal_bridge_width 0.5)
			(island_removal_mode 0)
		)
		(polygon
			(pts
				(arc
					(start 348.269052 -256.361438)
					(mid 347.616272 -256.361438)
					(end 348.269052 -256.361438)
				)
			)
		)
	)
	(zone
		(layers "B.Cu" "In13.Cu" "In15.Cu")
		(hatch none 0.5)
		(connect_pads
			(clearance 0)
		)
		(min_thickness 0.25)
		(keepout
			(tracks not_allowed)
			(vias allowed)
			(pads allowed)
			(copperpour not_allowed)
			(footprints allowed)
		)
		(placement
			(enabled no)
			(sheetname "")
		)
		(fill yes
			(thermal_gap 0.5)
			(thermal_bridge_width 0.5)
			(island_removal_mode 0)
		)
		(polygon
			(pts
				(arc
					(start 348.15907 -243.108988)
					(mid 347.50629 -243.108988)
					(end 348.15907 -243.108988)
				)
			)
		)
	)
	(zone
		(layers "B.Cu" "In13.Cu" "In15.Cu")
		(hatch none 0.5)
		(connect_pads
			(clearance 0)
		)
		(min_thickness 0.25)
		(keepout
			(tracks not_allowed)
			(vias allowed)
			(pads allowed)
			(copperpour not_allowed)
			(footprints allowed)
		)
		(placement
			(enabled no)
			(sheetname "")
		)
		(fill yes
			(thermal_gap 0.5)
			(thermal_bridge_width 0.5)
			(island_removal_mode 0)
		)
		(polygon
			(pts
				(arc
					(start 17.115536 -250.866656)
					(mid 16.462756 -250.866656)
					(end 17.115536 -250.866656)
				)
			)
		)
	)
	(zone
		(layers "B.Cu" "In13.Cu" "In15.Cu")
		(hatch none 0.5)
		(connect_pads
			(clearance 0)
		)
		(min_thickness 0.25)
		(keepout
			(tracks not_allowed)
			(vias allowed)
			(pads allowed)
			(copperpour not_allowed)
			(footprints allowed)
		)
		(placement
			(enabled no)
			(sheetname "")
		)
		(fill yes
			(thermal_gap 0.5)
			(thermal_bridge_width 0.5)
			(island_removal_mode 0)
		)
		(polygon
			(pts
				(arc
					(start 394.739622 -6.713474)
					(mid 394.036042 -6.713474)
					(end 394.739622 -6.713474)
				)
			)
		)
	)
	(zone
		(layers "B.Cu" "In13.Cu" "In15.Cu")
		(hatch none 0.5)
		(connect_pads
			(clearance 0)
		)
		(min_thickness 0.25)
		(keepout
			(tracks not_allowed)
			(vias allowed)
			(pads allowed)
			(copperpour not_allowed)
			(footprints allowed)
		)
		(placement
			(enabled no)
			(sheetname "")
		)
		(fill yes
			(thermal_gap 0.5)
			(thermal_bridge_width 0.5)
			(island_removal_mode 0)
		)
		(polygon
			(pts
				(arc
					(start 106.907584 -280.778204)
					(mid 106.254804 -280.778204)
					(end 106.907584 -280.778204)
				)
			)
		)
	)
	(zone
		(layers "B.Cu" "In13.Cu" "In15.Cu")
		(hatch none 0.5)
		(connect_pads
			(clearance 0)
		)
		(min_thickness 0.25)
		(keepout
			(tracks not_allowed)
			(vias allowed)
			(pads allowed)
			(copperpour not_allowed)
			(footprints allowed)
		)
		(placement
			(enabled no)
			(sheetname "")
		)
		(fill yes
			(thermal_gap 0.5)
			(thermal_bridge_width 0.5)
			(island_removal_mode 0)
		)
		(polygon
			(pts
				(arc
					(start 123.244356 -237.411514)
					(mid 122.591576 -237.411514)
					(end 123.244356 -237.411514)
				)
			)
		)
	)
	(zone
		(layers "B.Cu" "In13.Cu" "In15.Cu")
		(hatch none 0.5)
		(connect_pads
			(clearance 0)
		)
		(min_thickness 0.25)
		(keepout
			(tracks not_allowed)
			(vias allowed)
			(pads allowed)
			(copperpour not_allowed)
			(footprints allowed)
		)
		(placement
			(enabled no)
			(sheetname "")
		)
		(fill yes
			(thermal_gap 0.5)
			(thermal_bridge_width 0.5)
			(island_removal_mode 0)
		)
		(polygon
			(pts
				(arc
					(start 373.064024 -227.64496)
					(mid 372.411244 -227.64496)
					(end 373.064024 -227.64496)
				)
			)
		)
	)
	(zone
		(layers "B.Cu" "In13.Cu" "In15.Cu")
		(hatch none 0.5)
		(connect_pads
			(clearance 0)
		)
		(min_thickness 0.25)
		(keepout
			(tracks not_allowed)
			(vias allowed)
			(pads allowed)
			(copperpour not_allowed)
			(footprints allowed)
		)
		(placement
			(enabled no)
			(sheetname "")
		)
		(fill yes
			(thermal_gap 0.5)
			(thermal_bridge_width 0.5)
			(island_removal_mode 0)
		)
		(polygon
			(pts
				(arc
					(start 207.397604 -195.616576)
					(mid 206.744824 -195.616576)
					(end 207.397604 -195.616576)
				)
			)
		)
	)
	(zone
		(layers "B.Cu" "In13.Cu" "In15.Cu")
		(hatch none 0.5)
		(connect_pads
			(clearance 0)
		)
		(min_thickness 0.25)
		(keepout
			(tracks not_allowed)
			(vias allowed)
			(pads allowed)
			(copperpour not_allowed)
			(footprints allowed)
		)
		(placement
			(enabled no)
			(sheetname "")
		)
		(fill yes
			(thermal_gap 0.5)
			(thermal_bridge_width 0.5)
			(island_removal_mode 0)
		)
		(polygon
			(pts
				(arc
					(start 125.233938 -265.314176)
					(mid 124.581158 -265.314176)
					(end 125.233938 -265.314176)
				)
			)
		)
	)
	(zone
		(layers "B.Cu" "In13.Cu" "In15.Cu")
		(hatch none 0.5)
		(connect_pads
			(clearance 0)
		)
		(min_thickness 0.25)
		(keepout
			(tracks not_allowed)
			(vias allowed)
			(pads allowed)
			(copperpour not_allowed)
			(footprints allowed)
		)
		(placement
			(enabled no)
			(sheetname "")
		)
		(fill yes
			(thermal_gap 0.5)
			(thermal_bridge_width 0.5)
			(island_removal_mode 0)
		)
		(polygon
			(pts
				(arc
					(start 99.279202 -230.086662)
					(mid 98.626422 -230.086662)
					(end 99.279202 -230.086662)
				)
			)
		)
	)
	(zone
		(layers "B.Cu" "In13.Cu" "In15.Cu")
		(hatch none 0.5)
		(connect_pads
			(clearance 0)
		)
		(min_thickness 0.25)
		(keepout
			(tracks not_allowed)
			(vias allowed)
			(pads allowed)
			(copperpour not_allowed)
			(footprints allowed)
		)
		(placement
			(enabled no)
			(sheetname "")
		)
		(fill yes
			(thermal_gap 0.5)
			(thermal_bridge_width 0.5)
			(island_removal_mode 0)
		)
		(polygon
			(pts
				(arc
					(start 100.328984 -267.755878)
					(mid 99.676204 -267.755878)
					(end 100.328984 -267.755878)
				)
			)
		)
	)
	(zone
		(layers "B.Cu" "In13.Cu" "In15.Cu")
		(hatch none 0.5)
		(connect_pads
			(clearance 0)
		)
		(min_thickness 0.25)
		(keepout
			(tracks not_allowed)
			(vias allowed)
			(pads allowed)
			(copperpour not_allowed)
			(footprints allowed)
		)
		(placement
			(enabled no)
			(sheetname "")
		)
		(fill yes
			(thermal_gap 0.5)
			(thermal_bridge_width 0.5)
			(island_removal_mode 0)
		)
		(polygon
			(pts
				(arc
					(start 17.115536 -200.716642)
					(mid 16.462756 -200.716642)
					(end 17.115536 -200.716642)
				)
			)
		)
	)
	(zone
		(layers "B.Cu" "In13.Cu" "In15.Cu")
		(hatch none 0.5)
		(connect_pads
			(clearance 0)
		)
		(min_thickness 0.25)
		(keepout
			(tracks not_allowed)
			(vias allowed)
			(pads allowed)
			(copperpour not_allowed)
			(footprints allowed)
		)
		(placement
			(enabled no)
			(sheetname "")
		)
		(fill yes
			(thermal_gap 0.5)
			(thermal_bridge_width 0.5)
			(island_removal_mode 0)
		)
		(polygon
			(pts
				(arc
					(start 80.054958 -429.689768)
					(mid 79.245206 -429.689768)
					(end 80.054958 -429.689768)
				)
			)
		)
	)
	(zone
		(layers "B.Cu" "In13.Cu" "In15.Cu")
		(hatch none 0.5)
		(connect_pads
			(clearance 0)
		)
		(min_thickness 0.25)
		(keepout
			(tracks not_allowed)
			(vias allowed)
			(pads allowed)
			(copperpour not_allowed)
			(footprints allowed)
		)
		(placement
			(enabled no)
			(sheetname "")
		)
		(fill yes
			(thermal_gap 0.5)
			(thermal_bridge_width 0.5)
			(island_removal_mode 0)
		)
		(polygon
			(pts
				(arc
					(start 373.643652 -264.50036)
					(mid 372.990872 -264.50036)
					(end 373.643652 -264.50036)
				)
			)
		)
	)
	(zone
		(layers "B.Cu" "In13.Cu" "In15.Cu")
		(hatch none 0.5)
		(connect_pads
			(clearance 0)
		)
		(min_thickness 0.25)
		(keepout
			(tracks not_allowed)
			(vias allowed)
			(pads allowed)
			(copperpour not_allowed)
			(footprints allowed)
		)
		(placement
			(enabled no)
			(sheetname "")
		)
		(fill yes
			(thermal_gap 0.5)
			(thermal_bridge_width 0.5)
			(island_removal_mode 0)
		)
		(polygon
			(pts
				(arc
					(start 116.195602 -221.94774)
					(mid 115.542822 -221.94774)
					(end 116.195602 -221.94774)
				)
			)
		)
	)
	(zone
		(layers "B.Cu" "In13.Cu" "In15.Cu")
		(hatch none 0.5)
		(connect_pads
			(clearance 0)
		)
		(min_thickness 0.25)
		(keepout
			(tracks not_allowed)
			(vias allowed)
			(pads allowed)
			(copperpour not_allowed)
			(footprints allowed)
		)
		(placement
			(enabled no)
			(sheetname "")
		)
		(fill yes
			(thermal_gap 0.5)
			(thermal_bridge_width 0.5)
			(island_removal_mode 0)
		)
		(polygon
			(pts
				(arc
					(start 372.234206 -273.453098)
					(mid 371.581426 -273.453098)
					(end 372.234206 -273.453098)
				)
			)
		)
	)
	(zone
		(layers "B.Cu" "In13.Cu" "In15.Cu")
		(hatch none 0.5)
		(connect_pads
			(clearance 0)
		)
		(min_thickness 0.25)
		(keepout
			(tracks not_allowed)
			(vias allowed)
			(pads allowed)
			(copperpour not_allowed)
			(footprints allowed)
		)
		(placement
			(enabled no)
			(sheetname "")
		)
		(fill yes
			(thermal_gap 0.5)
			(thermal_bridge_width 0.5)
			(island_removal_mode 0)
		)
		(polygon
			(pts
				(arc
					(start 203.297536 -199.866758)
					(mid 202.644756 -199.866758)
					(end 203.297536 -199.866758)
				)
			)
		)
	)
	(zone
		(layers "B.Cu" "In13.Cu" "In15.Cu")
		(hatch none 0.5)
		(connect_pads
			(clearance 0)
		)
		(min_thickness 0.25)
		(keepout
			(tracks not_allowed)
			(vias allowed)
			(pads allowed)
			(copperpour not_allowed)
			(footprints allowed)
		)
		(placement
			(enabled no)
			(sheetname "")
		)
		(fill yes
			(thermal_gap 0.5)
			(thermal_bridge_width 0.5)
			(island_removal_mode 0)
		)
		(polygon
			(pts
				(arc
					(start 21.215604 -274.66671)
					(mid 20.562824 -274.66671)
					(end 21.215604 -274.66671)
				)
			)
		)
	)
	(zone
		(layers "B.Cu" "In13.Cu" "In15.Cu")
		(hatch none 0.5)
		(connect_pads
			(clearance 0)
		)
		(min_thickness 0.25)
		(keepout
			(tracks not_allowed)
			(vias allowed)
			(pads allowed)
			(copperpour not_allowed)
			(footprints allowed)
		)
		(placement
			(enabled no)
			(sheetname "")
		)
		(fill yes
			(thermal_gap 0.5)
			(thermal_bridge_width 0.5)
			(island_removal_mode 0)
		)
		(polygon
			(pts
				(arc
					(start 124.294138 -258.80314)
					(mid 123.641358 -258.80314)
					(end 124.294138 -258.80314)
				)
			)
		)
	)
	(zone
		(layers "B.Cu" "In13.Cu" "In15.Cu")
		(hatch none 0.5)
		(connect_pads
			(clearance 0)
		)
		(min_thickness 0.25)
		(keepout
			(tracks not_allowed)
			(vias allowed)
			(pads allowed)
			(copperpour not_allowed)
			(footprints allowed)
		)
		(placement
			(enabled no)
			(sheetname "")
		)
		(fill yes
			(thermal_gap 0.5)
			(thermal_bridge_width 0.5)
			(island_removal_mode 0)
		)
		(polygon
			(pts
				(arc
					(start 430.400714 -4.95173)
					(mid 429.697134 -4.95173)
					(end 430.400714 -4.95173)
				)
			)
		)
	)
	(zone
		(layers "B.Cu" "In13.Cu" "In15.Cu")
		(hatch none 0.5)
		(connect_pads
			(clearance 0)
		)
		(min_thickness 0.25)
		(keepout
			(tracks not_allowed)
			(vias allowed)
			(pads allowed)
			(copperpour not_allowed)
			(footprints allowed)
		)
		(placement
			(enabled no)
			(sheetname "")
		)
		(fill yes
			(thermal_gap 0.5)
			(thermal_bridge_width 0.5)
			(island_removal_mode 0)
		)
		(polygon
			(pts
				(arc
					(start 265.055604 -264.466578)
					(mid 264.402824 -264.466578)
					(end 265.055604 -264.466578)
				)
			)
		)
	)
	(zone
		(layers "B.Cu" "In13.Cu" "In15.Cu")
		(hatch none 0.5)
		(connect_pads
			(clearance 0)
		)
		(min_thickness 0.25)
		(keepout
			(tracks not_allowed)
			(vias allowed)
			(pads allowed)
			(copperpour not_allowed)
			(footprints allowed)
		)
		(placement
			(enabled no)
			(sheetname "")
		)
		(fill yes
			(thermal_gap 0.5)
			(thermal_bridge_width 0.5)
			(island_removal_mode 0)
		)
		(polygon
			(pts
				(arc
					(start 353.438206 -276.708616)
					(mid 352.785426 -276.708616)
					(end 353.438206 -276.708616)
				)
			)
		)
	)
	(zone
		(layers "B.Cu" "In13.Cu" "In15.Cu")
		(hatch none 0.5)
		(connect_pads
			(clearance 0)
		)
		(min_thickness 0.25)
		(keepout
			(tracks not_allowed)
			(vias allowed)
			(pads allowed)
			(copperpour not_allowed)
			(footprints allowed)
		)
		(placement
			(enabled no)
			(sheetname "")
		)
		(fill yes
			(thermal_gap 0.5)
			(thermal_bridge_width 0.5)
			(island_removal_mode 0)
		)
		(polygon
			(pts
				(arc
					(start 24.773128 -4.962652)
					(mid 24.069548 -4.962652)
					(end 24.773128 -4.962652)
				)
			)
		)
	)
	(zone
		(layers "B.Cu" "In13.Cu" "In15.Cu")
		(hatch none 0.5)
		(connect_pads
			(clearance 0)
		)
		(min_thickness 0.25)
		(keepout
			(tracks not_allowed)
			(vias allowed)
			(pads allowed)
			(copperpour not_allowed)
			(footprints allowed)
		)
		(placement
			(enabled no)
			(sheetname "")
		)
		(fill yes
			(thermal_gap 0.5)
			(thermal_bridge_width 0.5)
			(island_removal_mode 0)
		)
		(polygon
			(pts
				(arc
					(start 203.297536 -237.266734)
					(mid 202.644756 -237.266734)
					(end 203.297536 -237.266734)
				)
			)
		)
	)
	(zone
		(layers "B.Cu" "In13.Cu" "In15.Cu")
		(hatch none 0.5)
		(connect_pads
			(clearance 0)
		)
		(min_thickness 0.25)
		(keepout
			(tracks not_allowed)
			(vias allowed)
			(pads allowed)
			(copperpour not_allowed)
			(footprints allowed)
		)
		(placement
			(enabled no)
			(sheetname "")
		)
		(fill yes
			(thermal_gap 0.5)
			(thermal_bridge_width 0.5)
			(island_removal_mode 0)
		)
		(polygon
			(pts
				(arc
					(start 371.184424 -227.64496)
					(mid 370.531644 -227.64496)
					(end 371.184424 -227.64496)
				)
			)
		)
	)
	(zone
		(layers "B.Cu" "In13.Cu" "In15.Cu")
		(hatch none 0.5)
		(connect_pads
			(clearance 0)
		)
		(min_thickness 0.25)
		(keepout
			(tracks not_allowed)
			(vias allowed)
			(pads allowed)
			(copperpour not_allowed)
			(footprints allowed)
		)
		(placement
			(enabled no)
			(sheetname "")
		)
		(fill yes
			(thermal_gap 0.5)
			(thermal_bridge_width 0.5)
			(island_removal_mode 0)
		)
		(polygon
			(pts
				(arc
					(start 125.233938 -276.708616)
					(mid 124.581158 -276.708616)
					(end 125.233938 -276.708616)
				)
			)
		)
	)
	(zone
		(layers "B.Cu" "In13.Cu" "In15.Cu")
		(hatch none 0.5)
		(connect_pads
			(clearance 0)
		)
		(min_thickness 0.25)
		(keepout
			(tracks not_allowed)
			(vias allowed)
			(pads allowed)
			(copperpour not_allowed)
			(footprints allowed)
		)
		(placement
			(enabled no)
			(sheetname "")
		)
		(fill yes
			(thermal_gap 0.5)
			(thermal_bridge_width 0.5)
			(island_removal_mode 0)
		)
		(polygon
			(pts
				(arc
					(start 355.317806 -276.708616)
					(mid 354.665026 -276.708616)
					(end 355.317806 -276.708616)
				)
			)
		)
	)
	(zone
		(layers "B.Cu" "In13.Cu" "In15.Cu")
		(hatch none 0.5)
		(connect_pads
			(clearance 0)
		)
		(min_thickness 0.25)
		(keepout
			(tracks not_allowed)
			(vias allowed)
			(pads allowed)
			(copperpour not_allowed)
			(footprints allowed)
		)
		(placement
			(enabled no)
			(sheetname "")
		)
		(fill yes
			(thermal_gap 0.5)
			(thermal_bridge_width 0.5)
			(island_removal_mode 0)
		)
		(polygon
			(pts
				(arc
					(start 203.297536 -288.266632)
					(mid 202.644756 -288.266632)
					(end 203.297536 -288.266632)
				)
			)
		)
	)
	(zone
		(layers "B.Cu" "In13.Cu" "In15.Cu")
		(hatch none 0.5)
		(connect_pads
			(clearance 0)
		)
		(min_thickness 0.25)
		(keepout
			(tracks not_allowed)
			(vias allowed)
			(pads allowed)
			(copperpour not_allowed)
			(footprints allowed)
		)
		(placement
			(enabled no)
			(sheetname "")
		)
		(fill yes
			(thermal_gap 0.5)
			(thermal_bridge_width 0.5)
			(island_removal_mode 0)
		)
		(polygon
			(pts
				(arc
					(start 337.461352 -279.964134)
					(mid 336.808572 -279.964134)
					(end 337.461352 -279.964134)
				)
			)
		)
	)
	(zone
		(layers "B.Cu" "In13.Cu" "In15.Cu")
		(hatch none 0.5)
		(connect_pads
			(clearance 0)
		)
		(min_thickness 0.25)
		(keepout
			(tracks not_allowed)
			(vias allowed)
			(pads allowed)
			(copperpour not_allowed)
			(footprints allowed)
		)
		(placement
			(enabled no)
			(sheetname "")
		)
		(fill yes
			(thermal_gap 0.5)
			(thermal_bridge_width 0.5)
			(island_removal_mode 0)
		)
		(polygon
			(pts
				(arc
					(start 455.337672 -300.166532)
					(mid 454.684892 -300.166532)
					(end 455.337672 -300.166532)
				)
			)
		)
	)
	(zone
		(layers "B.Cu" "In13.Cu" "In15.Cu")
		(hatch none 0.5)
		(connect_pads
			(clearance 0)
		)
		(min_thickness 0.25)
		(keepout
			(tracks not_allowed)
			(vias allowed)
			(pads allowed)
			(copperpour not_allowed)
			(footprints allowed)
		)
		(placement
			(enabled no)
			(sheetname "")
		)
		(fill yes
			(thermal_gap 0.5)
			(thermal_bridge_width 0.5)
			(island_removal_mode 0)
		)
		(polygon
			(pts
				(arc
					(start 455.337672 -248.31675)
					(mid 454.684892 -248.31675)
					(end 455.337672 -248.31675)
				)
			)
		)
	)
	(zone
		(layers "B.Cu" "In13.Cu" "In15.Cu")
		(hatch none 0.5)
		(connect_pads
			(clearance 0)
		)
		(min_thickness 0.25)
		(keepout
			(tracks not_allowed)
			(vias allowed)
			(pads allowed)
			(copperpour not_allowed)
			(footprints allowed)
		)
		(placement
			(enabled no)
			(sheetname "")
		)
		(fill yes
			(thermal_gap 0.5)
			(thermal_bridge_width 0.5)
			(island_removal_mode 0)
		)
		(polygon
			(pts
				(arc
					(start 364.605824 -221.133924)
					(mid 363.953044 -221.133924)
					(end 364.605824 -221.133924)
				)
			)
		)
	)
	(zone
		(layers "B.Cu" "In13.Cu" "In15.Cu")
		(hatch none 0.5)
		(connect_pads
			(clearance 0)
		)
		(min_thickness 0.25)
		(keepout
			(tracks not_allowed)
			(vias allowed)
			(pads allowed)
			(copperpour not_allowed)
			(footprints allowed)
		)
		(placement
			(enabled no)
			(sheetname "")
		)
		(fill yes
			(thermal_gap 0.5)
			(thermal_bridge_width 0.5)
			(island_removal_mode 0)
		)
		(polygon
			(pts
				(arc
					(start 269.155672 -227.066602)
					(mid 268.502892 -227.066602)
					(end 269.155672 -227.066602)
				)
			)
		)
	)
	(zone
		(layers "B.Cu" "In13.Cu" "In15.Cu")
		(hatch none 0.5)
		(connect_pads
			(clearance 0)
		)
		(min_thickness 0.25)
		(keepout
			(tracks not_allowed)
			(vias allowed)
			(pads allowed)
			(copperpour not_allowed)
			(footprints allowed)
		)
		(placement
			(enabled no)
			(sheetname "")
		)
		(fill yes
			(thermal_gap 0.5)
			(thermal_bridge_width 0.5)
			(island_removal_mode 0)
		)
		(polygon
			(pts
				(arc
					(start 17.115536 -271.266666)
					(mid 16.462756 -271.266666)
					(end 17.115536 -271.266666)
				)
			)
		)
	)
	(zone
		(layers "B.Cu" "In13.Cu" "In15.Cu")
		(hatch none 0.5)
		(connect_pads
			(clearance 0)
		)
		(min_thickness 0.25)
		(keepout
			(tracks not_allowed)
			(vias allowed)
			(pads allowed)
			(copperpour not_allowed)
			(footprints allowed)
		)
		(placement
			(enabled no)
			(sheetname "")
		)
		(fill yes
			(thermal_gap 0.5)
			(thermal_bridge_width 0.5)
			(island_removal_mode 0)
		)
		(polygon
			(pts
				(arc
					(start 51.394868 -403.883876)
					(mid 50.691288 -403.883876)
					(end 51.394868 -403.883876)
				)
			)
		)
	)
	(zone
		(layers "B.Cu" "In13.Cu" "In15.Cu")
		(hatch none 0.5)
		(connect_pads
			(clearance 0)
		)
		(min_thickness 0.25)
		(keepout
			(tracks not_allowed)
			(vias allowed)
			(pads allowed)
			(copperpour not_allowed)
			(footprints allowed)
		)
		(placement
			(enabled no)
			(sheetname "")
		)
		(fill yes
			(thermal_gap 0.5)
			(thermal_bridge_width 0.5)
			(island_removal_mode 0)
		)
		(polygon
			(pts
				(arc
					(start 203.297536 -230.466646)
					(mid 202.644756 -230.466646)
					(end 203.297536 -230.466646)
				)
			)
		)
	)
	(zone
		(layers "B.Cu" "In13.Cu" "In15.Cu")
		(hatch none 0.5)
		(connect_pads
			(clearance 0)
		)
		(min_thickness 0.25)
		(keepout
			(tracks not_allowed)
			(vias allowed)
			(pads allowed)
			(copperpour not_allowed)
			(footprints allowed)
		)
		(placement
			(enabled no)
			(sheetname "")
		)
		(fill yes
			(thermal_gap 0.5)
			(thermal_bridge_width 0.5)
			(island_removal_mode 0)
		)
		(polygon
			(pts
				(arc
					(start 100.799138 -273.453098)
					(mid 100.146358 -273.453098)
					(end 100.799138 -273.453098)
				)
			)
		)
	)
	(zone
		(layers "B.Cu" "In13.Cu" "In15.Cu")
		(hatch none 0.5)
		(connect_pads
			(clearance 0)
		)
		(min_thickness 0.25)
		(keepout
			(tracks not_allowed)
			(vias allowed)
			(pads allowed)
			(copperpour not_allowed)
			(footprints allowed)
		)
		(placement
			(enabled no)
			(sheetname "")
		)
		(fill yes
			(thermal_gap 0.5)
			(thermal_bridge_width 0.5)
			(island_removal_mode 0)
		)
		(polygon
			(pts
				(arc
					(start 93.750638 -282.405836)
					(mid 93.097858 -282.405836)
					(end 93.750638 -282.405836)
				)
			)
		)
	)
	(zone
		(layers "B.Cu" "In13.Cu" "In15.Cu")
		(hatch none 0.5)
		(connect_pads
			(clearance 0)
		)
		(min_thickness 0.25)
		(keepout
			(tracks not_allowed)
			(vias allowed)
			(pads allowed)
			(copperpour not_allowed)
			(footprints allowed)
		)
		(placement
			(enabled no)
			(sheetname "")
		)
		(fill yes
			(thermal_gap 0.5)
			(thermal_bridge_width 0.5)
			(island_removal_mode 0)
		)
		(polygon
			(pts
				(arc
					(start 451.237604 -295.916604)
					(mid 450.584824 -295.916604)
					(end 451.237604 -295.916604)
				)
			)
		)
	)
	(zone
		(layers "B.Cu" "In13.Cu" "In15.Cu")
		(hatch none 0.5)
		(connect_pads
			(clearance 0)
		)
		(min_thickness 0.25)
		(keepout
			(tracks not_allowed)
			(vias allowed)
			(pads allowed)
			(copperpour not_allowed)
			(footprints allowed)
		)
		(placement
			(enabled no)
			(sheetname "")
		)
		(fill yes
			(thermal_gap 0.5)
			(thermal_bridge_width 0.5)
			(island_removal_mode 0)
		)
		(polygon
			(pts
				(arc
					(start 105.498138 -283.219906)
					(mid 104.845358 -283.219906)
					(end 105.498138 -283.219906)
				)
			)
		)
	)
	(zone
		(layers "B.Cu" "In13.Cu" "In15.Cu")
		(hatch none 0.5)
		(connect_pads
			(clearance 0)
		)
		(min_thickness 0.25)
		(keepout
			(tracks not_allowed)
			(vias allowed)
			(pads allowed)
			(copperpour not_allowed)
			(footprints allowed)
		)
		(placement
			(enabled no)
			(sheetname "")
		)
		(fill yes
			(thermal_gap 0.5)
			(thermal_bridge_width 0.5)
			(island_removal_mode 0)
		)
		(polygon
			(pts
				(arc
					(start 367.425224 -221.133924)
					(mid 366.772444 -221.133924)
					(end 367.425224 -221.133924)
				)
			)
		)
	)
	(zone
		(layers "B.Cu" "In13.Cu" "In15.Cu")
		(hatch none 0.5)
		(connect_pads
			(clearance 0)
		)
		(min_thickness 0.25)
		(keepout
			(tracks not_allowed)
			(vias allowed)
			(pads allowed)
			(copperpour not_allowed)
			(footprints allowed)
		)
		(placement
			(enabled no)
			(sheetname "")
		)
		(fill yes
			(thermal_gap 0.5)
			(thermal_bridge_width 0.5)
			(island_removal_mode 0)
		)
		(polygon
			(pts
				(arc
					(start 130.560064 -403.883876)
					(mid 129.856484 -403.883876)
					(end 130.560064 -403.883876)
				)
			)
		)
	)
	(zone
		(layers "B.Cu" "In13.Cu" "In15.Cu")
		(hatch none 0.5)
		(connect_pads
			(clearance 0)
		)
		(min_thickness 0.25)
		(keepout
			(tracks not_allowed)
			(vias allowed)
			(pads allowed)
			(copperpour not_allowed)
			(footprints allowed)
		)
		(placement
			(enabled no)
			(sheetname "")
		)
		(fill yes
			(thermal_gap 0.5)
			(thermal_bridge_width 0.5)
			(island_removal_mode 0)
		)
		(polygon
			(pts
				(arc
					(start 17.115536 -224.516696)
					(mid 16.462756 -224.516696)
					(end 17.115536 -224.516696)
				)
			)
		)
	)
	(zone
		(layers "B.Cu" "In13.Cu" "In15.Cu")
		(hatch none 0.5)
		(connect_pads
			(clearance 0)
		)
		(min_thickness 0.25)
		(keepout
			(tracks not_allowed)
			(vias allowed)
			(pads allowed)
			(copperpour not_allowed)
			(footprints allowed)
		)
		(placement
			(enabled no)
			(sheetname "")
		)
		(fill yes
			(thermal_gap 0.5)
			(thermal_bridge_width 0.5)
			(island_removal_mode 0)
		)
		(polygon
			(pts
				(arc
					(start 392.154918 -427.089824)
					(mid 391.345166 -427.089824)
					(end 392.154918 -427.089824)
				)
			)
		)
	)
	(zone
		(layers "B.Cu" "In13.Cu" "In15.Cu")
		(hatch none 0.5)
		(connect_pads
			(clearance 0)
		)
		(min_thickness 0.25)
		(keepout
			(tracks not_allowed)
			(vias allowed)
			(pads allowed)
			(copperpour not_allowed)
			(footprints allowed)
		)
		(placement
			(enabled no)
			(sheetname "")
		)
		(fill yes
			(thermal_gap 0.5)
			(thermal_bridge_width 0.5)
			(island_removal_mode 0)
		)
		(polygon
			(pts
				(arc
					(start 100.328984 -282.405836)
					(mid 99.676204 -282.405836)
					(end 100.328984 -282.405836)
				)
			)
		)
	)
	(zone
		(layers "B.Cu" "In13.Cu" "In15.Cu")
		(hatch none 0.5)
		(connect_pads
			(clearance 0)
		)
		(min_thickness 0.25)
		(keepout
			(tracks not_allowed)
			(vias allowed)
			(pads allowed)
			(copperpour not_allowed)
			(footprints allowed)
		)
		(placement
			(enabled no)
			(sheetname "")
		)
		(fill yes
			(thermal_gap 0.5)
			(thermal_bridge_width 0.5)
			(island_removal_mode 0)
		)
		(polygon
			(pts
				(arc
					(start 99.279202 -243.108988)
					(mid 98.626422 -243.108988)
					(end 99.279202 -243.108988)
				)
			)
		)
	)
	(zone
		(layers "B.Cu" "In13.Cu" "In15.Cu")
		(hatch none 0.5)
		(connect_pads
			(clearance 0)
		)
		(min_thickness 0.25)
		(keepout
			(tracks not_allowed)
			(vias allowed)
			(pads allowed)
			(copperpour not_allowed)
			(footprints allowed)
		)
		(placement
			(enabled no)
			(sheetname "")
		)
		(fill yes
			(thermal_gap 0.5)
			(thermal_bridge_width 0.5)
			(island_removal_mode 0)
		)
		(polygon
			(pts
				(arc
					(start 388.154926 -427.089824)
					(mid 387.345174 -427.089824)
					(end 388.154926 -427.089824)
				)
			)
		)
	)
	(zone
		(layers "B.Cu" "In13.Cu" "In15.Cu")
		(hatch none 0.5)
		(connect_pads
			(clearance 0)
		)
		(min_thickness 0.25)
		(keepout
			(tracks not_allowed)
			(vias allowed)
			(pads allowed)
			(copperpour not_allowed)
			(footprints allowed)
		)
		(placement
			(enabled no)
			(sheetname "")
		)
		(fill yes
			(thermal_gap 0.5)
			(thermal_bridge_width 0.5)
			(island_removal_mode 0)
		)
		(polygon
			(pts
				(arc
					(start 130.154934 -427.289976)
					(mid 129.345182 -427.289976)
					(end 130.154934 -427.289976)
				)
			)
		)
	)
	(zone
		(layers "B.Cu" "In13.Cu" "In15.Cu")
		(hatch none 0.5)
		(connect_pads
			(clearance 0)
		)
		(min_thickness 0.25)
		(keepout
			(tracks not_allowed)
			(vias allowed)
			(pads allowed)
			(copperpour not_allowed)
			(footprints allowed)
		)
		(placement
			(enabled no)
			(sheetname "")
		)
		(fill yes
			(thermal_gap 0.5)
			(thermal_bridge_width 0.5)
			(island_removal_mode 0)
		)
		(polygon
			(pts
				(arc
					(start 348.629224 -234.15625)
					(mid 347.976444 -234.15625)
					(end 348.629224 -234.15625)
				)
			)
		)
	)
	(zone
		(layers "B.Cu" "In13.Cu" "In15.Cu")
		(hatch none 0.5)
		(connect_pads
			(clearance 0)
		)
		(min_thickness 0.25)
		(keepout
			(tracks not_allowed)
			(vias allowed)
			(pads allowed)
			(copperpour not_allowed)
			(footprints allowed)
		)
		(placement
			(enabled no)
			(sheetname "")
		)
		(fill yes
			(thermal_gap 0.5)
			(thermal_bridge_width 0.5)
			(island_removal_mode 0)
		)
		(polygon
			(pts
				(arc
					(start 98.809556 -240.667286)
					(mid 98.156776 -240.667286)
					(end 98.809556 -240.667286)
				)
			)
		)
	)
	(zone
		(layers "B.Cu" "In13.Cu" "In15.Cu")
		(hatch none 0.5)
		(connect_pads
			(clearance 0)
		)
		(min_thickness 0.25)
		(keepout
			(tracks not_allowed)
			(vias allowed)
			(pads allowed)
			(copperpour not_allowed)
			(footprints allowed)
		)
		(placement
			(enabled no)
			(sheetname "")
		)
		(fill yes
			(thermal_gap 0.5)
			(thermal_bridge_width 0.5)
			(island_removal_mode 0)
		)
		(polygon
			(pts
				(arc
					(start 73.054972 -430.689766)
					(mid 72.24522 -430.689766)
					(end 73.054972 -430.689766)
				)
			)
		)
	)
	(zone
		(layers "B.Cu" "In13.Cu" "In15.Cu")
		(hatch none 0.5)
		(connect_pads
			(clearance 0)
		)
		(min_thickness 0.25)
		(keepout
			(tracks not_allowed)
			(vias allowed)
			(pads allowed)
			(copperpour not_allowed)
			(footprints allowed)
		)
		(placement
			(enabled no)
			(sheetname "")
		)
		(fill yes
			(thermal_gap 0.5)
			(thermal_bridge_width 0.5)
			(island_removal_mode 0)
		)
		(polygon
			(pts
				(arc
					(start 372.124224 -242.294918)
					(mid 371.471444 -242.294918)
					(end 372.124224 -242.294918)
				)
			)
		)
	)
	(zone
		(layers "B.Cu" "In13.Cu" "In15.Cu")
		(hatch none 0.5)
		(connect_pads
			(clearance 0)
		)
		(min_thickness 0.25)
		(keepout
			(tracks not_allowed)
			(vias allowed)
			(pads allowed)
			(copperpour not_allowed)
			(footprints allowed)
		)
		(placement
			(enabled no)
			(sheetname "")
		)
		(fill yes
			(thermal_gap 0.5)
			(thermal_bridge_width 0.5)
			(island_removal_mode 0)
		)
		(polygon
			(pts
				(arc
					(start 371.65407 -226.831144)
					(mid 371.00129 -226.831144)
					(end 371.65407 -226.831144)
				)
			)
		)
	)
	(zone
		(layers "B.Cu" "In13.Cu" "In15.Cu")
		(hatch none 0.5)
		(connect_pads
			(clearance 0)
		)
		(min_thickness 0.25)
		(keepout
			(tracks not_allowed)
			(vias allowed)
			(pads allowed)
			(copperpour not_allowed)
			(footprints allowed)
		)
		(placement
			(enabled no)
			(sheetname "")
		)
		(fill yes
			(thermal_gap 0.5)
			(thermal_bridge_width 0.5)
			(island_removal_mode 0)
		)
		(polygon
			(pts
				(arc
					(start 42.837354 -398.771872)
					(mid 42.133774 -398.771872)
					(end 42.837354 -398.771872)
				)
			)
		)
	)
	(zone
		(layers "B.Cu" "In13.Cu" "In15.Cu")
		(hatch none 0.5)
		(connect_pads
			(clearance 0)
		)
		(min_thickness 0.25)
		(keepout
			(tracks not_allowed)
			(vias allowed)
			(pads allowed)
			(copperpour not_allowed)
			(footprints allowed)
		)
		(placement
			(enabled no)
			(sheetname "")
		)
		(fill yes
			(thermal_gap 0.5)
			(thermal_bridge_width 0.5)
			(island_removal_mode 0)
		)
		(polygon
			(pts
				(arc
					(start 125.123956 -245.55069)
					(mid 124.471176 -245.55069)
					(end 125.123956 -245.55069)
				)
			)
		)
	)
	(zone
		(layers "B.Cu" "In13.Cu" "In15.Cu")
		(hatch none 0.5)
		(connect_pads
			(clearance 0)
		)
		(min_thickness 0.25)
		(keepout
			(tracks not_allowed)
			(vias allowed)
			(pads allowed)
			(copperpour not_allowed)
			(footprints allowed)
		)
		(placement
			(enabled no)
			(sheetname "")
		)
		(fill yes
			(thermal_gap 0.5)
			(thermal_bridge_width 0.5)
			(island_removal_mode 0)
		)
		(polygon
			(pts
				(arc
					(start 100.219002 -231.714548)
					(mid 99.566222 -231.714548)
					(end 100.219002 -231.714548)
				)
			)
		)
	)
	(zone
		(layers "B.Cu" "In13.Cu" "In15.Cu")
		(hatch none 0.5)
		(connect_pads
			(clearance 0)
		)
		(min_thickness 0.25)
		(keepout
			(tracks not_allowed)
			(vias allowed)
			(pads allowed)
			(copperpour not_allowed)
			(footprints allowed)
		)
		(placement
			(enabled no)
			(sheetname "")
		)
		(fill yes
			(thermal_gap 0.5)
			(thermal_bridge_width 0.5)
			(island_removal_mode 0)
		)
		(polygon
			(pts
				(arc
					(start 31.973266 -4.962652)
					(mid 31.269686 -4.962652)
					(end 31.973266 -4.962652)
				)
			)
		)
	)
	(zone
		(layers "B.Cu" "In13.Cu" "In15.Cu")
		(hatch none 0.5)
		(connect_pads
			(clearance 0)
		)
		(min_thickness 0.25)
		(keepout
			(tracks not_allowed)
			(vias allowed)
			(pads allowed)
			(copperpour not_allowed)
			(footprints allowed)
		)
		(placement
			(enabled no)
			(sheetname "")
		)
		(fill yes
			(thermal_gap 0.5)
			(thermal_bridge_width 0.5)
			(island_removal_mode 0)
		)
		(polygon
			(pts
				(arc
					(start 125.593602 -231.714548)
					(mid 124.940822 -231.714548)
					(end 125.593602 -231.714548)
				)
			)
		)
	)
	(zone
		(layers "B.Cu" "In13.Cu" "In15.Cu")
		(hatch none 0.5)
		(connect_pads
			(clearance 0)
		)
		(min_thickness 0.25)
		(keepout
			(tracks not_allowed)
			(vias allowed)
			(pads allowed)
			(copperpour not_allowed)
			(footprints allowed)
		)
		(placement
			(enabled no)
			(sheetname "")
		)
		(fill yes
			(thermal_gap 0.5)
			(thermal_bridge_width 0.5)
			(island_removal_mode 0)
		)
		(polygon
			(pts
				(arc
					(start 69.05498 -430.689766)
					(mid 68.245228 -430.689766)
					(end 69.05498 -430.689766)
				)
			)
		)
	)
	(zone
		(layers "B.Cu" "In13.Cu" "In15.Cu")
		(hatch none 0.5)
		(connect_pads
			(clearance 0)
		)
		(min_thickness 0.25)
		(keepout
			(tracks not_allowed)
			(vias allowed)
			(pads allowed)
			(copperpour not_allowed)
			(footprints allowed)
		)
		(placement
			(enabled no)
			(sheetname "")
		)
		(fill yes
			(thermal_gap 0.5)
			(thermal_bridge_width 0.5)
			(island_removal_mode 0)
		)
		(polygon
			(pts
				(arc
					(start 373.173752 -257.175254)
					(mid 372.520972 -257.175254)
					(end 373.173752 -257.175254)
				)
			)
		)
	)
	(zone
		(layers "B.Cu" "In13.Cu" "In15.Cu")
		(hatch none 0.5)
		(connect_pads
			(clearance 0)
		)
		(min_thickness 0.25)
		(keepout
			(tracks not_allowed)
			(vias allowed)
			(pads allowed)
			(copperpour not_allowed)
			(footprints allowed)
		)
		(placement
			(enabled no)
			(sheetname "")
		)
		(fill yes
			(thermal_gap 0.5)
			(thermal_bridge_width 0.5)
			(island_removal_mode 0)
		)
		(polygon
			(pts
				(arc
					(start 451.237604 -215.166702)
					(mid 450.584824 -215.166702)
					(end 451.237604 -215.166702)
				)
			)
		)
	)
	(zone
		(layers "B.Cu" "In13.Cu" "In15.Cu")
		(hatch none 0.5)
		(connect_pads
			(clearance 0)
		)
		(min_thickness 0.25)
		(keepout
			(tracks not_allowed)
			(vias allowed)
			(pads allowed)
			(copperpour not_allowed)
			(footprints allowed)
		)
		(placement
			(enabled no)
			(sheetname "")
		)
		(fill yes
			(thermal_gap 0.5)
			(thermal_bridge_width 0.5)
			(island_removal_mode 0)
		)
		(polygon
			(pts
				(arc
					(start 265.055604 -204.116686)
					(mid 264.402824 -204.116686)
					(end 265.055604 -204.116686)
				)
			)
		)
	)
	(zone
		(layers "B.Cu" "In13.Cu" "In15.Cu")
		(hatch none 0.5)
		(connect_pads
			(clearance 0)
		)
		(min_thickness 0.25)
		(keepout
			(tracks not_allowed)
			(vias allowed)
			(pads allowed)
			(copperpour not_allowed)
			(footprints allowed)
		)
		(placement
			(enabled no)
			(sheetname "")
		)
		(fill yes
			(thermal_gap 0.5)
			(thermal_bridge_width 0.5)
			(island_removal_mode 0)
		)
		(polygon
			(pts
				(arc
					(start 373.064024 -229.272846)
					(mid 372.411244 -229.272846)
					(end 373.064024 -229.272846)
				)
			)
		)
	)
	(zone
		(layers "B.Cu" "In13.Cu" "In15.Cu")
		(hatch none 0.5)
		(connect_pads
			(clearance 0)
		)
		(min_thickness 0.25)
		(keepout
			(tracks not_allowed)
			(vias allowed)
			(pads allowed)
			(copperpour not_allowed)
			(footprints allowed)
		)
		(placement
			(enabled no)
			(sheetname "")
		)
		(fill yes
			(thermal_gap 0.5)
			(thermal_bridge_width 0.5)
			(island_removal_mode 0)
		)
		(polygon
			(pts
				(arc
					(start 123.354338 -275.08073)
					(mid 122.701558 -275.08073)
					(end 123.354338 -275.08073)
				)
			)
		)
	)
	(zone
		(layers "B.Cu" "In13.Cu" "In15.Cu")
		(hatch none 0.5)
		(connect_pads
			(clearance 0)
		)
		(min_thickness 0.25)
		(keepout
			(tracks not_allowed)
			(vias allowed)
			(pads allowed)
			(copperpour not_allowed)
			(footprints allowed)
		)
		(placement
			(enabled no)
			(sheetname "")
		)
		(fill yes
			(thermal_gap 0.5)
			(thermal_bridge_width 0.5)
			(island_removal_mode 0)
		)
		(polygon
			(pts
				(arc
					(start 203.297536 -249.166634)
					(mid 202.644756 -249.166634)
					(end 203.297536 -249.166634)
				)
			)
		)
	)
	(zone
		(layers "B.Cu" "In13.Cu" "In15.Cu")
		(hatch none 0.5)
		(connect_pads
			(clearance 0)
		)
		(min_thickness 0.25)
		(keepout
			(tracks not_allowed)
			(vias allowed)
			(pads allowed)
			(copperpour not_allowed)
			(footprints allowed)
		)
		(placement
			(enabled no)
			(sheetname "")
		)
		(fill yes
			(thermal_gap 0.5)
			(thermal_bridge_width 0.5)
			(island_removal_mode 0)
		)
		(polygon
			(pts
				(arc
					(start 124.294138 -266.941808)
					(mid 123.641358 -266.941808)
					(end 124.294138 -266.941808)
				)
			)
		)
	)
	(zone
		(layers "B.Cu" "In13.Cu" "In15.Cu")
		(hatch none 0.5)
		(connect_pads
			(clearance 0)
		)
		(min_thickness 0.25)
		(keepout
			(tracks not_allowed)
			(vias allowed)
			(pads allowed)
			(copperpour not_allowed)
			(footprints allowed)
		)
		(placement
			(enabled no)
			(sheetname "")
		)
		(fill yes
			(thermal_gap 0.5)
			(thermal_bridge_width 0.5)
			(island_removal_mode 0)
		)
		(polygon
			(pts
				(arc
					(start 13.671804 -260.21665)
					(mid 13.019024 -260.21665)
					(end 13.671804 -260.21665)
				)
			)
		)
	)
	(zone
		(layers "B.Cu" "In13.Cu" "In15.Cu")
		(hatch none 0.5)
		(connect_pads
			(clearance 0)
		)
		(min_thickness 0.25)
		(keepout
			(tracks not_allowed)
			(vias allowed)
			(pads allowed)
			(copperpour not_allowed)
			(footprints allowed)
		)
		(placement
			(enabled no)
			(sheetname "")
		)
		(fill yes
			(thermal_gap 0.5)
			(thermal_bridge_width 0.5)
			(island_removal_mode 0)
		)
		(polygon
			(pts
				(arc
					(start 401.1549 -428.28972)
					(mid 400.345148 -428.28972)
					(end 401.1549 -428.28972)
				)
			)
		)
	)
	(zone
		(layers "B.Cu" "In13.Cu" "In15.Cu")
		(hatch none 0.5)
		(connect_pads
			(clearance 0)
		)
		(min_thickness 0.25)
		(keepout
			(tracks not_allowed)
			(vias allowed)
			(pads allowed)
			(copperpour not_allowed)
			(footprints allowed)
		)
		(placement
			(enabled no)
			(sheetname "")
		)
		(fill yes
			(thermal_gap 0.5)
			(thermal_bridge_width 0.5)
			(island_removal_mode 0)
		)
		(polygon
			(pts
				(arc
					(start 265.055604 -222.816674)
					(mid 264.402824 -222.816674)
					(end 265.055604 -222.816674)
				)
			)
		)
	)
	(zone
		(layers "B.Cu" "In13.Cu" "In15.Cu")
		(hatch none 0.5)
		(connect_pads
			(clearance 0)
		)
		(min_thickness 0.25)
		(keepout
			(tracks not_allowed)
			(vias allowed)
			(pads allowed)
			(copperpour not_allowed)
			(footprints allowed)
		)
		(placement
			(enabled no)
			(sheetname "")
		)
		(fill yes
			(thermal_gap 0.5)
			(thermal_bridge_width 0.5)
			(island_removal_mode 0)
		)
		(polygon
			(pts
				(arc
					(start 21.215604 -225.36658)
					(mid 20.562824 -225.36658)
					(end 21.215604 -225.36658)
				)
			)
		)
	)
	(zone
		(layers "B.Cu" "In13.Cu" "In15.Cu")
		(hatch none 0.5)
		(connect_pads
			(clearance 0)
		)
		(min_thickness 0.25)
		(keepout
			(tracks not_allowed)
			(vias allowed)
			(pads allowed)
			(copperpour not_allowed)
			(footprints allowed)
		)
		(placement
			(enabled no)
			(sheetname "")
		)
		(fill yes
			(thermal_gap 0.5)
			(thermal_bridge_width 0.5)
			(island_removal_mode 0)
		)
		(polygon
			(pts
				(arc
					(start 17.115536 -289.966654)
					(mid 16.462756 -289.966654)
					(end 17.115536 -289.966654)
				)
			)
		)
	)
	(zone
		(layers "B.Cu" "In13.Cu" "In15.Cu")
		(hatch none 0.5)
		(connect_pads
			(clearance 0)
		)
		(min_thickness 0.25)
		(keepout
			(tracks not_allowed)
			(vias allowed)
			(pads allowed)
			(copperpour not_allowed)
			(footprints allowed)
		)
		(placement
			(enabled no)
			(sheetname "")
		)
		(fill yes
			(thermal_gap 0.5)
			(thermal_bridge_width 0.5)
			(island_removal_mode 0)
		)
		(polygon
			(pts
				(arc
					(start 17.115536 -267.866622)
					(mid 16.462756 -267.866622)
					(end 17.115536 -267.866622)
				)
			)
		)
	)
	(zone
		(layers "B.Cu" "In13.Cu" "In15.Cu")
		(hatch none 0.5)
		(connect_pads
			(clearance 0)
		)
		(min_thickness 0.25)
		(keepout
			(tracks not_allowed)
			(vias allowed)
			(pads allowed)
			(copperpour not_allowed)
			(footprints allowed)
		)
		(placement
			(enabled no)
			(sheetname "")
		)
		(fill yes
			(thermal_gap 0.5)
			(thermal_bridge_width 0.5)
			(island_removal_mode 0)
		)
		(polygon
			(pts
				(arc
					(start 132.15493 -427.089824)
					(mid 131.345178 -427.089824)
					(end 132.15493 -427.089824)
				)
			)
		)
	)
	(zone
		(layers "B.Cu" "In13.Cu" "In15.Cu")
		(hatch none 0.5)
		(connect_pads
			(clearance 0)
		)
		(min_thickness 0.25)
		(keepout
			(tracks not_allowed)
			(vias allowed)
			(pads allowed)
			(copperpour not_allowed)
			(footprints allowed)
		)
		(placement
			(enabled no)
			(sheetname "")
		)
		(fill yes
			(thermal_gap 0.5)
			(thermal_bridge_width 0.5)
			(island_removal_mode 0)
		)
		(polygon
			(pts
				(arc
					(start 352.968052 -275.8948)
					(mid 352.315272 -275.8948)
					(end 352.968052 -275.8948)
				)
			)
		)
	)
	(zone
		(layers "B.Cu" "In13.Cu" "In15.Cu")
		(hatch none 0.5)
		(connect_pads
			(clearance 0)
		)
		(min_thickness 0.25)
		(keepout
			(tracks not_allowed)
			(vias allowed)
			(pads allowed)
			(copperpour not_allowed)
			(footprints allowed)
		)
		(placement
			(enabled no)
			(sheetname "")
		)
		(fill yes
			(thermal_gap 0.5)
			(thermal_bridge_width 0.5)
			(island_removal_mode 0)
		)
		(polygon
			(pts
				(arc
					(start 371.65407 -231.714548)
					(mid 371.00129 -231.714548)
					(end 371.65407 -231.714548)
				)
			)
		)
	)
	(zone
		(layers "B.Cu" "In13.Cu" "In15.Cu")
		(hatch none 0.5)
		(connect_pads
			(clearance 0)
		)
		(min_thickness 0.25)
		(keepout
			(tracks not_allowed)
			(vias allowed)
			(pads allowed)
			(copperpour not_allowed)
			(footprints allowed)
		)
		(placement
			(enabled no)
			(sheetname "")
		)
		(fill yes
			(thermal_gap 0.5)
			(thermal_bridge_width 0.5)
			(island_removal_mode 0)
		)
		(polygon
			(pts
				(arc
					(start 455.337672 -292.51656)
					(mid 454.684892 -292.51656)
					(end 455.337672 -292.51656)
				)
			)
		)
	)
	(zone
		(layers "B.Cu" "In13.Cu" "In15.Cu")
		(hatch none 0.5)
		(connect_pads
			(clearance 0)
		)
		(min_thickness 0.25)
		(keepout
			(tracks not_allowed)
			(vias allowed)
			(pads allowed)
			(copperpour not_allowed)
			(footprints allowed)
		)
		(placement
			(enabled no)
			(sheetname "")
		)
		(fill yes
			(thermal_gap 0.5)
			(thermal_bridge_width 0.5)
			(island_removal_mode 0)
		)
		(polygon
			(pts
				(arc
					(start 21.215604 -295.06672)
					(mid 20.562824 -295.06672)
					(end 21.215604 -295.06672)
				)
			)
		)
	)
	(zone
		(layers "B.Cu" "In13.Cu" "In15.Cu")
		(hatch none 0.5)
		(connect_pads
			(clearance 0)
		)
		(min_thickness 0.25)
		(keepout
			(tracks not_allowed)
			(vias allowed)
			(pads allowed)
			(copperpour not_allowed)
			(footprints allowed)
		)
		(placement
			(enabled no)
			(sheetname "")
		)
		(fill yes
			(thermal_gap 0.5)
			(thermal_bridge_width 0.5)
			(island_removal_mode 0)
		)
		(polygon
			(pts
				(arc
					(start 203.297536 -295.916604)
					(mid 202.644756 -295.916604)
					(end 203.297536 -295.916604)
				)
			)
		)
	)
	(zone
		(layers "B.Cu" "In13.Cu" "In15.Cu")
		(hatch none 0.5)
		(connect_pads
			(clearance 0)
		)
		(min_thickness 0.25)
		(keepout
			(tracks not_allowed)
			(vias allowed)
			(pads allowed)
			(copperpour not_allowed)
			(footprints allowed)
		)
		(placement
			(enabled no)
			(sheetname "")
		)
		(fill yes
			(thermal_gap 0.5)
			(thermal_bridge_width 0.5)
			(island_removal_mode 0)
		)
		(polygon
			(pts
				(arc
					(start 155.154884 -427.289976)
					(mid 154.345132 -427.289976)
					(end 155.154884 -427.289976)
				)
			)
		)
	)
	(zone
		(layers "B.Cu" "In13.Cu" "In15.Cu")
		(hatch none 0.5)
		(connect_pads
			(clearance 0)
		)
		(min_thickness 0.25)
		(keepout
			(tracks not_allowed)
			(vias allowed)
			(pads allowed)
			(copperpour not_allowed)
			(footprints allowed)
		)
		(placement
			(enabled no)
			(sheetname "")
		)
		(fill yes
			(thermal_gap 0.5)
			(thermal_bridge_width 0.5)
			(island_removal_mode 0)
		)
		(polygon
			(pts
				(arc
					(start 207.397604 -223.666558)
					(mid 206.744824 -223.666558)
					(end 207.397604 -223.666558)
				)
			)
		)
	)
	(zone
		(layers "B.Cu" "In13.Cu" "In15.Cu")
		(hatch none 0.5)
		(connect_pads
			(clearance 0)
		)
		(min_thickness 0.25)
		(keepout
			(tracks not_allowed)
			(vias allowed)
			(pads allowed)
			(copperpour not_allowed)
			(footprints allowed)
		)
		(placement
			(enabled no)
			(sheetname "")
		)
		(fill yes
			(thermal_gap 0.5)
			(thermal_bridge_width 0.5)
			(island_removal_mode 0)
		)
		(polygon
			(pts
				(arc
					(start 203.297536 -241.516662)
					(mid 202.644756 -241.516662)
					(end 203.297536 -241.516662)
				)
			)
		)
	)
	(zone
		(layers "B.Cu" "In13.Cu" "In15.Cu")
		(hatch none 0.5)
		(connect_pads
			(clearance 0)
		)
		(min_thickness 0.25)
		(keepout
			(tracks not_allowed)
			(vias allowed)
			(pads allowed)
			(copperpour not_allowed)
			(footprints allowed)
		)
		(placement
			(enabled no)
			(sheetname "")
		)
		(fill yes
			(thermal_gap 0.5)
			(thermal_bridge_width 0.5)
			(island_removal_mode 0)
		)
		(polygon
			(pts
				(arc
					(start 371.294406 -270.19758)
					(mid 370.641626 -270.19758)
					(end 371.294406 -270.19758)
				)
			)
		)
	)
	(zone
		(layers "B.Cu" "In13.Cu" "In15.Cu")
		(hatch none 0.5)
		(connect_pads
			(clearance 0)
		)
		(min_thickness 0.25)
		(keepout
			(tracks not_allowed)
			(vias allowed)
			(pads allowed)
			(copperpour not_allowed)
			(footprints allowed)
		)
		(placement
			(enabled no)
			(sheetname "")
		)
		(fill yes
			(thermal_gap 0.5)
			(thermal_bridge_width 0.5)
			(island_removal_mode 0)
		)
		(polygon
			(pts
				(arc
					(start 123.244356 -227.64496)
					(mid 122.591576 -227.64496)
					(end 123.244356 -227.64496)
				)
			)
		)
	)
	(zone
		(layers "B.Cu" "In13.Cu" "In15.Cu")
		(hatch none 0.5)
		(connect_pads
			(clearance 0)
		)
		(min_thickness 0.25)
		(keepout
			(tracks not_allowed)
			(vias allowed)
			(pads allowed)
			(copperpour not_allowed)
			(footprints allowed)
		)
		(placement
			(enabled no)
			(sheetname "")
		)
		(fill yes
			(thermal_gap 0.5)
			(thermal_bridge_width 0.5)
			(island_removal_mode 0)
		)
		(polygon
			(pts
				(arc
					(start 455.337672 -298.466764)
					(mid 454.684892 -298.466764)
					(end 455.337672 -298.466764)
				)
			)
		)
	)
	(zone
		(layers "B.Cu" "In13.Cu" "In15.Cu")
		(hatch none 0.5)
		(connect_pads
			(clearance 0)
		)
		(min_thickness 0.25)
		(keepout
			(tracks not_allowed)
			(vias allowed)
			(pads allowed)
			(copperpour not_allowed)
			(footprints allowed)
		)
		(placement
			(enabled no)
			(sheetname "")
		)
		(fill yes
			(thermal_gap 0.5)
			(thermal_bridge_width 0.5)
			(island_removal_mode 0)
		)
		(polygon
			(pts
				(arc
					(start 63.054992 -430.889918)
					(mid 62.24524 -430.889918)
					(end 63.054992 -430.889918)
				)
			)
		)
	)
	(zone
		(layers "B.Cu" "In13.Cu" "In15.Cu")
		(hatch none 0.5)
		(connect_pads
			(clearance 0)
		)
		(min_thickness 0.25)
		(keepout
			(tracks not_allowed)
			(vias allowed)
			(pads allowed)
			(copperpour not_allowed)
			(footprints allowed)
		)
		(placement
			(enabled no)
			(sheetname "")
		)
		(fill yes
			(thermal_gap 0.5)
			(thermal_bridge_width 0.5)
			(island_removal_mode 0)
		)
		(polygon
			(pts
				(arc
					(start 125.593602 -243.108988)
					(mid 124.940822 -243.108988)
					(end 125.593602 -243.108988)
				)
			)
		)
	)
	(zone
		(layers "B.Cu" "In13.Cu" "In15.Cu")
		(hatch none 0.5)
		(connect_pads
			(clearance 0)
		)
		(min_thickness 0.25)
		(keepout
			(tracks not_allowed)
			(vias allowed)
			(pads allowed)
			(copperpour not_allowed)
			(footprints allowed)
		)
		(placement
			(enabled no)
			(sheetname "")
		)
		(fill yes
			(thermal_gap 0.5)
			(thermal_bridge_width 0.5)
			(island_removal_mode 0)
		)
		(polygon
			(pts
				(arc
					(start 373.53367 -231.714548)
					(mid 372.88089 -231.714548)
					(end 373.53367 -231.714548)
				)
			)
		)
	)
	(zone
		(layers "B.Cu" "In13.Cu" "In15.Cu")
		(hatch none 0.5)
		(connect_pads
			(clearance 0)
		)
		(min_thickness 0.25)
		(keepout
			(tracks not_allowed)
			(vias allowed)
			(pads allowed)
			(copperpour not_allowed)
			(footprints allowed)
		)
		(placement
			(enabled no)
			(sheetname "")
		)
		(fill yes
			(thermal_gap 0.5)
			(thermal_bridge_width 0.5)
			(island_removal_mode 0)
		)
		(polygon
			(pts
				(arc
					(start 98.449384 -272.639282)
					(mid 97.796604 -272.639282)
					(end 98.449384 -272.639282)
				)
			)
		)
	)
	(zone
		(layers "B.Cu" "In13.Cu" "In15.Cu")
		(hatch none 0.5)
		(connect_pads
			(clearance 0)
		)
		(min_thickness 0.25)
		(keepout
			(tracks not_allowed)
			(vias allowed)
			(pads allowed)
			(copperpour not_allowed)
			(footprints allowed)
		)
		(placement
			(enabled no)
			(sheetname "")
		)
		(fill yes
			(thermal_gap 0.5)
			(thermal_bridge_width 0.5)
			(island_removal_mode 0)
		)
		(polygon
			(pts
				(arc
					(start 340.237318 -410.030168)
					(mid 339.533738 -410.030168)
					(end 340.237318 -410.030168)
				)
			)
		)
	)
	(zone
		(layers "B.Cu" "In13.Cu" "In15.Cu")
		(hatch none 0.5)
		(connect_pads
			(clearance 0)
		)
		(min_thickness 0.25)
		(keepout
			(tracks not_allowed)
			(vias allowed)
			(pads allowed)
			(copperpour not_allowed)
			(footprints allowed)
		)
		(placement
			(enabled no)
			(sheetname "")
		)
		(fill yes
			(thermal_gap 0.5)
			(thermal_bridge_width 0.5)
			(island_removal_mode 0)
		)
		(polygon
			(pts
				(arc
					(start 345.809824 -247.178322)
					(mid 345.157044 -247.178322)
					(end 345.809824 -247.178322)
				)
			)
		)
	)
	(zone
		(layers "B.Cu" "In13.Cu" "In15.Cu")
		(hatch none 0.5)
		(connect_pads
			(clearance 0)
		)
		(min_thickness 0.25)
		(keepout
			(tracks not_allowed)
			(vias allowed)
			(pads allowed)
			(copperpour not_allowed)
			(footprints allowed)
		)
		(placement
			(enabled no)
			(sheetname "")
		)
		(fill yes
			(thermal_gap 0.5)
			(thermal_bridge_width 0.5)
			(island_removal_mode 0)
		)
		(polygon
			(pts
				(arc
					(start 425.859702 -6.713474)
					(mid 425.156122 -6.713474)
					(end 425.859702 -6.713474)
				)
			)
		)
	)
	(zone
		(layers "B.Cu" "In13.Cu" "In15.Cu")
		(hatch none 0.5)
		(connect_pads
			(clearance 0)
		)
		(min_thickness 0.25)
		(keepout
			(tracks not_allowed)
			(vias allowed)
			(pads allowed)
			(copperpour not_allowed)
			(footprints allowed)
		)
		(placement
			(enabled no)
			(sheetname "")
		)
		(fill yes
			(thermal_gap 0.5)
			(thermal_bridge_width 0.5)
			(island_removal_mode 0)
		)
		(polygon
			(pts
				(arc
					(start 348.739206 -278.336502)
					(mid 348.086426 -278.336502)
					(end 348.739206 -278.336502)
				)
			)
		)
	)
	(zone
		(layers "B.Cu" "In13.Cu" "In15.Cu")
		(hatch none 0.5)
		(connect_pads
			(clearance 0)
		)
		(min_thickness 0.25)
		(keepout
			(tracks not_allowed)
			(vias allowed)
			(pads allowed)
			(copperpour not_allowed)
			(footprints allowed)
		)
		(placement
			(enabled no)
			(sheetname "")
		)
		(fill yes
			(thermal_gap 0.5)
			(thermal_bridge_width 0.5)
			(island_removal_mode 0)
		)
		(polygon
			(pts
				(arc
					(start 100.219002 -233.34218)
					(mid 99.566222 -233.34218)
					(end 100.219002 -233.34218)
				)
			)
		)
	)
	(zone
		(layers "B.Cu" "In13.Cu" "In15.Cu")
		(hatch none 0.5)
		(connect_pads
			(clearance 0)
		)
		(min_thickness 0.25)
		(keepout
			(tracks not_allowed)
			(vias allowed)
			(pads allowed)
			(copperpour not_allowed)
			(footprints allowed)
		)
		(placement
			(enabled no)
			(sheetname "")
		)
		(fill yes
			(thermal_gap 0.5)
			(thermal_bridge_width 0.5)
			(island_removal_mode 0)
		)
		(polygon
			(pts
				(arc
					(start 265.055604 -233.86669)
					(mid 264.402824 -233.86669)
					(end 265.055604 -233.86669)
				)
			)
		)
	)
	(zone
		(layers "B.Cu" "In13.Cu" "In15.Cu")
		(hatch none 0.5)
		(connect_pads
			(clearance 0)
		)
		(min_thickness 0.25)
		(keepout
			(tracks not_allowed)
			(vias allowed)
			(pads allowed)
			(copperpour not_allowed)
			(footprints allowed)
		)
		(placement
			(enabled no)
			(sheetname "")
		)
		(fill yes
			(thermal_gap 0.5)
			(thermal_bridge_width 0.5)
			(island_removal_mode 0)
		)
		(polygon
			(pts
				(arc
					(start 372.124224 -230.900478)
					(mid 371.471444 -230.900478)
					(end 372.124224 -230.900478)
				)
			)
		)
	)
	(zone
		(layers "B.Cu" "In13.Cu" "In15.Cu")
		(hatch none 0.5)
		(connect_pads
			(clearance 0)
		)
		(min_thickness 0.25)
		(keepout
			(tracks not_allowed)
			(vias allowed)
			(pads allowed)
			(copperpour not_allowed)
			(footprints allowed)
		)
		(placement
			(enabled no)
			(sheetname "")
		)
		(fill yes
			(thermal_gap 0.5)
			(thermal_bridge_width 0.5)
			(island_removal_mode 0)
		)
		(polygon
			(pts
				(arc
					(start 203.297536 -239.81664)
					(mid 202.644756 -239.81664)
					(end 203.297536 -239.81664)
				)
			)
		)
	)
	(zone
		(layers "B.Cu" "In13.Cu" "In15.Cu")
		(hatch none 0.5)
		(connect_pads
			(clearance 0)
		)
		(min_thickness 0.25)
		(keepout
			(tracks not_allowed)
			(vias allowed)
			(pads allowed)
			(copperpour not_allowed)
			(footprints allowed)
		)
		(placement
			(enabled no)
			(sheetname "")
		)
		(fill yes
			(thermal_gap 0.5)
			(thermal_bridge_width 0.5)
			(island_removal_mode 0)
		)
		(polygon
			(pts
				(arc
					(start 356.61727 -221.94774)
					(mid 355.96449 -221.94774)
					(end 356.61727 -221.94774)
				)
			)
		)
	)
	(zone
		(layers "B.Cu" "In13.Cu" "In15.Cu")
		(hatch none 0.5)
		(connect_pads
			(clearance 0)
		)
		(min_thickness 0.25)
		(keepout
			(tracks not_allowed)
			(vias allowed)
			(pads allowed)
			(copperpour not_allowed)
			(footprints allowed)
		)
		(placement
			(enabled no)
			(sheetname "")
		)
		(fill yes
			(thermal_gap 0.5)
			(thermal_bridge_width 0.5)
			(island_removal_mode 0)
		)
		(polygon
			(pts
				(arc
					(start 78.054962 -430.689766)
					(mid 77.24521 -430.689766)
					(end 78.054962 -430.689766)
				)
			)
		)
	)
	(zone
		(layers "B.Cu" "In13.Cu" "In15.Cu")
		(hatch none 0.5)
		(connect_pads
			(clearance 0)
		)
		(min_thickness 0.25)
		(keepout
			(tracks not_allowed)
			(vias allowed)
			(pads allowed)
			(copperpour not_allowed)
			(footprints allowed)
		)
		(placement
			(enabled no)
			(sheetname "")
		)
		(fill yes
			(thermal_gap 0.5)
			(thermal_bridge_width 0.5)
			(island_removal_mode 0)
		)
		(polygon
			(pts
				(arc
					(start 82.054954 -431.889916)
					(mid 81.245202 -431.889916)
					(end 82.054954 -431.889916)
				)
			)
		)
	)
	(zone
		(layers "B.Cu" "In13.Cu" "In15.Cu")
		(hatch none 0.5)
		(connect_pads
			(clearance 0)
		)
		(min_thickness 0.25)
		(keepout
			(tracks not_allowed)
			(vias allowed)
			(pads allowed)
			(copperpour not_allowed)
			(footprints allowed)
		)
		(placement
			(enabled no)
			(sheetname "")
		)
		(fill yes
			(thermal_gap 0.5)
			(thermal_bridge_width 0.5)
			(island_removal_mode 0)
		)
		(polygon
			(pts
				(arc
					(start 345.449652 -280.778204)
					(mid 344.796872 -280.778204)
					(end 345.449652 -280.778204)
				)
			)
		)
	)
	(zone
		(layers "B.Cu" "In13.Cu" "In15.Cu")
		(hatch none 0.5)
		(connect_pads
			(clearance 0)
		)
		(min_thickness 0.25)
		(keepout
			(tracks not_allowed)
			(vias allowed)
			(pads allowed)
			(copperpour not_allowed)
			(footprints allowed)
		)
		(placement
			(enabled no)
			(sheetname "")
		)
		(fill yes
			(thermal_gap 0.5)
			(thermal_bridge_width 0.5)
			(island_removal_mode 0)
		)
		(polygon
			(pts
				(arc
					(start 41.94683 -4.962652)
					(mid 41.24325 -4.962652)
					(end 41.94683 -4.962652)
				)
			)
		)
	)
	(zone
		(layers "B.Cu" "In13.Cu" "In15.Cu")
		(hatch none 0.5)
		(connect_pads
			(clearance 0)
		)
		(min_thickness 0.25)
		(keepout
			(tracks not_allowed)
			(vias allowed)
			(pads allowed)
			(copperpour not_allowed)
			(footprints allowed)
		)
		(placement
			(enabled no)
			(sheetname "")
		)
		(fill yes
			(thermal_gap 0.5)
			(thermal_bridge_width 0.5)
			(island_removal_mode 0)
		)
		(polygon
			(pts
				(arc
					(start 123.714002 -226.831144)
					(mid 123.061222 -226.831144)
					(end 123.714002 -226.831144)
				)
			)
		)
	)
	(zone
		(layers "B.Cu" "In13.Cu" "In15.Cu")
		(hatch none 0.5)
		(connect_pads
			(clearance 0)
		)
		(min_thickness 0.25)
		(keepout
			(tracks not_allowed)
			(vias allowed)
			(pads allowed)
			(copperpour not_allowed)
			(footprints allowed)
		)
		(placement
			(enabled no)
			(sheetname "")
		)
		(fill yes
			(thermal_gap 0.5)
			(thermal_bridge_width 0.5)
			(island_removal_mode 0)
		)
		(polygon
			(pts
				(arc
					(start 346.859606 -266.941808)
					(mid 346.206826 -266.941808)
					(end 346.859606 -266.941808)
				)
			)
		)
	)
	(zone
		(layers "B.Cu" "In13.Cu" "In15.Cu")
		(hatch none 0.5)
		(connect_pads
			(clearance 0)
		)
		(min_thickness 0.25)
		(keepout
			(tracks not_allowed)
			(vias allowed)
			(pads allowed)
			(copperpour not_allowed)
			(footprints allowed)
		)
		(placement
			(enabled no)
			(sheetname "")
		)
		(fill yes
			(thermal_gap 0.5)
			(thermal_bridge_width 0.5)
			(island_removal_mode 0)
		)
		(polygon
			(pts
				(arc
					(start 417.72332 -403.883876)
					(mid 417.01974 -403.883876)
					(end 417.72332 -403.883876)
				)
			)
		)
	)
	(zone
		(layers "B.Cu" "In13.Cu" "In15.Cu")
		(hatch none 0.5)
		(connect_pads
			(clearance 0)
		)
		(min_thickness 0.25)
		(keepout
			(tracks not_allowed)
			(vias allowed)
			(pads allowed)
			(copperpour not_allowed)
			(footprints allowed)
		)
		(placement
			(enabled no)
			(sheetname "")
		)
		(fill yes
			(thermal_gap 0.5)
			(thermal_bridge_width 0.5)
			(island_removal_mode 0)
		)
		(polygon
			(pts
				(arc
					(start 17.115536 -303.566576)
					(mid 16.462756 -303.566576)
					(end 17.115536 -303.566576)
				)
			)
		)
	)
	(zone
		(layers "B.Cu" "In13.Cu" "In15.Cu")
		(hatch none 0.5)
		(connect_pads
			(clearance 0)
		)
		(min_thickness 0.25)
		(keepout
			(tracks not_allowed)
			(vias allowed)
			(pads allowed)
			(copperpour not_allowed)
			(footprints allowed)
		)
		(placement
			(enabled no)
			(sheetname "")
		)
		(fill yes
			(thermal_gap 0.5)
			(thermal_bridge_width 0.5)
			(island_removal_mode 0)
		)
		(polygon
			(pts
				(arc
					(start 269.155672 -199.866758)
					(mid 268.502892 -199.866758)
					(end 269.155672 -199.866758)
				)
			)
		)
	)
	(zone
		(layers "B.Cu" "In13.Cu" "In15.Cu")
		(hatch none 0.5)
		(connect_pads
			(clearance 0)
		)
		(min_thickness 0.25)
		(keepout
			(tracks not_allowed)
			(vias allowed)
			(pads allowed)
			(copperpour not_allowed)
			(footprints allowed)
		)
		(placement
			(enabled no)
			(sheetname "")
		)
		(fill yes
			(thermal_gap 0.5)
			(thermal_bridge_width 0.5)
			(island_removal_mode 0)
		)
		(polygon
			(pts
				(arc
					(start 351.088452 -275.8948)
					(mid 350.435672 -275.8948)
					(end 351.088452 -275.8948)
				)
			)
		)
	)
	(zone
		(layers "B.Cu" "In13.Cu" "In15.Cu")
		(hatch none 0.5)
		(connect_pads
			(clearance 0)
		)
		(min_thickness 0.25)
		(keepout
			(tracks not_allowed)
			(vias allowed)
			(pads allowed)
			(copperpour not_allowed)
			(footprints allowed)
		)
		(placement
			(enabled no)
			(sheetname "")
		)
		(fill yes
			(thermal_gap 0.5)
			(thermal_bridge_width 0.5)
			(island_removal_mode 0)
		)
		(polygon
			(pts
				(arc
					(start 347.329252 -264.50036)
					(mid 346.676472 -264.50036)
					(end 347.329252 -264.50036)
				)
			)
		)
	)
	(zone
		(layers "B.Cu" "In13.Cu" "In15.Cu")
		(hatch none 0.5)
		(connect_pads
			(clearance 0)
		)
		(min_thickness 0.25)
		(keepout
			(tracks not_allowed)
			(vias allowed)
			(pads allowed)
			(copperpour not_allowed)
			(footprints allowed)
		)
		(placement
			(enabled no)
			(sheetname "")
		)
		(fill yes
			(thermal_gap 0.5)
			(thermal_bridge_width 0.5)
			(island_removal_mode 0)
		)
		(polygon
			(pts
				(arc
					(start 21.215604 -240.666778)
					(mid 20.562824 -240.666778)
					(end 21.215604 -240.666778)
				)
			)
		)
	)
	(zone
		(layers "B.Cu" "In13.Cu" "In15.Cu")
		(hatch none 0.5)
		(connect_pads
			(clearance 0)
		)
		(min_thickness 0.25)
		(keepout
			(tracks not_allowed)
			(vias allowed)
			(pads allowed)
			(copperpour not_allowed)
			(footprints allowed)
		)
		(placement
			(enabled no)
			(sheetname "")
		)
		(fill yes
			(thermal_gap 0.5)
			(thermal_bridge_width 0.5)
			(island_removal_mode 0)
		)
		(polygon
			(pts
				(arc
					(start 347.329252 -256.361438)
					(mid 346.676472 -256.361438)
					(end 347.329252 -256.361438)
				)
			)
		)
	)
	(zone
		(layers "B.Cu" "In13.Cu" "In15.Cu")
		(hatch none 0.5)
		(connect_pads
			(clearance 0)
		)
		(min_thickness 0.25)
		(keepout
			(tracks not_allowed)
			(vias allowed)
			(pads allowed)
			(copperpour not_allowed)
			(footprints allowed)
		)
		(placement
			(enabled no)
			(sheetname "")
		)
		(fill yes
			(thermal_gap 0.5)
			(thermal_bridge_width 0.5)
			(island_removal_mode 0)
		)
		(polygon
			(pts
				(arc
					(start 100.799138 -266.941808)
					(mid 100.146358 -266.941808)
					(end 100.799138 -266.941808)
				)
			)
		)
	)
	(zone
		(layers "B.Cu" "In13.Cu" "In15.Cu")
		(hatch none 0.5)
		(connect_pads
			(clearance 0)
		)
		(min_thickness 0.25)
		(keepout
			(tracks not_allowed)
			(vias allowed)
			(pads allowed)
			(copperpour not_allowed)
			(footprints allowed)
		)
		(placement
			(enabled no)
			(sheetname "")
		)
		(fill yes
			(thermal_gap 0.5)
			(thermal_bridge_width 0.5)
			(island_removal_mode 0)
		)
		(polygon
			(pts
				(arc
					(start 89.017348 -403.883876)
					(mid 88.313768 -403.883876)
					(end 89.017348 -403.883876)
				)
			)
		)
	)
	(zone
		(layers "B.Cu" "In13.Cu" "In15.Cu")
		(hatch none 0.5)
		(connect_pads
			(clearance 0)
		)
		(min_thickness 0.25)
		(keepout
			(tracks not_allowed)
			(vias allowed)
			(pads allowed)
			(copperpour not_allowed)
			(footprints allowed)
		)
		(placement
			(enabled no)
			(sheetname "")
		)
		(fill yes
			(thermal_gap 0.5)
			(thermal_bridge_width 0.5)
			(island_removal_mode 0)
		)
		(polygon
			(pts
				(arc
					(start 318.794638 -410.030168)
					(mid 318.091058 -410.030168)
					(end 318.794638 -410.030168)
				)
			)
		)
	)
	(zone
		(layers "B.Cu" "In13.Cu" "In15.Cu")
		(hatch none 0.5)
		(connect_pads
			(clearance 0)
		)
		(min_thickness 0.25)
		(keepout
			(tracks not_allowed)
			(vias allowed)
			(pads allowed)
			(copperpour not_allowed)
			(footprints allowed)
		)
		(placement
			(enabled no)
			(sheetname "")
		)
		(fill yes
			(thermal_gap 0.5)
			(thermal_bridge_width 0.5)
			(island_removal_mode 0)
		)
		(polygon
			(pts
				(arc
					(start 157.15488 -428.28972)
					(mid 156.345128 -428.28972)
					(end 157.15488 -428.28972)
				)
			)
		)
	)
	(zone
		(layers "B.Cu" "In13.Cu" "In15.Cu")
		(hatch none 0.5)
		(connect_pads
			(clearance 0)
		)
		(min_thickness 0.25)
		(keepout
			(tracks not_allowed)
			(vias allowed)
			(pads allowed)
			(copperpour not_allowed)
			(footprints allowed)
		)
		(placement
			(enabled no)
			(sheetname "")
		)
		(fill yes
			(thermal_gap 0.5)
			(thermal_bridge_width 0.5)
			(island_removal_mode 0)
		)
		(polygon
			(pts
				(arc
					(start 17.115536 -306.96662)
					(mid 16.462756 -306.96662)
					(end 17.115536 -306.96662)
				)
			)
		)
	)
	(zone
		(layers "B.Cu" "In13.Cu" "In15.Cu")
		(hatch none 0.5)
		(connect_pads
			(clearance 0)
		)
		(min_thickness 0.25)
		(keepout
			(tracks not_allowed)
			(vias allowed)
			(pads allowed)
			(copperpour not_allowed)
			(footprints allowed)
		)
		(placement
			(enabled no)
			(sheetname "")
		)
		(fill yes
			(thermal_gap 0.5)
			(thermal_bridge_width 0.5)
			(island_removal_mode 0)
		)
		(polygon
			(pts
				(arc
					(start 356.727252 -277.522432)
					(mid 356.074472 -277.522432)
					(end 356.727252 -277.522432)
				)
			)
		)
	)
	(zone
		(layers "B.Cu" "In13.Cu" "In15.Cu")
		(hatch none 0.5)
		(connect_pads
			(clearance 0)
		)
		(min_thickness 0.25)
		(keepout
			(tracks not_allowed)
			(vias allowed)
			(pads allowed)
			(copperpour not_allowed)
			(footprints allowed)
		)
		(placement
			(enabled no)
			(sheetname "")
		)
		(fill yes
			(thermal_gap 0.5)
			(thermal_bridge_width 0.5)
			(island_removal_mode 0)
		)
		(polygon
			(pts
				(arc
					(start 451.237604 -264.466578)
					(mid 450.584824 -264.466578)
					(end 451.237604 -264.466578)
				)
			)
		)
	)
	(zone
		(layers "B.Cu" "In13.Cu" "In15.Cu")
		(hatch none 0.5)
		(connect_pads
			(clearance 0)
		)
		(min_thickness 0.25)
		(keepout
			(tracks not_allowed)
			(vias allowed)
			(pads allowed)
			(copperpour not_allowed)
			(footprints allowed)
		)
		(placement
			(enabled no)
			(sheetname "")
		)
		(fill yes
			(thermal_gap 0.5)
			(thermal_bridge_width 0.5)
			(island_removal_mode 0)
		)
		(polygon
			(pts
				(arc
					(start 166.455344 -403.883876)
					(mid 165.751764 -403.883876)
					(end 166.455344 -403.883876)
				)
			)
		)
	)
	(zone
		(layers "B.Cu" "In13.Cu" "In15.Cu")
		(hatch none 0.5)
		(connect_pads
			(clearance 0)
		)
		(min_thickness 0.25)
		(keepout
			(tracks not_allowed)
			(vias allowed)
			(pads allowed)
			(copperpour not_allowed)
			(footprints allowed)
		)
		(placement
			(enabled no)
			(sheetname "")
		)
		(fill yes
			(thermal_gap 0.5)
			(thermal_bridge_width 0.5)
			(island_removal_mode 0)
		)
		(polygon
			(pts
				(arc
					(start 22.968458 -6.724396)
					(mid 22.264878 -6.724396)
					(end 22.968458 -6.724396)
				)
			)
		)
	)
	(zone
		(layers "B.Cu" "In13.Cu" "In15.Cu")
		(hatch none 0.5)
		(connect_pads
			(clearance 0)
		)
		(min_thickness 0.25)
		(keepout
			(tracks not_allowed)
			(vias allowed)
			(pads allowed)
			(copperpour not_allowed)
			(footprints allowed)
		)
		(placement
			(enabled no)
			(sheetname "")
		)
		(fill yes
			(thermal_gap 0.5)
			(thermal_bridge_width 0.5)
			(island_removal_mode 0)
		)
		(polygon
			(pts
				(arc
					(start 269.155672 -225.36658)
					(mid 268.502892 -225.36658)
					(end 269.155672 -225.36658)
				)
			)
		)
	)
	(zone
		(layers "B.Cu" "In13.Cu" "In15.Cu")
		(hatch none 0.5)
		(connect_pads
			(clearance 0)
		)
		(min_thickness 0.25)
		(keepout
			(tracks not_allowed)
			(vias allowed)
			(pads allowed)
			(copperpour not_allowed)
			(footprints allowed)
		)
		(placement
			(enabled no)
			(sheetname "")
		)
		(fill yes
			(thermal_gap 0.5)
			(thermal_bridge_width 0.5)
			(island_removal_mode 0)
		)
		(polygon
			(pts
				(arc
					(start 325.054976 -431.889916)
					(mid 324.245224 -431.889916)
					(end 325.054976 -431.889916)
				)
			)
		)
	)
	(zone
		(layers "B.Cu" "In13.Cu" "In15.Cu")
		(hatch none 0.5)
		(connect_pads
			(clearance 0)
		)
		(min_thickness 0.25)
		(keepout
			(tracks not_allowed)
			(vias allowed)
			(pads allowed)
			(copperpour not_allowed)
			(footprints allowed)
		)
		(placement
			(enabled no)
			(sheetname "")
		)
		(fill yes
			(thermal_gap 0.5)
			(thermal_bridge_width 0.5)
			(island_removal_mode 0)
		)
		(polygon
			(pts
				(arc
					(start 106.797602 -221.94774)
					(mid 106.144822 -221.94774)
					(end 106.797602 -221.94774)
				)
			)
		)
	)
	(zone
		(layers "B.Cu" "In13.Cu" "In15.Cu")
		(hatch none 0.5)
		(connect_pads
			(clearance 0)
		)
		(min_thickness 0.25)
		(keepout
			(tracks not_allowed)
			(vias allowed)
			(pads allowed)
			(copperpour not_allowed)
			(footprints allowed)
		)
		(placement
			(enabled no)
			(sheetname "")
		)
		(fill yes
			(thermal_gap 0.5)
			(thermal_bridge_width 0.5)
			(island_removal_mode 0)
		)
		(polygon
			(pts
				(arc
					(start 100.219002 -244.73662)
					(mid 99.566222 -244.73662)
					(end 100.219002 -244.73662)
				)
			)
		)
	)
	(zone
		(layers "B.Cu" "In13.Cu" "In15.Cu")
		(hatch none 0.5)
		(connect_pads
			(clearance 0)
		)
		(min_thickness 0.25)
		(keepout
			(tracks not_allowed)
			(vias allowed)
			(pads allowed)
			(copperpour not_allowed)
			(footprints allowed)
		)
		(placement
			(enabled no)
			(sheetname "")
		)
		(fill yes
			(thermal_gap 0.5)
			(thermal_bridge_width 0.5)
			(island_removal_mode 0)
		)
		(polygon
			(pts
				(arc
					(start 265.055604 -215.166702)
					(mid 264.402824 -215.166702)
					(end 265.055604 -215.166702)
				)
			)
		)
	)
	(zone
		(layers "B.Cu" "In13.Cu" "In15.Cu")
		(hatch none 0.5)
		(connect_pads
			(clearance 0)
		)
		(min_thickness 0.25)
		(keepout
			(tracks not_allowed)
			(vias allowed)
			(pads allowed)
			(copperpour not_allowed)
			(footprints allowed)
		)
		(placement
			(enabled no)
			(sheetname "")
		)
		(fill yes
			(thermal_gap 0.5)
			(thermal_bridge_width 0.5)
			(island_removal_mode 0)
		)
		(polygon
			(pts
				(arc
					(start 451.237604 -271.266666)
					(mid 450.584824 -271.266666)
					(end 451.237604 -271.266666)
				)
			)
		)
	)
	(zone
		(layers "B.Cu" "In13.Cu" "In15.Cu")
		(hatch none 0.5)
		(connect_pads
			(clearance 0)
		)
		(min_thickness 0.25)
		(keepout
			(tracks not_allowed)
			(vias allowed)
			(pads allowed)
			(copperpour not_allowed)
			(footprints allowed)
		)
		(placement
			(enabled no)
			(sheetname "")
		)
		(fill yes
			(thermal_gap 0.5)
			(thermal_bridge_width 0.5)
			(island_removal_mode 0)
		)
		(polygon
			(pts
				(arc
					(start 207.397604 -261.916672)
					(mid 206.744824 -261.916672)
					(end 207.397604 -261.916672)
				)
			)
		)
	)
	(zone
		(layers "B.Cu" "In13.Cu" "In15.Cu")
		(hatch none 0.5)
		(connect_pads
			(clearance 0)
		)
		(min_thickness 0.25)
		(keepout
			(tracks not_allowed)
			(vias allowed)
			(pads allowed)
			(copperpour not_allowed)
			(footprints allowed)
		)
		(placement
			(enabled no)
			(sheetname "")
		)
		(fill yes
			(thermal_gap 0.5)
			(thermal_bridge_width 0.5)
			(island_removal_mode 0)
		)
		(polygon
			(pts
				(arc
					(start 101.158802 -249.620024)
					(mid 100.506022 -249.620024)
					(end 101.158802 -249.620024)
				)
			)
		)
	)
	(zone
		(layers "B.Cu" "In13.Cu" "In15.Cu")
		(hatch none 0.5)
		(connect_pads
			(clearance 0)
		)
		(min_thickness 0.25)
		(keepout
			(tracks not_allowed)
			(vias allowed)
			(pads allowed)
			(copperpour not_allowed)
			(footprints allowed)
		)
		(placement
			(enabled no)
			(sheetname "")
		)
		(fill yes
			(thermal_gap 0.5)
			(thermal_bridge_width 0.5)
			(island_removal_mode 0)
		)
		(polygon
			(pts
				(arc
					(start 347.21927 -230.086662)
					(mid 346.56649 -230.086662)
					(end 347.21927 -230.086662)
				)
			)
		)
	)
	(zone
		(layers "B.Cu" "In13.Cu" "In15.Cu")
		(hatch none 0.5)
		(connect_pads
			(clearance 0)
		)
		(min_thickness 0.25)
		(keepout
			(tracks not_allowed)
			(vias allowed)
			(pads allowed)
			(copperpour not_allowed)
			(footprints allowed)
		)
		(placement
			(enabled no)
			(sheetname "")
		)
		(fill yes
			(thermal_gap 0.5)
			(thermal_bridge_width 0.5)
			(island_removal_mode 0)
		)
		(polygon
			(pts
				(arc
					(start 100.219002 -247.992138)
					(mid 99.566222 -247.992138)
					(end 100.219002 -247.992138)
				)
			)
		)
	)
	(zone
		(layers "B.Cu" "In13.Cu" "In15.Cu")
		(hatch none 0.5)
		(connect_pads
			(clearance 0)
		)
		(min_thickness 0.25)
		(keepout
			(tracks not_allowed)
			(vias allowed)
			(pads allowed)
			(copperpour not_allowed)
			(footprints allowed)
		)
		(placement
			(enabled no)
			(sheetname "")
		)
		(fill yes
			(thermal_gap 0.5)
			(thermal_bridge_width 0.5)
			(island_removal_mode 0)
		)
		(polygon
			(pts
				(arc
					(start 17.115536 -284.016704)
					(mid 16.462756 -284.016704)
					(end 17.115536 -284.016704)
				)
			)
		)
	)
	(zone
		(layers "B.Cu" "In13.Cu" "In15.Cu")
		(hatch none 0.5)
		(connect_pads
			(clearance 0)
		)
		(min_thickness 0.25)
		(keepout
			(tracks not_allowed)
			(vias allowed)
			(pads allowed)
			(copperpour not_allowed)
			(footprints allowed)
		)
		(placement
			(enabled no)
			(sheetname "")
		)
		(fill yes
			(thermal_gap 0.5)
			(thermal_bridge_width 0.5)
			(island_removal_mode 0)
		)
		(polygon
			(pts
				(arc
					(start 364.13567 -221.94774)
					(mid 363.48289 -221.94774)
					(end 364.13567 -221.94774)
				)
			)
		)
	)
	(zone
		(layers "B.Cu" "In13.Cu" "In15.Cu")
		(hatch none 0.5)
		(connect_pads
			(clearance 0)
		)
		(min_thickness 0.25)
		(keepout
			(tracks not_allowed)
			(vias allowed)
			(pads allowed)
			(copperpour not_allowed)
			(footprints allowed)
		)
		(placement
			(enabled no)
			(sheetname "")
		)
		(fill yes
			(thermal_gap 0.5)
			(thermal_bridge_width 0.5)
			(island_removal_mode 0)
		)
		(polygon
			(pts
				(arc
					(start 99.389184 -279.150318)
					(mid 98.736404 -279.150318)
					(end 99.389184 -279.150318)
				)
			)
		)
	)
	(zone
		(layers "B.Cu" "In13.Cu" "In15.Cu")
		(hatch none 0.5)
		(connect_pads
			(clearance 0)
		)
		(min_thickness 0.25)
		(keepout
			(tracks not_allowed)
			(vias allowed)
			(pads allowed)
			(copperpour not_allowed)
			(footprints allowed)
		)
		(placement
			(enabled no)
			(sheetname "")
		)
		(fill yes
			(thermal_gap 0.5)
			(thermal_bridge_width 0.5)
			(island_removal_mode 0)
		)
		(polygon
			(pts
				(arc
					(start 265.055604 -237.266734)
					(mid 264.402824 -237.266734)
					(end 265.055604 -237.266734)
				)
			)
		)
	)
	(zone
		(layers "B.Cu" "In13.Cu" "In15.Cu")
		(hatch none 0.5)
		(connect_pads
			(clearance 0)
		)
		(min_thickness 0.25)
		(keepout
			(tracks not_allowed)
			(vias allowed)
			(pads allowed)
			(copperpour not_allowed)
			(footprints allowed)
		)
		(placement
			(enabled no)
			(sheetname "")
		)
		(fill yes
			(thermal_gap 0.5)
			(thermal_bridge_width 0.5)
			(island_removal_mode 0)
		)
		(polygon
			(pts
				(arc
					(start 142.813024 -403.883876)
					(mid 142.109444 -403.883876)
					(end 142.813024 -403.883876)
				)
			)
		)
	)
	(zone
		(layers "B.Cu" "In13.Cu" "In15.Cu")
		(hatch none 0.5)
		(connect_pads
			(clearance 0)
		)
		(min_thickness 0.25)
		(keepout
			(tracks not_allowed)
			(vias allowed)
			(pads allowed)
			(copperpour not_allowed)
			(footprints allowed)
		)
		(placement
			(enabled no)
			(sheetname "")
		)
		(fill yes
			(thermal_gap 0.5)
			(thermal_bridge_width 0.5)
			(island_removal_mode 0)
		)
		(polygon
			(pts
				(arc
					(start 309.604918 -410.030168)
					(mid 308.901338 -410.030168)
					(end 309.604918 -410.030168)
				)
			)
		)
	)
	(zone
		(layers "B.Cu" "In13.Cu" "In15.Cu")
		(hatch none 0.5)
		(connect_pads
			(clearance 0)
		)
		(min_thickness 0.25)
		(keepout
			(tracks not_allowed)
			(vias allowed)
			(pads allowed)
			(copperpour not_allowed)
			(footprints allowed)
		)
		(placement
			(enabled no)
			(sheetname "")
		)
		(fill yes
			(thermal_gap 0.5)
			(thermal_bridge_width 0.5)
			(island_removal_mode 0)
		)
		(polygon
			(pts
				(arc
					(start 455.337672 -263.616694)
					(mid 454.684892 -263.616694)
					(end 455.337672 -263.616694)
				)
			)
		)
	)
	(zone
		(layers "B.Cu" "In13.Cu" "In15.Cu")
		(hatch none 0.5)
		(connect_pads
			(clearance 0)
		)
		(min_thickness 0.25)
		(keepout
			(tracks not_allowed)
			(vias allowed)
			(pads allowed)
			(copperpour not_allowed)
			(footprints allowed)
		)
		(placement
			(enabled no)
			(sheetname "")
		)
		(fill yes
			(thermal_gap 0.5)
			(thermal_bridge_width 0.5)
			(island_removal_mode 0)
		)
		(polygon
			(pts
				(arc
					(start 269.155672 -278.066754)
					(mid 268.502892 -278.066754)
					(end 269.155672 -278.066754)
				)
			)
		)
	)
	(zone
		(layers "B.Cu" "In13.Cu" "In15.Cu")
		(hatch none 0.5)
		(connect_pads
			(clearance 0)
		)
		(min_thickness 0.25)
		(keepout
			(tracks not_allowed)
			(vias allowed)
			(pads allowed)
			(copperpour not_allowed)
			(footprints allowed)
		)
		(placement
			(enabled no)
			(sheetname "")
		)
		(fill yes
			(thermal_gap 0.5)
			(thermal_bridge_width 0.5)
			(island_removal_mode 0)
		)
		(polygon
			(pts
				(arc
					(start 124.184156 -243.922804)
					(mid 123.531376 -243.922804)
					(end 124.184156 -243.922804)
				)
			)
		)
	)
	(zone
		(layers "B.Cu" "In13.Cu" "In15.Cu")
		(hatch none 0.5)
		(connect_pads
			(clearance 0)
		)
		(min_thickness 0.25)
		(keepout
			(tracks not_allowed)
			(vias allowed)
			(pads allowed)
			(copperpour not_allowed)
			(footprints allowed)
		)
		(placement
			(enabled no)
			(sheetname "")
		)
		(fill yes
			(thermal_gap 0.5)
			(thermal_bridge_width 0.5)
			(island_removal_mode 0)
		)
		(polygon
			(pts
				(arc
					(start 21.215604 -304.416714)
					(mid 20.562824 -304.416714)
					(end 21.215604 -304.416714)
				)
			)
		)
	)
	(zone
		(layers "B.Cu" "In13.Cu" "In15.Cu")
		(hatch none 0.5)
		(connect_pads
			(clearance 0)
		)
		(min_thickness 0.25)
		(keepout
			(tracks not_allowed)
			(vias allowed)
			(pads allowed)
			(copperpour not_allowed)
			(footprints allowed)
		)
		(placement
			(enabled no)
			(sheetname "")
		)
		(fill yes
			(thermal_gap 0.5)
			(thermal_bridge_width 0.5)
			(island_removal_mode 0)
		)
		(polygon
			(pts
				(arc
					(start 124.184156 -239.0394)
					(mid 123.531376 -239.0394)
					(end 124.184156 -239.0394)
				)
			)
		)
	)
	(zone
		(layers "B.Cu" "In13.Cu" "In15.Cu")
		(hatch none 0.5)
		(connect_pads
			(clearance 0)
		)
		(min_thickness 0.25)
		(keepout
			(tracks not_allowed)
			(vias allowed)
			(pads allowed)
			(copperpour not_allowed)
			(footprints allowed)
		)
		(placement
			(enabled no)
			(sheetname "")
		)
		(fill yes
			(thermal_gap 0.5)
			(thermal_bridge_width 0.5)
			(island_removal_mode 0)
		)
		(polygon
			(pts
				(arc
					(start 265.055604 -230.466646)
					(mid 264.402824 -230.466646)
					(end 265.055604 -230.466646)
				)
			)
		)
	)
	(zone
		(layers "B.Cu" "In13.Cu" "In15.Cu")
		(hatch none 0.5)
		(connect_pads
			(clearance 0)
		)
		(min_thickness 0.25)
		(keepout
			(tracks not_allowed)
			(vias allowed)
			(pads allowed)
			(copperpour not_allowed)
			(footprints allowed)
		)
		(placement
			(enabled no)
			(sheetname "")
		)
		(fill yes
			(thermal_gap 0.5)
			(thermal_bridge_width 0.5)
			(island_removal_mode 0)
		)
		(polygon
			(pts
				(arc
					(start 455.337672 -260.21665)
					(mid 454.684892 -260.21665)
					(end 455.337672 -260.21665)
				)
			)
		)
	)
	(zone
		(layers "B.Cu" "In13.Cu" "In15.Cu")
		(hatch none 0.5)
		(connect_pads
			(clearance 0)
		)
		(min_thickness 0.25)
		(keepout
			(tracks not_allowed)
			(vias allowed)
			(pads allowed)
			(copperpour not_allowed)
			(footprints allowed)
		)
		(placement
			(enabled no)
			(sheetname "")
		)
		(fill yes
			(thermal_gap 0.5)
			(thermal_bridge_width 0.5)
			(island_removal_mode 0)
		)
		(polygon
			(pts
				(arc
					(start 135.822944 -403.883876)
					(mid 135.119364 -403.883876)
					(end 135.822944 -403.883876)
				)
			)
		)
	)
	(zone
		(layers "B.Cu" "In13.Cu" "In15.Cu")
		(hatch none 0.5)
		(connect_pads
			(clearance 0)
		)
		(min_thickness 0.25)
		(keepout
			(tracks not_allowed)
			(vias allowed)
			(pads allowed)
			(copperpour not_allowed)
			(footprints allowed)
		)
		(placement
			(enabled no)
			(sheetname "")
		)
		(fill yes
			(thermal_gap 0.5)
			(thermal_bridge_width 0.5)
			(island_removal_mode 0)
		)
		(polygon
			(pts
				(arc
					(start 353.438206 -275.08073)
					(mid 352.785426 -275.08073)
					(end 353.438206 -275.08073)
				)
			)
		)
	)
	(zone
		(layers "B.Cu" "In13.Cu" "In15.Cu")
		(hatch none 0.5)
		(connect_pads
			(clearance 0)
		)
		(min_thickness 0.25)
		(keepout
			(tracks not_allowed)
			(vias allowed)
			(pads allowed)
			(copperpour not_allowed)
			(footprints allowed)
		)
		(placement
			(enabled no)
			(sheetname "")
		)
		(fill yes
			(thermal_gap 0.5)
			(thermal_bridge_width 0.5)
			(island_removal_mode 0)
		)
		(polygon
			(pts
				(arc
					(start 265.055604 -249.166634)
					(mid 264.402824 -249.166634)
					(end 265.055604 -249.166634)
				)
			)
		)
	)
	(zone
		(layers "B.Cu" "In13.Cu" "In15.Cu")
		(hatch none 0.5)
		(connect_pads
			(clearance 0)
		)
		(min_thickness 0.25)
		(keepout
			(tracks not_allowed)
			(vias allowed)
			(pads allowed)
			(copperpour not_allowed)
			(footprints allowed)
		)
		(placement
			(enabled no)
			(sheetname "")
		)
		(fill yes
			(thermal_gap 0.5)
			(thermal_bridge_width 0.5)
			(island_removal_mode 0)
		)
		(polygon
			(pts
				(arc
					(start 343.570052 -280.778204)
					(mid 342.917272 -280.778204)
					(end 343.570052 -280.778204)
				)
			)
		)
	)
	(zone
		(layers "B.Cu" "In13.Cu" "In15.Cu")
		(hatch none 0.5)
		(connect_pads
			(clearance 0)
		)
		(min_thickness 0.25)
		(keepout
			(tracks not_allowed)
			(vias allowed)
			(pads allowed)
			(copperpour not_allowed)
			(footprints allowed)
		)
		(placement
			(enabled no)
			(sheetname "")
		)
		(fill yes
			(thermal_gap 0.5)
			(thermal_bridge_width 0.5)
			(island_removal_mode 0)
		)
		(polygon
			(pts
				(arc
					(start 346.749624 -239.0394)
					(mid 346.096844 -239.0394)
					(end 346.749624 -239.0394)
				)
			)
		)
	)
	(zone
		(layers "B.Cu" "In13.Cu" "In15.Cu")
		(hatch none 0.5)
		(connect_pads
			(clearance 0)
		)
		(min_thickness 0.25)
		(keepout
			(tracks not_allowed)
			(vias allowed)
			(pads allowed)
			(copperpour not_allowed)
			(footprints allowed)
		)
		(placement
			(enabled no)
			(sheetname "")
		)
		(fill yes
			(thermal_gap 0.5)
			(thermal_bridge_width 0.5)
			(island_removal_mode 0)
		)
		(polygon
			(pts
				(arc
					(start 372.234206 -258.80314)
					(mid 371.581426 -258.80314)
					(end 372.234206 -258.80314)
				)
			)
		)
	)
	(zone
		(layers "B.Cu" "In13.Cu" "In15.Cu")
		(hatch none 0.5)
		(connect_pads
			(clearance 0)
		)
		(min_thickness 0.25)
		(keepout
			(tracks not_allowed)
			(vias allowed)
			(pads allowed)
			(copperpour not_allowed)
			(footprints allowed)
		)
		(placement
			(enabled no)
			(sheetname "")
		)
		(fill yes
			(thermal_gap 0.5)
			(thermal_bridge_width 0.5)
			(island_removal_mode 0)
		)
		(polygon
			(pts
				(arc
					(start 347.219524 -247.992138)
					(mid 346.566744 -247.992138)
					(end 347.219524 -247.992138)
				)
			)
		)
	)
	(zone
		(layers "B.Cu" "In13.Cu" "In15.Cu")
		(hatch none 0.5)
		(connect_pads
			(clearance 0)
		)
		(min_thickness 0.25)
		(keepout
			(tracks not_allowed)
			(vias allowed)
			(pads allowed)
			(copperpour not_allowed)
			(footprints allowed)
		)
		(placement
			(enabled no)
			(sheetname "")
		)
		(fill yes
			(thermal_gap 0.5)
			(thermal_bridge_width 0.5)
			(island_removal_mode 0)
		)
		(polygon
			(pts
				(arc
					(start 347.21927 -243.108988)
					(mid 346.56649 -243.108988)
					(end 347.21927 -243.108988)
				)
			)
		)
	)
	(zone
		(layers "B.Cu" "In13.Cu" "In15.Cu")
		(hatch none 0.5)
		(connect_pads
			(clearance 0)
		)
		(min_thickness 0.25)
		(keepout
			(tracks not_allowed)
			(vias allowed)
			(pads allowed)
			(copperpour not_allowed)
			(footprints allowed)
		)
		(placement
			(enabled no)
			(sheetname "")
		)
		(fill yes
			(thermal_gap 0.5)
			(thermal_bridge_width 0.5)
			(island_removal_mode 0)
		)
		(polygon
			(pts
				(arc
					(start 348.269052 -275.8948)
					(mid 347.616272 -275.8948)
					(end 348.269052 -275.8948)
				)
			)
		)
	)
	(zone
		(layers "B.Cu" "In13.Cu" "In15.Cu")
		(hatch none 0.5)
		(connect_pads
			(clearance 0)
		)
		(min_thickness 0.25)
		(keepout
			(tracks not_allowed)
			(vias allowed)
			(pads allowed)
			(copperpour not_allowed)
			(footprints allowed)
		)
		(placement
			(enabled no)
			(sheetname "")
		)
		(fill yes
			(thermal_gap 0.5)
			(thermal_bridge_width 0.5)
			(island_removal_mode 0)
		)
		(polygon
			(pts
				(arc
					(start 372.124224 -232.528364)
					(mid 371.471444 -232.528364)
					(end 372.124224 -232.528364)
				)
			)
		)
	)
	(zone
		(layers "B.Cu" "In13.Cu" "In15.Cu")
		(hatch none 0.5)
		(connect_pads
			(clearance 0)
		)
		(min_thickness 0.25)
		(keepout
			(tracks not_allowed)
			(vias allowed)
			(pads allowed)
			(copperpour not_allowed)
			(footprints allowed)
		)
		(placement
			(enabled no)
			(sheetname "")
		)
		(fill yes
			(thermal_gap 0.5)
			(thermal_bridge_width 0.5)
			(island_removal_mode 0)
		)
		(polygon
			(pts
				(arc
					(start 124.184156 -237.411514)
					(mid 123.531376 -237.411514)
					(end 124.184156 -237.411514)
				)
			)
		)
	)
	(zone
		(layers "B.Cu" "In13.Cu" "In15.Cu")
		(hatch none 0.5)
		(connect_pads
			(clearance 0)
		)
		(min_thickness 0.25)
		(keepout
			(tracks not_allowed)
			(vias allowed)
			(pads allowed)
			(copperpour not_allowed)
			(footprints allowed)
		)
		(placement
			(enabled no)
			(sheetname "")
		)
		(fill yes
			(thermal_gap 0.5)
			(thermal_bridge_width 0.5)
			(island_removal_mode 0)
		)
		(polygon
			(pts
				(arc
					(start 126.173738 -275.08073)
					(mid 125.520958 -275.08073)
					(end 126.173738 -275.08073)
				)
			)
		)
	)
	(zone
		(layers "B.Cu" "In13.Cu" "In15.Cu")
		(hatch none 0.5)
		(connect_pads
			(clearance 0)
		)
		(min_thickness 0.25)
		(keepout
			(tracks not_allowed)
			(vias allowed)
			(pads allowed)
			(copperpour not_allowed)
			(footprints allowed)
		)
		(placement
			(enabled no)
			(sheetname "")
		)
		(fill yes
			(thermal_gap 0.5)
			(thermal_bridge_width 0.5)
			(island_removal_mode 0)
		)
		(polygon
			(pts
				(arc
					(start 346.054934 -430.689766)
					(mid 345.245182 -430.689766)
					(end 346.054934 -430.689766)
				)
			)
		)
	)
	(zone
		(layers "B.Cu" "In13.Cu" "In15.Cu")
		(hatch none 0.5)
		(connect_pads
			(clearance 0)
		)
		(min_thickness 0.25)
		(keepout
			(tracks not_allowed)
			(vias allowed)
			(pads allowed)
			(copperpour not_allowed)
			(footprints allowed)
		)
		(placement
			(enabled no)
			(sheetname "")
		)
		(fill yes
			(thermal_gap 0.5)
			(thermal_bridge_width 0.5)
			(island_removal_mode 0)
		)
		(polygon
			(pts
				(arc
					(start 125.123956 -232.528364)
					(mid 124.471176 -232.528364)
					(end 125.123956 -232.528364)
				)
			)
		)
	)
	(zone
		(layers "B.Cu" "In13.Cu" "In15.Cu")
		(hatch none 0.5)
		(connect_pads
			(clearance 0)
		)
		(min_thickness 0.25)
		(keepout
			(tracks not_allowed)
			(vias allowed)
			(pads allowed)
			(copperpour not_allowed)
			(footprints allowed)
		)
		(placement
			(enabled no)
			(sheetname "")
		)
		(fill yes
			(thermal_gap 0.5)
			(thermal_bridge_width 0.5)
			(island_removal_mode 0)
		)
		(polygon
			(pts
				(arc
					(start 324.057518 -410.030168)
					(mid 323.353938 -410.030168)
					(end 324.057518 -410.030168)
				)
			)
		)
	)
	(zone
		(layers "B.Cu" "In13.Cu" "In15.Cu")
		(hatch none 0.5)
		(connect_pads
			(clearance 0)
		)
		(min_thickness 0.25)
		(keepout
			(tracks not_allowed)
			(vias allowed)
			(pads allowed)
			(copperpour not_allowed)
			(footprints allowed)
		)
		(placement
			(enabled no)
			(sheetname "")
		)
		(fill yes
			(thermal_gap 0.5)
			(thermal_bridge_width 0.5)
			(island_removal_mode 0)
		)
		(polygon
			(pts
				(arc
					(start 207.397604 -217.716608)
					(mid 206.744824 -217.716608)
					(end 207.397604 -217.716608)
				)
			)
		)
	)
	(zone
		(layers "B.Cu" "In13.Cu" "In15.Cu")
		(hatch none 0.5)
		(connect_pads
			(clearance 0)
		)
		(min_thickness 0.25)
		(keepout
			(tracks not_allowed)
			(vias allowed)
			(pads allowed)
			(copperpour not_allowed)
			(footprints allowed)
		)
		(placement
			(enabled no)
			(sheetname "")
		)
		(fill yes
			(thermal_gap 0.5)
			(thermal_bridge_width 0.5)
			(island_removal_mode 0)
		)
		(polygon
			(pts
				(arc
					(start 337.461606 -281.59202)
					(mid 336.808826 -281.59202)
					(end 337.461606 -281.59202)
				)
			)
		)
	)
	(zone
		(layers "B.Cu" "In13.Cu" "In15.Cu")
		(hatch none 0.5)
		(connect_pads
			(clearance 0)
		)
		(min_thickness 0.25)
		(keepout
			(tracks not_allowed)
			(vias allowed)
			(pads allowed)
			(copperpour not_allowed)
			(footprints allowed)
		)
		(placement
			(enabled no)
			(sheetname "")
		)
		(fill yes
			(thermal_gap 0.5)
			(thermal_bridge_width 0.5)
			(island_removal_mode 0)
		)
		(polygon
			(pts
				(arc
					(start 17.115536 -221.116652)
					(mid 16.462756 -221.116652)
					(end 17.115536 -221.116652)
				)
			)
		)
	)
	(zone
		(layers "B.Cu" "In13.Cu" "In15.Cu")
		(hatch none 0.5)
		(connect_pads
			(clearance 0)
		)
		(min_thickness 0.25)
		(keepout
			(tracks not_allowed)
			(vias allowed)
			(pads allowed)
			(copperpour not_allowed)
			(footprints allowed)
		)
		(placement
			(enabled no)
			(sheetname "")
		)
		(fill yes
			(thermal_gap 0.5)
			(thermal_bridge_width 0.5)
			(island_removal_mode 0)
		)
		(polygon
			(pts
				(arc
					(start 265.055604 -219.41663)
					(mid 264.402824 -219.41663)
					(end 265.055604 -219.41663)
				)
			)
		)
	)
	(zone
		(layers "B.Cu" "In13.Cu" "In15.Cu")
		(hatch none 0.5)
		(connect_pads
			(clearance 0)
		)
		(min_thickness 0.25)
		(keepout
			(tracks not_allowed)
			(vias allowed)
			(pads allowed)
			(copperpour not_allowed)
			(footprints allowed)
		)
		(placement
			(enabled no)
			(sheetname "")
		)
		(fill yes
			(thermal_gap 0.5)
			(thermal_bridge_width 0.5)
			(island_removal_mode 0)
		)
		(polygon
			(pts
				(arc
					(start 75.900788 -403.883876)
					(mid 75.197208 -403.883876)
					(end 75.900788 -403.883876)
				)
			)
		)
	)
	(zone
		(layers "B.Cu" "In13.Cu" "In15.Cu")
		(hatch none 0.5)
		(connect_pads
			(clearance 0)
		)
		(min_thickness 0.25)
		(keepout
			(tracks not_allowed)
			(vias allowed)
			(pads allowed)
			(copperpour not_allowed)
			(footprints allowed)
		)
		(placement
			(enabled no)
			(sheetname "")
		)
		(fill yes
			(thermal_gap 0.5)
			(thermal_bridge_width 0.5)
			(island_removal_mode 0)
		)
		(polygon
			(pts
				(arc
					(start 21.215604 -272.116804)
					(mid 20.562824 -272.116804)
					(end 21.215604 -272.116804)
				)
			)
		)
	)
	(zone
		(layers "B.Cu" "In13.Cu" "In15.Cu")
		(hatch none 0.5)
		(connect_pads
			(clearance 0)
		)
		(min_thickness 0.25)
		(keepout
			(tracks not_allowed)
			(vias allowed)
			(pads allowed)
			(copperpour not_allowed)
			(footprints allowed)
		)
		(placement
			(enabled no)
			(sheetname "")
		)
		(fill yes
			(thermal_gap 0.5)
			(thermal_bridge_width 0.5)
			(island_removal_mode 0)
		)
		(polygon
			(pts
				(arc
					(start 269.155672 -214.316564)
					(mid 268.502892 -214.316564)
					(end 269.155672 -214.316564)
				)
			)
		)
	)
	(zone
		(layers "B.Cu" "In13.Cu" "In15.Cu")
		(hatch none 0.5)
		(connect_pads
			(clearance 0)
		)
		(min_thickness 0.25)
		(keepout
			(tracks not_allowed)
			(vias allowed)
			(pads allowed)
			(copperpour not_allowed)
			(footprints allowed)
		)
		(placement
			(enabled no)
			(sheetname "")
		)
		(fill yes
			(thermal_gap 0.5)
			(thermal_bridge_width 0.5)
			(island_removal_mode 0)
		)
		(polygon
			(pts
				(arc
					(start 347.329252 -272.639282)
					(mid 346.676472 -272.639282)
					(end 347.329252 -272.639282)
				)
			)
		)
	)
	(zone
		(layers "B.Cu" "In13.Cu" "In15.Cu")
		(hatch none 0.5)
		(connect_pads
			(clearance 0)
		)
		(min_thickness 0.25)
		(keepout
			(tracks not_allowed)
			(vias allowed)
			(pads allowed)
			(copperpour not_allowed)
			(footprints allowed)
		)
		(placement
			(enabled no)
			(sheetname "")
		)
		(fill yes
			(thermal_gap 0.5)
			(thermal_bridge_width 0.5)
			(island_removal_mode 0)
		)
		(polygon
			(pts
				(arc
					(start 451.237604 -241.516662)
					(mid 450.584824 -241.516662)
					(end 451.237604 -241.516662)
				)
			)
		)
	)
	(zone
		(layers "B.Cu" "In13.Cu" "In15.Cu")
		(hatch none 0.5)
		(connect_pads
			(clearance 0)
		)
		(min_thickness 0.25)
		(keepout
			(tracks not_allowed)
			(vias allowed)
			(pads allowed)
			(copperpour not_allowed)
			(footprints allowed)
		)
		(placement
			(enabled no)
			(sheetname "")
		)
		(fill yes
			(thermal_gap 0.5)
			(thermal_bridge_width 0.5)
			(island_removal_mode 0)
		)
		(polygon
			(pts
				(arc
					(start 94.280228 -403.883876)
					(mid 93.576648 -403.883876)
					(end 94.280228 -403.883876)
				)
			)
		)
	)
	(zone
		(layers "B.Cu" "In13.Cu" "In15.Cu")
		(hatch none 0.5)
		(connect_pads
			(clearance 0)
		)
		(min_thickness 0.25)
		(keepout
			(tracks not_allowed)
			(vias allowed)
			(pads allowed)
			(copperpour not_allowed)
			(footprints allowed)
		)
		(placement
			(enabled no)
			(sheetname "")
		)
		(fill yes
			(thermal_gap 0.5)
			(thermal_bridge_width 0.5)
			(island_removal_mode 0)
		)
		(polygon
			(pts
				(arc
					(start 405.154892 -427.089824)
					(mid 404.34514 -427.089824)
					(end 405.154892 -427.089824)
				)
			)
		)
	)
	(zone
		(layers "B.Cu" "In13.Cu" "In15.Cu")
		(hatch none 0.5)
		(connect_pads
			(clearance 0)
		)
		(min_thickness 0.25)
		(keepout
			(tracks not_allowed)
			(vias allowed)
			(pads allowed)
			(copperpour not_allowed)
			(footprints allowed)
		)
		(placement
			(enabled no)
			(sheetname "")
		)
		(fill yes
			(thermal_gap 0.5)
			(thermal_bridge_width 0.5)
			(island_removal_mode 0)
		)
		(polygon
			(pts
				(arc
					(start 371.764052 -259.616956)
					(mid 371.111272 -259.616956)
					(end 371.764052 -259.616956)
				)
			)
		)
	)
	(zone
		(layers "B.Cu" "In13.Cu" "In15.Cu")
		(hatch none 0.5)
		(connect_pads
			(clearance 0)
		)
		(min_thickness 0.25)
		(keepout
			(tracks not_allowed)
			(vias allowed)
			(pads allowed)
			(copperpour not_allowed)
			(footprints allowed)
		)
		(placement
			(enabled no)
			(sheetname "")
		)
		(fill yes
			(thermal_gap 0.5)
			(thermal_bridge_width 0.5)
			(island_removal_mode 0)
		)
		(polygon
			(pts
				(arc
					(start 348.269052 -261.244842)
					(mid 347.616272 -261.244842)
					(end 348.269052 -261.244842)
				)
			)
		)
	)
	(zone
		(layers "B.Cu" "In13.Cu" "In15.Cu")
		(hatch none 0.5)
		(connect_pads
			(clearance 0)
		)
		(min_thickness 0.25)
		(keepout
			(tracks not_allowed)
			(vias allowed)
			(pads allowed)
			(copperpour not_allowed)
			(footprints allowed)
		)
		(placement
			(enabled no)
			(sheetname "")
		)
		(fill yes
			(thermal_gap 0.5)
			(thermal_bridge_width 0.5)
			(island_removal_mode 0)
		)
		(polygon
			(pts
				(arc
					(start 123.714002 -233.34218)
					(mid 123.061222 -233.34218)
					(end 123.714002 -233.34218)
				)
			)
		)
	)
	(zone
		(layers "B.Cu" "In13.Cu" "In15.Cu")
		(hatch none 0.5)
		(connect_pads
			(clearance 0)
		)
		(min_thickness 0.25)
		(keepout
			(tracks not_allowed)
			(vias allowed)
			(pads allowed)
			(copperpour not_allowed)
			(footprints allowed)
		)
		(placement
			(enabled no)
			(sheetname "")
		)
		(fill yes
			(thermal_gap 0.5)
			(thermal_bridge_width 0.5)
			(island_removal_mode 0)
		)
		(polygon
			(pts
				(arc
					(start 124.294138 -263.686544)
					(mid 123.641358 -263.686544)
					(end 124.294138 -263.686544)
				)
			)
		)
	)
	(zone
		(layers "B.Cu" "In13.Cu" "In15.Cu")
		(hatch none 0.5)
		(connect_pads
			(clearance 0)
		)
		(min_thickness 0.25)
		(keepout
			(tracks not_allowed)
			(vias allowed)
			(pads allowed)
			(copperpour not_allowed)
			(footprints allowed)
		)
		(placement
			(enabled no)
			(sheetname "")
		)
		(fill yes
			(thermal_gap 0.5)
			(thermal_bridge_width 0.5)
			(island_removal_mode 0)
		)
		(polygon
			(pts
				(arc
					(start 91.400884 -283.219906)
					(mid 90.748104 -283.219906)
					(end 91.400884 -283.219906)
				)
			)
		)
	)
	(zone
		(layers "B.Cu" "In13.Cu" "In15.Cu")
		(hatch none 0.5)
		(connect_pads
			(clearance 0)
		)
		(min_thickness 0.25)
		(keepout
			(tracks not_allowed)
			(vias allowed)
			(pads allowed)
			(copperpour not_allowed)
			(footprints allowed)
		)
		(placement
			(enabled no)
			(sheetname "")
		)
		(fill yes
			(thermal_gap 0.5)
			(thermal_bridge_width 0.5)
			(island_removal_mode 0)
		)
		(polygon
			(pts
				(arc
					(start 348.15907 -238.225584)
					(mid 347.50629 -238.225584)
					(end 348.15907 -238.225584)
				)
			)
		)
	)
	(zone
		(layers "B.Cu" "In13.Cu" "In15.Cu")
		(hatch none 0.5)
		(connect_pads
			(clearance 0)
		)
		(min_thickness 0.25)
		(keepout
			(tracks not_allowed)
			(vias allowed)
			(pads allowed)
			(copperpour not_allowed)
			(footprints allowed)
		)
		(placement
			(enabled no)
			(sheetname "")
		)
		(fill yes
			(thermal_gap 0.5)
			(thermal_bridge_width 0.5)
			(island_removal_mode 0)
		)
		(polygon
			(pts
				(arc
					(start 99.389184 -264.50036)
					(mid 98.736404 -264.50036)
					(end 99.389184 -264.50036)
				)
			)
		)
	)
	(zone
		(layers "B.Cu" "In13.Cu" "In15.Cu")
		(hatch none 0.5)
		(connect_pads
			(clearance 0)
		)
		(min_thickness 0.25)
		(keepout
			(tracks not_allowed)
			(vias allowed)
			(pads allowed)
			(copperpour not_allowed)
			(footprints allowed)
		)
		(placement
			(enabled no)
			(sheetname "")
		)
		(fill yes
			(thermal_gap 0.5)
			(thermal_bridge_width 0.5)
			(island_removal_mode 0)
		)
		(polygon
			(pts
				(arc
					(start 80.054958 -430.889918)
					(mid 79.245206 -430.889918)
					(end 80.054958 -430.889918)
				)
			)
		)
	)
	(zone
		(layers "B.Cu" "In13.Cu" "In15.Cu")
		(hatch none 0.5)
		(connect_pads
			(clearance 0)
		)
		(min_thickness 0.25)
		(keepout
			(tracks not_allowed)
			(vias allowed)
			(pads allowed)
			(copperpour not_allowed)
			(footprints allowed)
		)
		(placement
			(enabled no)
			(sheetname "")
		)
		(fill yes
			(thermal_gap 0.5)
			(thermal_bridge_width 0.5)
			(island_removal_mode 0)
		)
		(polygon
			(pts
				(arc
					(start 207.397604 -238.966756)
					(mid 206.744824 -238.966756)
					(end 207.397604 -238.966756)
				)
			)
		)
	)
	(zone
		(layers "B.Cu" "In13.Cu" "In15.Cu")
		(hatch none 0.5)
		(connect_pads
			(clearance 0)
		)
		(min_thickness 0.25)
		(keepout
			(tracks not_allowed)
			(vias allowed)
			(pads allowed)
			(copperpour not_allowed)
			(footprints allowed)
		)
		(placement
			(enabled no)
			(sheetname "")
		)
		(fill yes
			(thermal_gap 0.5)
			(thermal_bridge_width 0.5)
			(island_removal_mode 0)
		)
		(polygon
			(pts
				(arc
					(start 451.237604 -259.366766)
					(mid 450.584824 -259.366766)
					(end 451.237604 -259.366766)
				)
			)
		)
	)
	(zone
		(layers "B.Cu" "In13.Cu" "In15.Cu")
		(hatch none 0.5)
		(connect_pads
			(clearance 0)
		)
		(min_thickness 0.25)
		(keepout
			(tracks not_allowed)
			(vias allowed)
			(pads allowed)
			(copperpour not_allowed)
			(footprints allowed)
		)
		(placement
			(enabled no)
			(sheetname "")
		)
		(fill yes
			(thermal_gap 0.5)
			(thermal_bridge_width 0.5)
			(island_removal_mode 0)
		)
		(polygon
			(pts
				(arc
					(start 382.154938 -426.089826)
					(mid 381.345186 -426.089826)
					(end 382.154938 -426.089826)
				)
			)
		)
	)
	(zone
		(layers "B.Cu" "In13.Cu" "In15.Cu")
		(hatch none 0.5)
		(connect_pads
			(clearance 0)
		)
		(min_thickness 0.25)
		(keepout
			(tracks not_allowed)
			(vias allowed)
			(pads allowed)
			(copperpour not_allowed)
			(footprints allowed)
		)
		(placement
			(enabled no)
			(sheetname "")
		)
		(fill yes
			(thermal_gap 0.5)
			(thermal_bridge_width 0.5)
			(island_removal_mode 0)
		)
		(polygon
			(pts
				(arc
					(start 17.115536 -241.516662)
					(mid 16.462756 -241.516662)
					(end 17.115536 -241.516662)
				)
			)
		)
	)
	(zone
		(layers "B.Cu" "In13.Cu" "In15.Cu")
		(hatch none 0.5)
		(connect_pads
			(clearance 0)
		)
		(min_thickness 0.25)
		(keepout
			(tracks not_allowed)
			(vias allowed)
			(pads allowed)
			(copperpour not_allowed)
			(footprints allowed)
		)
		(placement
			(enabled no)
			(sheetname "")
		)
		(fill yes
			(thermal_gap 0.5)
			(thermal_bridge_width 0.5)
			(island_removal_mode 0)
		)
		(polygon
			(pts
				(arc
					(start 203.297536 -266.1666)
					(mid 202.644756 -266.1666)
					(end 203.297536 -266.1666)
				)
			)
		)
	)
	(zone
		(layers "B.Cu" "In13.Cu" "In15.Cu")
		(hatch none 0.5)
		(connect_pads
			(clearance 0)
		)
		(min_thickness 0.25)
		(keepout
			(tracks not_allowed)
			(vias allowed)
			(pads allowed)
			(copperpour not_allowed)
			(footprints allowed)
		)
		(placement
			(enabled no)
			(sheetname "")
		)
		(fill yes
			(thermal_gap 0.5)
			(thermal_bridge_width 0.5)
			(island_removal_mode 0)
		)
		(polygon
			(pts
				(arc
					(start 265.055604 -202.416664)
					(mid 264.402824 -202.416664)
					(end 265.055604 -202.416664)
				)
			)
		)
	)
	(zone
		(layers "B.Cu" "In13.Cu" "In15.Cu")
		(hatch none 0.5)
		(connect_pads
			(clearance 0)
		)
		(min_thickness 0.25)
		(keepout
			(tracks not_allowed)
			(vias allowed)
			(pads allowed)
			(copperpour not_allowed)
			(footprints allowed)
		)
		(placement
			(enabled no)
			(sheetname "")
		)
		(fill yes
			(thermal_gap 0.5)
			(thermal_bridge_width 0.5)
			(island_removal_mode 0)
		)
		(polygon
			(pts
				(arc
					(start 455.337672 -274.66671)
					(mid 454.684892 -274.66671)
					(end 455.337672 -274.66671)
				)
			)
		)
	)
	(zone
		(layers "B.Cu" "In13.Cu" "In15.Cu")
		(hatch none 0.5)
		(connect_pads
			(clearance 0)
		)
		(min_thickness 0.25)
		(keepout
			(tracks not_allowed)
			(vias allowed)
			(pads allowed)
			(copperpour not_allowed)
			(footprints allowed)
		)
		(placement
			(enabled no)
			(sheetname "")
		)
		(fill yes
			(thermal_gap 0.5)
			(thermal_bridge_width 0.5)
			(island_removal_mode 0)
		)
		(polygon
			(pts
				(arc
					(start 451.237604 -305.266598)
					(mid 450.584824 -305.266598)
					(end 451.237604 -305.266598)
				)
			)
		)
	)
	(zone
		(layers "B.Cu" "In13.Cu" "In15.Cu")
		(hatch none 0.5)
		(connect_pads
			(clearance 0)
		)
		(min_thickness 0.25)
		(keepout
			(tracks not_allowed)
			(vias allowed)
			(pads allowed)
			(copperpour not_allowed)
			(footprints allowed)
		)
		(placement
			(enabled no)
			(sheetname "")
		)
		(fill yes
			(thermal_gap 0.5)
			(thermal_bridge_width 0.5)
			(island_removal_mode 0)
		)
		(polygon
			(pts
				(arc
					(start 373.064024 -230.900478)
					(mid 372.411244 -230.900478)
					(end 373.064024 -230.900478)
				)
			)
		)
	)
	(zone
		(layers "B.Cu" "In13.Cu" "In15.Cu")
		(hatch none 0.5)
		(connect_pads
			(clearance 0)
		)
		(min_thickness 0.25)
		(keepout
			(tracks not_allowed)
			(vias allowed)
			(pads allowed)
			(copperpour not_allowed)
			(footprints allowed)
		)
		(placement
			(enabled no)
			(sheetname "")
		)
		(fill yes
			(thermal_gap 0.5)
			(thermal_bridge_width 0.5)
			(island_removal_mode 0)
		)
		(polygon
			(pts
				(arc
					(start 100.689156 -239.0394)
					(mid 100.036376 -239.0394)
					(end 100.689156 -239.0394)
				)
			)
		)
	)
	(zone
		(layers "B.Cu" "In13.Cu" "In15.Cu")
		(hatch none 0.5)
		(connect_pads
			(clearance 0)
		)
		(min_thickness 0.25)
		(keepout
			(tracks not_allowed)
			(vias allowed)
			(pads allowed)
			(copperpour not_allowed)
			(footprints allowed)
		)
		(placement
			(enabled no)
			(sheetname "")
		)
		(fill yes
			(thermal_gap 0.5)
			(thermal_bridge_width 0.5)
			(island_removal_mode 0)
		)
		(polygon
			(pts
				(arc
					(start 455.337672 -284.016704)
					(mid 454.684892 -284.016704)
					(end 455.337672 -284.016704)
				)
			)
		)
	)
	(zone
		(layers "B.Cu" "In13.Cu" "In15.Cu")
		(hatch none 0.5)
		(connect_pads
			(clearance 0)
		)
		(min_thickness 0.25)
		(keepout
			(tracks not_allowed)
			(vias allowed)
			(pads allowed)
			(copperpour not_allowed)
			(footprints allowed)
		)
		(placement
			(enabled no)
			(sheetname "")
		)
		(fill yes
			(thermal_gap 0.5)
			(thermal_bridge_width 0.5)
			(island_removal_mode 0)
		)
		(polygon
			(pts
				(arc
					(start 351.558606 -275.08073)
					(mid 350.905826 -275.08073)
					(end 351.558606 -275.08073)
				)
			)
		)
	)
	(zone
		(layers "B.Cu" "In13.Cu" "In15.Cu")
		(hatch none 0.5)
		(connect_pads
			(clearance 0)
		)
		(min_thickness 0.25)
		(keepout
			(tracks not_allowed)
			(vias allowed)
			(pads allowed)
			(copperpour not_allowed)
			(footprints allowed)
		)
		(placement
			(enabled no)
			(sheetname "")
		)
		(fill yes
			(thermal_gap 0.5)
			(thermal_bridge_width 0.5)
			(island_removal_mode 0)
		)
		(polygon
			(pts
				(arc
					(start 27.432 -6.724396)
					(mid 26.72842 -6.724396)
					(end 27.432 -6.724396)
				)
			)
		)
	)
	(zone
		(layers "B.Cu" "In13.Cu" "In15.Cu")
		(hatch none 0.5)
		(connect_pads
			(clearance 0)
		)
		(min_thickness 0.25)
		(keepout
			(tracks not_allowed)
			(vias allowed)
			(pads allowed)
			(copperpour not_allowed)
			(footprints allowed)
		)
		(placement
			(enabled no)
			(sheetname "")
		)
		(fill yes
			(thermal_gap 0.5)
			(thermal_bridge_width 0.5)
			(island_removal_mode 0)
		)
		(polygon
			(pts
				(arc
					(start 455.337672 -296.766742)
					(mid 454.684892 -296.766742)
					(end 455.337672 -296.766742)
				)
			)
		)
	)
	(zone
		(layers "B.Cu" "In13.Cu" "In15.Cu")
		(hatch none 0.5)
		(connect_pads
			(clearance 0)
		)
		(min_thickness 0.25)
		(keepout
			(tracks not_allowed)
			(vias allowed)
			(pads allowed)
			(copperpour not_allowed)
			(footprints allowed)
		)
		(placement
			(enabled no)
			(sheetname "")
		)
		(fill yes
			(thermal_gap 0.5)
			(thermal_bridge_width 0.5)
			(island_removal_mode 0)
		)
		(polygon
			(pts
				(arc
					(start 346.389452 -267.755878)
					(mid 345.736672 -267.755878)
					(end 346.389452 -267.755878)
				)
			)
		)
	)
	(zone
		(layers "B.Cu" "In13.Cu" "In15.Cu")
		(hatch none 0.5)
		(connect_pads
			(clearance 0)
		)
		(min_thickness 0.25)
		(keepout
			(tracks not_allowed)
			(vias allowed)
			(pads allowed)
			(copperpour not_allowed)
			(footprints allowed)
		)
		(placement
			(enabled no)
			(sheetname "")
		)
		(fill yes
			(thermal_gap 0.5)
			(thermal_bridge_width 0.5)
			(island_removal_mode 0)
		)
		(polygon
			(pts
				(arc
					(start 21.215604 -199.866758)
					(mid 20.562824 -199.866758)
					(end 21.215604 -199.866758)
				)
			)
		)
	)
	(zone
		(layers "B.Cu" "In13.Cu" "In15.Cu")
		(hatch none 0.5)
		(connect_pads
			(clearance 0)
		)
		(min_thickness 0.25)
		(keepout
			(tracks not_allowed)
			(vias allowed)
			(pads allowed)
			(copperpour not_allowed)
			(footprints allowed)
		)
		(placement
			(enabled no)
			(sheetname "")
		)
		(fill yes
			(thermal_gap 0.5)
			(thermal_bridge_width 0.5)
			(island_removal_mode 0)
		)
		(polygon
			(pts
				(arc
					(start 411.15488 -426.089826)
					(mid 410.345128 -426.089826)
					(end 411.15488 -426.089826)
				)
			)
		)
	)
	(zone
		(layers "B.Cu" "In13.Cu" "In15.Cu")
		(hatch none 0.5)
		(connect_pads
			(clearance 0)
		)
		(min_thickness 0.25)
		(keepout
			(tracks not_allowed)
			(vias allowed)
			(pads allowed)
			(copperpour not_allowed)
			(footprints allowed)
		)
		(placement
			(enabled no)
			(sheetname "")
		)
		(fill yes
			(thermal_gap 0.5)
			(thermal_bridge_width 0.5)
			(island_removal_mode 0)
		)
		(polygon
			(pts
				(arc
					(start 124.184156 -240.667286)
					(mid 123.531376 -240.667286)
					(end 124.184156 -240.667286)
				)
			)
		)
	)
	(zone
		(layers "B.Cu" "In13.Cu" "In15.Cu")
		(hatch none 0.5)
		(connect_pads
			(clearance 0)
		)
		(min_thickness 0.25)
		(keepout
			(tracks not_allowed)
			(vias allowed)
			(pads allowed)
			(copperpour not_allowed)
			(footprints allowed)
		)
		(placement
			(enabled no)
			(sheetname "")
		)
		(fill yes
			(thermal_gap 0.5)
			(thermal_bridge_width 0.5)
			(island_removal_mode 0)
		)
		(polygon
			(pts
				(arc
					(start 455.337672 -278.066754)
					(mid 454.684892 -278.066754)
					(end 455.337672 -278.066754)
				)
			)
		)
	)
	(zone
		(layers "B.Cu" "In13.Cu" "In15.Cu")
		(hatch none 0.5)
		(connect_pads
			(clearance 0)
		)
		(min_thickness 0.25)
		(keepout
			(tracks not_allowed)
			(vias allowed)
			(pads allowed)
			(copperpour not_allowed)
			(footprints allowed)
		)
		(placement
			(enabled no)
			(sheetname "")
		)
		(fill yes
			(thermal_gap 0.5)
			(thermal_bridge_width 0.5)
			(island_removal_mode 0)
		)
		(polygon
			(pts
				(arc
					(start 355.67747 -220.319854)
					(mid 355.02469 -220.319854)
					(end 355.67747 -220.319854)
				)
			)
		)
	)
	(zone
		(layers "B.Cu" "In13.Cu" "In15.Cu")
		(hatch none 0.5)
		(connect_pads
			(clearance 0)
		)
		(min_thickness 0.25)
		(keepout
			(tracks not_allowed)
			(vias allowed)
			(pads allowed)
			(copperpour not_allowed)
			(footprints allowed)
		)
		(placement
			(enabled no)
			(sheetname "")
		)
		(fill yes
			(thermal_gap 0.5)
			(thermal_bridge_width 0.5)
			(island_removal_mode 0)
		)
		(polygon
			(pts
				(arc
					(start 373.53367 -238.225584)
					(mid 372.88089 -238.225584)
					(end 373.53367 -238.225584)
				)
			)
		)
	)
	(zone
		(layers "B.Cu" "In13.Cu" "In15.Cu")
		(hatch none 0.5)
		(connect_pads
			(clearance 0)
		)
		(min_thickness 0.25)
		(keepout
			(tracks not_allowed)
			(vias allowed)
			(pads allowed)
			(copperpour not_allowed)
			(footprints allowed)
		)
		(placement
			(enabled no)
			(sheetname "")
		)
		(fill yes
			(thermal_gap 0.5)
			(thermal_bridge_width 0.5)
			(island_removal_mode 0)
		)
		(polygon
			(pts
				(arc
					(start 371.65407 -238.225584)
					(mid 371.00129 -238.225584)
					(end 371.65407 -238.225584)
				)
			)
		)
	)
	(zone
		(layers "B.Cu" "In13.Cu" "In15.Cu")
		(hatch none 0.5)
		(connect_pads
			(clearance 0)
		)
		(min_thickness 0.25)
		(keepout
			(tracks not_allowed)
			(vias allowed)
			(pads allowed)
			(copperpour not_allowed)
			(footprints allowed)
		)
		(placement
			(enabled no)
			(sheetname "")
		)
		(fill yes
			(thermal_gap 0.5)
			(thermal_bridge_width 0.5)
			(island_removal_mode 0)
		)
		(polygon
			(pts
				(arc
					(start 121.370344 -403.883876)
					(mid 120.666764 -403.883876)
					(end 121.370344 -403.883876)
				)
			)
		)
	)
	(zone
		(layers "B.Cu" "In13.Cu" "In15.Cu")
		(hatch none 0.5)
		(connect_pads
			(clearance 0)
		)
		(min_thickness 0.25)
		(keepout
			(tracks not_allowed)
			(vias allowed)
			(pads allowed)
			(copperpour not_allowed)
			(footprints allowed)
		)
		(placement
			(enabled no)
			(sheetname "")
		)
		(fill yes
			(thermal_gap 0.5)
			(thermal_bridge_width 0.5)
			(island_removal_mode 0)
		)
		(polygon
			(pts
				(arc
					(start 203.297536 -235.566712)
					(mid 202.644756 -235.566712)
					(end 203.297536 -235.566712)
				)
			)
		)
	)
	(zone
		(layers "B.Cu" "In13.Cu" "In15.Cu")
		(hatch none 0.5)
		(connect_pads
			(clearance 0)
		)
		(min_thickness 0.25)
		(keepout
			(tracks not_allowed)
			(vias allowed)
			(pads allowed)
			(copperpour not_allowed)
			(footprints allowed)
		)
		(placement
			(enabled no)
			(sheetname "")
		)
		(fill yes
			(thermal_gap 0.5)
			(thermal_bridge_width 0.5)
			(island_removal_mode 0)
		)
		(polygon
			(pts
				(arc
					(start 17.115536 -264.466578)
					(mid 16.462756 -264.466578)
					(end 17.115536 -264.466578)
				)
			)
		)
	)
	(zone
		(layers "B.Cu" "In13.Cu" "In15.Cu")
		(hatch none 0.5)
		(connect_pads
			(clearance 0)
		)
		(min_thickness 0.25)
		(keepout
			(tracks not_allowed)
			(vias allowed)
			(pads allowed)
			(copperpour not_allowed)
			(footprints allowed)
		)
		(placement
			(enabled no)
			(sheetname "")
		)
		(fill yes
			(thermal_gap 0.5)
			(thermal_bridge_width 0.5)
			(island_removal_mode 0)
		)
		(polygon
			(pts
				(arc
					(start 207.397604 -216.016586)
					(mid 206.744824 -216.016586)
					(end 207.397604 -216.016586)
				)
			)
		)
	)
	(zone
		(layers "B.Cu" "In13.Cu" "In15.Cu")
		(hatch none 0.5)
		(connect_pads
			(clearance 0)
		)
		(min_thickness 0.25)
		(keepout
			(tracks not_allowed)
			(vias allowed)
			(pads allowed)
			(copperpour not_allowed)
			(footprints allowed)
		)
		(placement
			(enabled no)
			(sheetname "")
		)
		(fill yes
			(thermal_gap 0.5)
			(thermal_bridge_width 0.5)
			(island_removal_mode 0)
		)
		(polygon
			(pts
				(arc
					(start 203.297536 -198.166736)
					(mid 202.644756 -198.166736)
					(end 203.297536 -198.166736)
				)
			)
		)
	)
	(zone
		(layers "B.Cu" "In13.Cu" "In15.Cu")
		(hatch none 0.5)
		(connect_pads
			(clearance 0)
		)
		(min_thickness 0.25)
		(keepout
			(tracks not_allowed)
			(vias allowed)
			(pads allowed)
			(copperpour not_allowed)
			(footprints allowed)
		)
		(placement
			(enabled no)
			(sheetname "")
		)
		(fill yes
			(thermal_gap 0.5)
			(thermal_bridge_width 0.5)
			(island_removal_mode 0)
		)
		(polygon
			(pts
				(arc
					(start 348.739206 -257.175254)
					(mid 348.086426 -257.175254)
					(end 348.739206 -257.175254)
				)
			)
		)
	)
	(zone
		(layers "B.Cu" "In13.Cu" "In15.Cu")
		(hatch none 0.5)
		(connect_pads
			(clearance 0)
		)
		(min_thickness 0.25)
		(keepout
			(tracks not_allowed)
			(vias allowed)
			(pads allowed)
			(copperpour not_allowed)
			(footprints allowed)
		)
		(placement
			(enabled no)
			(sheetname "")
		)
		(fill yes
			(thermal_gap 0.5)
			(thermal_bridge_width 0.5)
			(island_removal_mode 0)
		)
		(polygon
			(pts
				(arc
					(start 105.967784 -282.405836)
					(mid 105.315004 -282.405836)
					(end 105.967784 -282.405836)
				)
			)
		)
	)
	(zone
		(layers "B.Cu" "In13.Cu" "In15.Cu")
		(hatch none 0.5)
		(connect_pads
			(clearance 0)
		)
		(min_thickness 0.25)
		(keepout
			(tracks not_allowed)
			(vias allowed)
			(pads allowed)
			(copperpour not_allowed)
			(footprints allowed)
		)
		(placement
			(enabled no)
			(sheetname "")
		)
		(fill yes
			(thermal_gap 0.5)
			(thermal_bridge_width 0.5)
			(island_removal_mode 0)
		)
		(polygon
			(pts
				(arc
					(start 207.397604 -274.66671)
					(mid 206.744824 -274.66671)
					(end 207.397604 -274.66671)
				)
			)
		)
	)
	(zone
		(layers "B.Cu" "In13.Cu" "In15.Cu")
		(hatch none 0.5)
		(connect_pads
			(clearance 0)
		)
		(min_thickness 0.25)
		(keepout
			(tracks not_allowed)
			(vias allowed)
			(pads allowed)
			(copperpour not_allowed)
			(footprints allowed)
		)
		(placement
			(enabled no)
			(sheetname "")
		)
		(fill yes
			(thermal_gap 0.5)
			(thermal_bridge_width 0.5)
			(island_removal_mode 0)
		)
		(polygon
			(pts
				(arc
					(start 98.809556 -248.806208)
					(mid 98.156776 -248.806208)
					(end 98.809556 -248.806208)
				)
			)
		)
	)
	(zone
		(layers "B.Cu" "In13.Cu" "In15.Cu")
		(hatch none 0.5)
		(connect_pads
			(clearance 0)
		)
		(min_thickness 0.25)
		(keepout
			(tracks not_allowed)
			(vias allowed)
			(pads allowed)
			(copperpour not_allowed)
			(footprints allowed)
		)
		(placement
			(enabled no)
			(sheetname "")
		)
		(fill yes
			(thermal_gap 0.5)
			(thermal_bridge_width 0.5)
			(island_removal_mode 0)
		)
		(polygon
			(pts
				(arc
					(start 123.714002 -246.364506)
					(mid 123.061222 -246.364506)
					(end 123.714002 -246.364506)
				)
			)
		)
	)
	(zone
		(layers "B.Cu" "In13.Cu" "In15.Cu")
		(hatch none 0.5)
		(connect_pads
			(clearance 0)
		)
		(min_thickness 0.25)
		(keepout
			(tracks not_allowed)
			(vias allowed)
			(pads allowed)
			(copperpour not_allowed)
			(footprints allowed)
		)
		(placement
			(enabled no)
			(sheetname "")
		)
		(fill yes
			(thermal_gap 0.5)
			(thermal_bridge_width 0.5)
			(island_removal_mode 0)
		)
		(polygon
			(pts
				(arc
					(start 348.15907 -230.086662)
					(mid 347.50629 -230.086662)
					(end 348.15907 -230.086662)
				)
			)
		)
	)
	(zone
		(layers "B.Cu" "In13.Cu" "In15.Cu")
		(hatch none 0.5)
		(connect_pads
			(clearance 0)
		)
		(min_thickness 0.25)
		(keepout
			(tracks not_allowed)
			(vias allowed)
			(pads allowed)
			(copperpour not_allowed)
			(footprints allowed)
		)
		(placement
			(enabled no)
			(sheetname "")
		)
		(fill yes
			(thermal_gap 0.5)
			(thermal_bridge_width 0.5)
			(island_removal_mode 0)
		)
		(polygon
			(pts
				(arc
					(start 265.055604 -282.316682)
					(mid 264.402824 -282.316682)
					(end 265.055604 -282.316682)
				)
			)
		)
	)
	(zone
		(layers "B.Cu" "In13.Cu" "In15.Cu")
		(hatch none 0.5)
		(connect_pads
			(clearance 0)
		)
		(min_thickness 0.25)
		(keepout
			(tracks not_allowed)
			(vias allowed)
			(pads allowed)
			(copperpour not_allowed)
			(footprints allowed)
		)
		(placement
			(enabled no)
			(sheetname "")
		)
		(fill yes
			(thermal_gap 0.5)
			(thermal_bridge_width 0.5)
			(island_removal_mode 0)
		)
		(polygon
			(pts
				(arc
					(start 348.269052 -269.38351)
					(mid 347.616272 -269.38351)
					(end 348.269052 -269.38351)
				)
			)
		)
	)
	(zone
		(layers "B.Cu" "In13.Cu" "In15.Cu")
		(hatch none 0.5)
		(connect_pads
			(clearance 0)
		)
		(min_thickness 0.25)
		(keepout
			(tracks not_allowed)
			(vias allowed)
			(pads allowed)
			(copperpour not_allowed)
			(footprints allowed)
		)
		(placement
			(enabled no)
			(sheetname "")
		)
		(fill yes
			(thermal_gap 0.5)
			(thermal_bridge_width 0.5)
			(island_removal_mode 0)
		)
		(polygon
			(pts
				(arc
					(start 101.738938 -283.219906)
					(mid 101.086158 -283.219906)
					(end 101.738938 -283.219906)
				)
			)
		)
	)
	(zone
		(layers "B.Cu" "In13.Cu" "In15.Cu")
		(hatch none 0.5)
		(connect_pads
			(clearance 0)
		)
		(min_thickness 0.25)
		(keepout
			(tracks not_allowed)
			(vias allowed)
			(pads allowed)
			(copperpour not_allowed)
			(footprints allowed)
		)
		(placement
			(enabled no)
			(sheetname "")
		)
		(fill yes
			(thermal_gap 0.5)
			(thermal_bridge_width 0.5)
			(island_removal_mode 0)
		)
		(polygon
			(pts
				(arc
					(start 21.215604 -284.016704)
					(mid 20.562824 -284.016704)
					(end 21.215604 -284.016704)
				)
			)
		)
	)
	(zone
		(layers "B.Cu" "In13.Cu" "In15.Cu")
		(hatch none 0.5)
		(connect_pads
			(clearance 0)
		)
		(min_thickness 0.25)
		(keepout
			(tracks not_allowed)
			(vias allowed)
			(pads allowed)
			(copperpour not_allowed)
			(footprints allowed)
		)
		(placement
			(enabled no)
			(sheetname "")
		)
		(fill yes
			(thermal_gap 0.5)
			(thermal_bridge_width 0.5)
			(island_removal_mode 0)
		)
		(polygon
			(pts
				(arc
					(start 17.115536 -266.1666)
					(mid 16.462756 -266.1666)
					(end 17.115536 -266.1666)
				)
			)
		)
	)
	(zone
		(layers "B.Cu" "In13.Cu" "In15.Cu")
		(hatch none 0.5)
		(connect_pads
			(clearance 0)
		)
		(min_thickness 0.25)
		(keepout
			(tracks not_allowed)
			(vias allowed)
			(pads allowed)
			(copperpour not_allowed)
			(footprints allowed)
		)
		(placement
			(enabled no)
			(sheetname "")
		)
		(fill yes
			(thermal_gap 0.5)
			(thermal_bridge_width 0.5)
			(island_removal_mode 0)
		)
		(polygon
			(pts
				(arc
					(start 374.113806 -270.19758)
					(mid 373.461026 -270.19758)
					(end 374.113806 -270.19758)
				)
			)
		)
	)
	(zone
		(layers "B.Cu" "In13.Cu" "In15.Cu")
		(hatch none 0.5)
		(connect_pads
			(clearance 0)
		)
		(min_thickness 0.25)
		(keepout
			(tracks not_allowed)
			(vias allowed)
			(pads allowed)
			(copperpour not_allowed)
			(footprints allowed)
		)
		(placement
			(enabled no)
			(sheetname "")
		)
		(fill yes
			(thermal_gap 0.5)
			(thermal_bridge_width 0.5)
			(island_removal_mode 0)
		)
		(polygon
			(pts
				(arc
					(start 314.867798 -410.030168)
					(mid 314.164218 -410.030168)
					(end 314.867798 -410.030168)
				)
			)
		)
	)
	(zone
		(layers "B.Cu" "In13.Cu" "In15.Cu")
		(hatch none 0.5)
		(connect_pads
			(clearance 0)
		)
		(min_thickness 0.25)
		(keepout
			(tracks not_allowed)
			(vias allowed)
			(pads allowed)
			(copperpour not_allowed)
			(footprints allowed)
		)
		(placement
			(enabled no)
			(sheetname "")
		)
		(fill yes
			(thermal_gap 0.5)
			(thermal_bridge_width 0.5)
			(island_removal_mode 0)
		)
		(polygon
			(pts
				(arc
					(start 373.53367 -226.831144)
					(mid 372.88089 -226.831144)
					(end 373.53367 -226.831144)
				)
			)
		)
	)
	(zone
		(layers "B.Cu" "In13.Cu" "In15.Cu")
		(hatch none 0.5)
		(connect_pads
			(clearance 0)
		)
		(min_thickness 0.25)
		(keepout
			(tracks not_allowed)
			(vias allowed)
			(pads allowed)
			(copperpour not_allowed)
			(footprints allowed)
		)
		(placement
			(enabled no)
			(sheetname "")
		)
		(fill yes
			(thermal_gap 0.5)
			(thermal_bridge_width 0.5)
			(island_removal_mode 0)
		)
		(polygon
			(pts
				(arc
					(start 265.055604 -277.216616)
					(mid 264.402824 -277.216616)
					(end 265.055604 -277.216616)
				)
			)
		)
	)
	(zone
		(layers "B.Cu" "In13.Cu" "In15.Cu")
		(hatch none 0.5)
		(connect_pads
			(clearance 0)
		)
		(min_thickness 0.25)
		(keepout
			(tracks not_allowed)
			(vias allowed)
			(pads allowed)
			(copperpour not_allowed)
			(footprints allowed)
		)
		(placement
			(enabled no)
			(sheetname "")
		)
		(fill yes
			(thermal_gap 0.5)
			(thermal_bridge_width 0.5)
			(island_removal_mode 0)
		)
		(polygon
			(pts
				(arc
					(start 95.143828 -403.883876)
					(mid 94.440248 -403.883876)
					(end 95.143828 -403.883876)
				)
			)
		)
	)
	(zone
		(layers "B.Cu" "In13.Cu" "In15.Cu")
		(hatch none 0.5)
		(connect_pads
			(clearance 0)
		)
		(min_thickness 0.25)
		(keepout
			(tracks not_allowed)
			(vias allowed)
			(pads allowed)
			(copperpour not_allowed)
			(footprints allowed)
		)
		(placement
			(enabled no)
			(sheetname "")
		)
		(fill yes
			(thermal_gap 0.5)
			(thermal_bridge_width 0.5)
			(island_removal_mode 0)
		)
		(polygon
			(pts
				(arc
					(start 455.337672 -301.866554)
					(mid 454.684892 -301.866554)
					(end 455.337672 -301.866554)
				)
			)
		)
	)
	(zone
		(layers "B.Cu" "In13.Cu" "In15.Cu")
		(hatch none 0.5)
		(connect_pads
			(clearance 0)
		)
		(min_thickness 0.25)
		(keepout
			(tracks not_allowed)
			(vias allowed)
			(pads allowed)
			(copperpour not_allowed)
			(footprints allowed)
		)
		(placement
			(enabled no)
			(sheetname "")
		)
		(fill yes
			(thermal_gap 0.5)
			(thermal_bridge_width 0.5)
			(island_removal_mode 0)
		)
		(polygon
			(pts
				(arc
					(start 99.279202 -233.34218)
					(mid 98.626422 -233.34218)
					(end 99.279202 -233.34218)
				)
			)
		)
	)
	(zone
		(layers "B.Cu" "In13.Cu" "In15.Cu")
		(hatch none 0.5)
		(connect_pads
			(clearance 0)
		)
		(min_thickness 0.25)
		(keepout
			(tracks not_allowed)
			(vias allowed)
			(pads allowed)
			(copperpour not_allowed)
			(footprints allowed)
		)
		(placement
			(enabled no)
			(sheetname "")
		)
		(fill yes
			(thermal_gap 0.5)
			(thermal_bridge_width 0.5)
			(island_removal_mode 0)
		)
		(polygon
			(pts
				(arc
					(start 45.546772 -4.962652)
					(mid 44.843192 -4.962652)
					(end 45.546772 -4.962652)
				)
			)
		)
	)
	(zone
		(layers "B.Cu" "In13.Cu" "In15.Cu")
		(hatch none 0.5)
		(connect_pads
			(clearance 0)
		)
		(min_thickness 0.25)
		(keepout
			(tracks not_allowed)
			(vias allowed)
			(pads allowed)
			(copperpour not_allowed)
			(footprints allowed)
		)
		(placement
			(enabled no)
			(sheetname "")
		)
		(fill yes
			(thermal_gap 0.5)
			(thermal_bridge_width 0.5)
			(island_removal_mode 0)
		)
		(polygon
			(pts
				(arc
					(start 345.500198 -410.030168)
					(mid 344.796618 -410.030168)
					(end 345.500198 -410.030168)
				)
			)
		)
	)
	(zone
		(layers "B.Cu" "In13.Cu" "In15.Cu")
		(hatch none 0.5)
		(connect_pads
			(clearance 0)
		)
		(min_thickness 0.25)
		(keepout
			(tracks not_allowed)
			(vias allowed)
			(pads allowed)
			(copperpour not_allowed)
			(footprints allowed)
		)
		(placement
			(enabled no)
			(sheetname "")
		)
		(fill yes
			(thermal_gap 0.5)
			(thermal_bridge_width 0.5)
			(island_removal_mode 0)
		)
		(polygon
			(pts
				(arc
					(start 269.155672 -284.016704)
					(mid 268.502892 -284.016704)
					(end 269.155672 -284.016704)
				)
			)
		)
	)
	(zone
		(layers "B.Cu" "In13.Cu" "In15.Cu")
		(hatch none 0.5)
		(connect_pads
			(clearance 0)
		)
		(min_thickness 0.25)
		(keepout
			(tracks not_allowed)
			(vias allowed)
			(pads allowed)
			(copperpour not_allowed)
			(footprints allowed)
		)
		(placement
			(enabled no)
			(sheetname "")
		)
		(fill yes
			(thermal_gap 0.5)
			(thermal_bridge_width 0.5)
			(island_removal_mode 0)
		)
		(polygon
			(pts
				(arc
					(start 99.389184 -277.522432)
					(mid 98.736404 -277.522432)
					(end 99.389184 -277.522432)
				)
			)
		)
	)
	(zone
		(layers "B.Cu" "In13.Cu" "In15.Cu")
		(hatch none 0.5)
		(connect_pads
			(clearance 0)
		)
		(min_thickness 0.25)
		(keepout
			(tracks not_allowed)
			(vias allowed)
			(pads allowed)
			(copperpour not_allowed)
			(footprints allowed)
		)
		(placement
			(enabled no)
			(sheetname "")
		)
		(fill yes
			(thermal_gap 0.5)
			(thermal_bridge_width 0.5)
			(island_removal_mode 0)
		)
		(polygon
			(pts
				(arc
					(start 109.147356 -221.133924)
					(mid 108.494576 -221.133924)
					(end 109.147356 -221.133924)
				)
			)
		)
	)
	(zone
		(layers "B.Cu" "In13.Cu" "In15.Cu")
		(hatch none 0.5)
		(connect_pads
			(clearance 0)
		)
		(min_thickness 0.25)
		(keepout
			(tracks not_allowed)
			(vias allowed)
			(pads allowed)
			(copperpour not_allowed)
			(footprints allowed)
		)
		(placement
			(enabled no)
			(sheetname "")
		)
		(fill yes
			(thermal_gap 0.5)
			(thermal_bridge_width 0.5)
			(island_removal_mode 0)
		)
		(polygon
			(pts
				(arc
					(start 269.155672 -231.316784)
					(mid 268.502892 -231.316784)
					(end 269.155672 -231.316784)
				)
			)
		)
	)
	(zone
		(layers "B.Cu" "In13.Cu" "In15.Cu")
		(hatch none 0.5)
		(connect_pads
			(clearance 0)
		)
		(min_thickness 0.25)
		(keepout
			(tracks not_allowed)
			(vias allowed)
			(pads allowed)
			(copperpour not_allowed)
			(footprints allowed)
		)
		(placement
			(enabled no)
			(sheetname "")
		)
		(fill yes
			(thermal_gap 0.5)
			(thermal_bridge_width 0.5)
			(island_removal_mode 0)
		)
		(polygon
			(pts
				(arc
					(start 78.964028 -403.883876)
					(mid 78.260448 -403.883876)
					(end 78.964028 -403.883876)
				)
			)
		)
	)
	(zone
		(layers "B.Cu" "In13.Cu" "In15.Cu")
		(hatch none 0.5)
		(connect_pads
			(clearance 0)
		)
		(min_thickness 0.25)
		(keepout
			(tracks not_allowed)
			(vias allowed)
			(pads allowed)
			(copperpour not_allowed)
			(footprints allowed)
		)
		(placement
			(enabled no)
			(sheetname "")
		)
		(fill yes
			(thermal_gap 0.5)
			(thermal_bridge_width 0.5)
			(island_removal_mode 0)
		)
		(polygon
			(pts
				(arc
					(start 100.219002 -234.970066)
					(mid 99.566222 -234.970066)
					(end 100.219002 -234.970066)
				)
			)
		)
	)
	(zone
		(layers "B.Cu" "In13.Cu" "In15.Cu")
		(hatch none 0.5)
		(connect_pads
			(clearance 0)
		)
		(min_thickness 0.25)
		(keepout
			(tracks not_allowed)
			(vias allowed)
			(pads allowed)
			(copperpour not_allowed)
			(footprints allowed)
		)
		(placement
			(enabled no)
			(sheetname "")
		)
		(fill yes
			(thermal_gap 0.5)
			(thermal_bridge_width 0.5)
			(island_removal_mode 0)
		)
		(polygon
			(pts
				(arc
					(start 61.054996 -430.689766)
					(mid 60.245244 -430.689766)
					(end 61.054996 -430.689766)
				)
			)
		)
	)
	(zone
		(layers "B.Cu" "In13.Cu" "In15.Cu")
		(hatch none 0.5)
		(connect_pads
			(clearance 0)
		)
		(min_thickness 0.25)
		(keepout
			(tracks not_allowed)
			(vias allowed)
			(pads allowed)
			(copperpour not_allowed)
			(footprints allowed)
		)
		(placement
			(enabled no)
			(sheetname "")
		)
		(fill yes
			(thermal_gap 0.5)
			(thermal_bridge_width 0.5)
			(island_removal_mode 0)
		)
		(polygon
			(pts
				(arc
					(start 99.279202 -231.714548)
					(mid 98.626422 -231.714548)
					(end 99.279202 -231.714548)
				)
			)
		)
	)
	(zone
		(layers "B.Cu" "In13.Cu" "In15.Cu")
		(hatch none 0.5)
		(connect_pads
			(clearance 0)
		)
		(min_thickness 0.25)
		(keepout
			(tracks not_allowed)
			(vias allowed)
			(pads allowed)
			(copperpour not_allowed)
			(footprints allowed)
		)
		(placement
			(enabled no)
			(sheetname "")
		)
		(fill yes
			(thermal_gap 0.5)
			(thermal_bridge_width 0.5)
			(island_removal_mode 0)
		)
		(polygon
			(pts
				(arc
					(start 335.112106 -282.405836)
					(mid 334.459326 -282.405836)
					(end 335.112106 -282.405836)
				)
			)
		)
	)
	(zone
		(layers "B.Cu" "In13.Cu" "In15.Cu")
		(hatch none 0.5)
		(connect_pads
			(clearance 0)
		)
		(min_thickness 0.25)
		(keepout
			(tracks not_allowed)
			(vias allowed)
			(pads allowed)
			(copperpour not_allowed)
			(footprints allowed)
		)
		(placement
			(enabled no)
			(sheetname "")
		)
		(fill yes
			(thermal_gap 0.5)
			(thermal_bridge_width 0.5)
			(island_removal_mode 0)
		)
		(polygon
			(pts
				(arc
					(start 455.337672 -218.566746)
					(mid 454.684892 -218.566746)
					(end 455.337672 -218.566746)
				)
			)
		)
	)
	(zone
		(layers "B.Cu" "In13.Cu" "In15.Cu")
		(hatch none 0.5)
		(connect_pads
			(clearance 0)
		)
		(min_thickness 0.25)
		(keepout
			(tracks not_allowed)
			(vias allowed)
			(pads allowed)
			(copperpour not_allowed)
			(footprints allowed)
		)
		(placement
			(enabled no)
			(sheetname "")
		)
		(fill yes
			(thermal_gap 0.5)
			(thermal_bridge_width 0.5)
			(island_removal_mode 0)
		)
		(polygon
			(pts
				(arc
					(start 98.919538 -276.708616)
					(mid 98.266758 -276.708616)
					(end 98.919538 -276.708616)
				)
			)
		)
	)
	(zone
		(layers "B.Cu" "In13.Cu" "In15.Cu")
		(hatch none 0.5)
		(connect_pads
			(clearance 0)
		)
		(min_thickness 0.25)
		(keepout
			(tracks not_allowed)
			(vias allowed)
			(pads allowed)
			(copperpour not_allowed)
			(footprints allowed)
		)
		(placement
			(enabled no)
			(sheetname "")
		)
		(fill yes
			(thermal_gap 0.5)
			(thermal_bridge_width 0.5)
			(island_removal_mode 0)
		)
		(polygon
			(pts
				(arc
					(start 344.980006 -279.964134)
					(mid 344.327226 -279.964134)
					(end 344.980006 -279.964134)
				)
			)
		)
	)
	(zone
		(layers "B.Cu" "In13.Cu" "In15.Cu")
		(hatch none 0.5)
		(connect_pads
			(clearance 0)
		)
		(min_thickness 0.25)
		(keepout
			(tracks not_allowed)
			(vias allowed)
			(pads allowed)
			(copperpour not_allowed)
			(footprints allowed)
		)
		(placement
			(enabled no)
			(sheetname "")
		)
		(fill yes
			(thermal_gap 0.5)
			(thermal_bridge_width 0.5)
			(island_removal_mode 0)
		)
		(polygon
			(pts
				(arc
					(start 348.269052 -271.011396)
					(mid 347.616272 -271.011396)
					(end 348.269052 -271.011396)
				)
			)
		)
	)
	(zone
		(layers "B.Cu" "In13.Cu" "In15.Cu")
		(hatch none 0.5)
		(connect_pads
			(clearance 0)
		)
		(min_thickness 0.25)
		(keepout
			(tracks not_allowed)
			(vias allowed)
			(pads allowed)
			(copperpour not_allowed)
			(footprints allowed)
		)
		(placement
			(enabled no)
			(sheetname "")
		)
		(fill yes
			(thermal_gap 0.5)
			(thermal_bridge_width 0.5)
			(island_removal_mode 0)
		)
		(polygon
			(pts
				(arc
					(start 17.115536 -216.866724)
					(mid 16.462756 -216.866724)
					(end 17.115536 -216.866724)
				)
			)
		)
	)
	(zone
		(layers "B.Cu" "In13.Cu" "In15.Cu")
		(hatch none 0.5)
		(connect_pads
			(clearance 0)
		)
		(min_thickness 0.25)
		(keepout
			(tracks not_allowed)
			(vias allowed)
			(pads allowed)
			(copperpour not_allowed)
			(footprints allowed)
		)
		(placement
			(enabled no)
			(sheetname "")
		)
		(fill yes
			(thermal_gap 0.5)
			(thermal_bridge_width 0.5)
			(island_removal_mode 0)
		)
		(polygon
			(pts
				(arc
					(start 415.52368 -403.883876)
					(mid 414.8201 -403.883876)
					(end 415.52368 -403.883876)
				)
			)
		)
	)
	(zone
		(layers "B.Cu" "In13.Cu" "In15.Cu")
		(hatch none 0.5)
		(connect_pads
			(clearance 0)
		)
		(min_thickness 0.25)
		(keepout
			(tracks not_allowed)
			(vias allowed)
			(pads allowed)
			(copperpour not_allowed)
			(footprints allowed)
		)
		(placement
			(enabled no)
			(sheetname "")
		)
		(fill yes
			(thermal_gap 0.5)
			(thermal_bridge_width 0.5)
			(island_removal_mode 0)
		)
		(polygon
			(pts
				(arc
					(start 346.859606 -278.336502)
					(mid 346.206826 -278.336502)
					(end 346.859606 -278.336502)
				)
			)
		)
	)
	(zone
		(layers "B.Cu" "In13.Cu" "In15.Cu")
		(hatch none 0.5)
		(connect_pads
			(clearance 0)
		)
		(min_thickness 0.25)
		(keepout
			(tracks not_allowed)
			(vias allowed)
			(pads allowed)
			(copperpour not_allowed)
			(footprints allowed)
		)
		(placement
			(enabled no)
			(sheetname "")
		)
		(fill yes
			(thermal_gap 0.5)
			(thermal_bridge_width 0.5)
			(island_removal_mode 0)
		)
		(polygon
			(pts
				(arc
					(start 373.064024 -245.55069)
					(mid 372.411244 -245.55069)
					(end 373.064024 -245.55069)
				)
			)
		)
	)
	(zone
		(layers "B.Cu" "In13.Cu" "In15.Cu")
		(hatch none 0.5)
		(connect_pads
			(clearance 0)
		)
		(min_thickness 0.25)
		(keepout
			(tracks not_allowed)
			(vias allowed)
			(pads allowed)
			(copperpour not_allowed)
			(footprints allowed)
		)
		(placement
			(enabled no)
			(sheetname "")
		)
		(fill yes
			(thermal_gap 0.5)
			(thermal_bridge_width 0.5)
			(island_removal_mode 0)
		)
		(polygon
			(pts
				(arc
					(start 19.203162 -399.416016)
					(mid 18.499582 -399.416016)
					(end 19.203162 -399.416016)
				)
			)
		)
	)
	(zone
		(layers "B.Cu" "In13.Cu" "In15.Cu")
		(hatch none 0.5)
		(connect_pads
			(clearance 0)
		)
		(min_thickness 0.25)
		(keepout
			(tracks not_allowed)
			(vias allowed)
			(pads allowed)
			(copperpour not_allowed)
			(footprints allowed)
		)
		(placement
			(enabled no)
			(sheetname "")
		)
		(fill yes
			(thermal_gap 0.5)
			(thermal_bridge_width 0.5)
			(island_removal_mode 0)
		)
		(polygon
			(pts
				(arc
					(start 347.21927 -241.481102)
					(mid 346.56649 -241.481102)
					(end 347.21927 -241.481102)
				)
			)
		)
	)
	(zone
		(layers "B.Cu" "In13.Cu" "In15.Cu")
		(hatch none 0.5)
		(connect_pads
			(clearance 0)
		)
		(min_thickness 0.25)
		(keepout
			(tracks not_allowed)
			(vias allowed)
			(pads allowed)
			(copperpour not_allowed)
			(footprints allowed)
		)
		(placement
			(enabled no)
			(sheetname "")
		)
		(fill yes
			(thermal_gap 0.5)
			(thermal_bridge_width 0.5)
			(island_removal_mode 0)
		)
		(polygon
			(pts
				(arc
					(start 48.331628 -403.883876)
					(mid 47.628048 -403.883876)
					(end 48.331628 -403.883876)
				)
			)
		)
	)
	(zone
		(layers "B.Cu" "In13.Cu" "In15.Cu")
		(hatch none 0.5)
		(connect_pads
			(clearance 0)
		)
		(min_thickness 0.25)
		(keepout
			(tracks not_allowed)
			(vias allowed)
			(pads allowed)
			(copperpour not_allowed)
			(footprints allowed)
		)
		(placement
			(enabled no)
			(sheetname "")
		)
		(fill yes
			(thermal_gap 0.5)
			(thermal_bridge_width 0.5)
			(island_removal_mode 0)
		)
		(polygon
			(pts
				(arc
					(start 349.427038 -410.030168)
					(mid 348.723458 -410.030168)
					(end 349.427038 -410.030168)
				)
			)
		)
	)
	(zone
		(layers "B.Cu" "In13.Cu" "In15.Cu")
		(hatch none 0.5)
		(connect_pads
			(clearance 0)
		)
		(min_thickness 0.25)
		(keepout
			(tracks not_allowed)
			(vias allowed)
			(pads allowed)
			(copperpour not_allowed)
			(footprints allowed)
		)
		(placement
			(enabled no)
			(sheetname "")
		)
		(fill yes
			(thermal_gap 0.5)
			(thermal_bridge_width 0.5)
			(island_removal_mode 0)
		)
		(polygon
			(pts
				(arc
					(start 123.244356 -247.178322)
					(mid 122.591576 -247.178322)
					(end 123.244356 -247.178322)
				)
			)
		)
	)
	(zone
		(layers "B.Cu" "In13.Cu" "In15.Cu")
		(hatch none 0.5)
		(connect_pads
			(clearance 0)
		)
		(min_thickness 0.25)
		(keepout
			(tracks not_allowed)
			(vias allowed)
			(pads allowed)
			(copperpour not_allowed)
			(footprints allowed)
		)
		(placement
			(enabled no)
			(sheetname "")
		)
		(fill yes
			(thermal_gap 0.5)
			(thermal_bridge_width 0.5)
			(island_removal_mode 0)
		)
		(polygon
			(pts
				(arc
					(start 347.21927 -231.714548)
					(mid 346.56649 -231.714548)
					(end 347.21927 -231.714548)
				)
			)
		)
	)
	(zone
		(layers "B.Cu" "In13.Cu" "In15.Cu")
		(hatch none 0.5)
		(connect_pads
			(clearance 0)
		)
		(min_thickness 0.25)
		(keepout
			(tracks not_allowed)
			(vias allowed)
			(pads allowed)
			(copperpour not_allowed)
			(footprints allowed)
		)
		(placement
			(enabled no)
			(sheetname "")
		)
		(fill yes
			(thermal_gap 0.5)
			(thermal_bridge_width 0.5)
			(island_removal_mode 0)
		)
		(polygon
			(pts
				(arc
					(start 365.07547 -220.319854)
					(mid 364.42269 -220.319854)
					(end 365.07547 -220.319854)
				)
			)
		)
	)
	(zone
		(layers "B.Cu" "In13.Cu" "In15.Cu")
		(hatch none 0.5)
		(connect_pads
			(clearance 0)
		)
		(min_thickness 0.25)
		(keepout
			(tracks not_allowed)
			(vias allowed)
			(pads allowed)
			(copperpour not_allowed)
			(footprints allowed)
		)
		(placement
			(enabled no)
			(sheetname "")
		)
		(fill yes
			(thermal_gap 0.5)
			(thermal_bridge_width 0.5)
			(island_removal_mode 0)
		)
		(polygon
			(pts
				(arc
					(start 376.823224 -245.55069)
					(mid 376.170444 -245.55069)
					(end 376.823224 -245.55069)
				)
			)
		)
	)
	(zone
		(layers "B.Cu" "In13.Cu" "In15.Cu")
		(hatch none 0.5)
		(connect_pads
			(clearance 0)
		)
		(min_thickness 0.25)
		(keepout
			(tracks not_allowed)
			(vias allowed)
			(pads allowed)
			(copperpour not_allowed)
			(footprints allowed)
		)
		(placement
			(enabled no)
			(sheetname "")
		)
		(fill yes
			(thermal_gap 0.5)
			(thermal_bridge_width 0.5)
			(island_removal_mode 0)
		)
		(polygon
			(pts
				(arc
					(start 387.95452 -403.883876)
					(mid 387.25094 -403.883876)
					(end 387.95452 -403.883876)
				)
			)
		)
	)
	(zone
		(layers "B.Cu" "In13.Cu" "In15.Cu")
		(hatch none 0.5)
		(connect_pads
			(clearance 0)
		)
		(min_thickness 0.25)
		(keepout
			(tracks not_allowed)
			(vias allowed)
			(pads allowed)
			(copperpour not_allowed)
			(footprints allowed)
		)
		(placement
			(enabled no)
			(sheetname "")
		)
		(fill yes
			(thermal_gap 0.5)
			(thermal_bridge_width 0.5)
			(island_removal_mode 0)
		)
		(polygon
			(pts
				(arc
					(start 88.581484 -286.475424)
					(mid 87.928704 -286.475424)
					(end 88.581484 -286.475424)
				)
			)
		)
	)
	(zone
		(layers "B.Cu" "In13.Cu" "In15.Cu")
		(hatch none 0.5)
		(connect_pads
			(clearance 0)
		)
		(min_thickness 0.25)
		(keepout
			(tracks not_allowed)
			(vias allowed)
			(pads allowed)
			(copperpour not_allowed)
			(footprints allowed)
		)
		(placement
			(enabled no)
			(sheetname "")
		)
		(fill yes
			(thermal_gap 0.5)
			(thermal_bridge_width 0.5)
			(island_removal_mode 0)
		)
		(polygon
			(pts
				(arc
					(start 265.055604 -272.966688)
					(mid 264.402824 -272.966688)
					(end 265.055604 -272.966688)
				)
			)
		)
	)
	(zone
		(layers "B.Cu" "In13.Cu" "In15.Cu")
		(hatch none 0.5)
		(connect_pads
			(clearance 0)
		)
		(min_thickness 0.25)
		(keepout
			(tracks not_allowed)
			(vias allowed)
			(pads allowed)
			(copperpour not_allowed)
			(footprints allowed)
		)
		(placement
			(enabled no)
			(sheetname "")
		)
		(fill yes
			(thermal_gap 0.5)
			(thermal_bridge_width 0.5)
			(island_removal_mode 0)
		)
		(polygon
			(pts
				(arc
					(start 100.219002 -230.086662)
					(mid 99.566222 -230.086662)
					(end 100.219002 -230.086662)
				)
			)
		)
	)
	(zone
		(layers "B.Cu" "In13.Cu" "In15.Cu")
		(hatch none 0.5)
		(connect_pads
			(clearance 0)
		)
		(min_thickness 0.25)
		(keepout
			(tracks not_allowed)
			(vias allowed)
			(pads allowed)
			(copperpour not_allowed)
			(footprints allowed)
		)
		(placement
			(enabled no)
			(sheetname "")
		)
		(fill yes
			(thermal_gap 0.5)
			(thermal_bridge_width 0.5)
			(island_removal_mode 0)
		)
		(polygon
			(pts
				(arc
					(start 108.207556 -221.133924)
					(mid 107.554776 -221.133924)
					(end 108.207556 -221.133924)
				)
			)
		)
	)
	(zone
		(layers "B.Cu" "In13.Cu" "In15.Cu")
		(hatch none 0.5)
		(connect_pads
			(clearance 0)
		)
		(min_thickness 0.25)
		(keepout
			(tracks not_allowed)
			(vias allowed)
			(pads allowed)
			(copperpour not_allowed)
			(footprints allowed)
		)
		(placement
			(enabled no)
			(sheetname "")
		)
		(fill yes
			(thermal_gap 0.5)
			(thermal_bridge_width 0.5)
			(island_removal_mode 0)
		)
		(polygon
			(pts
				(arc
					(start 71.054976 -429.689768)
					(mid 70.245224 -429.689768)
					(end 71.054976 -429.689768)
				)
			)
		)
	)
	(zone
		(layers "B.Cu" "In13.Cu" "In15.Cu")
		(hatch none 0.5)
		(connect_pads
			(clearance 0)
		)
		(min_thickness 0.25)
		(keepout
			(tracks not_allowed)
			(vias allowed)
			(pads allowed)
			(copperpour not_allowed)
			(footprints allowed)
		)
		(placement
			(enabled no)
			(sheetname "")
		)
		(fill yes
			(thermal_gap 0.5)
			(thermal_bridge_width 0.5)
			(island_removal_mode 0)
		)
		(polygon
			(pts
				(arc
					(start 265.055604 -299.316648)
					(mid 264.402824 -299.316648)
					(end 265.055604 -299.316648)
				)
			)
		)
	)
	(zone
		(layers "B.Cu" "In13.Cu" "In15.Cu")
		(hatch none 0.5)
		(connect_pads
			(clearance 0)
		)
		(min_thickness 0.25)
		(keepout
			(tracks not_allowed)
			(vias allowed)
			(pads allowed)
			(copperpour not_allowed)
			(footprints allowed)
		)
		(placement
			(enabled no)
			(sheetname "")
		)
		(fill yes
			(thermal_gap 0.5)
			(thermal_bridge_width 0.5)
			(island_removal_mode 0)
		)
		(polygon
			(pts
				(arc
					(start 17.115536 -299.316648)
					(mid 16.462756 -299.316648)
					(end 17.115536 -299.316648)
				)
			)
		)
	)
	(zone
		(layers "B.Cu" "In13.Cu" "In15.Cu")
		(hatch none 0.5)
		(connect_pads
			(clearance 0)
		)
		(min_thickness 0.25)
		(keepout
			(tracks not_allowed)
			(vias allowed)
			(pads allowed)
			(copperpour not_allowed)
			(footprints allowed)
		)
		(placement
			(enabled no)
			(sheetname "")
		)
		(fill yes
			(thermal_gap 0.5)
			(thermal_bridge_width 0.5)
			(island_removal_mode 0)
		)
		(polygon
			(pts
				(arc
					(start 372.124224 -243.922804)
					(mid 371.471444 -243.922804)
					(end 372.124224 -243.922804)
				)
			)
		)
	)
	(zone
		(layers "B.Cu" "In13.Cu" "In15.Cu")
		(hatch none 0.5)
		(connect_pads
			(clearance 0)
		)
		(min_thickness 0.25)
		(keepout
			(tracks not_allowed)
			(vias allowed)
			(pads allowed)
			(copperpour not_allowed)
			(footprints allowed)
		)
		(placement
			(enabled no)
			(sheetname "")
		)
		(fill yes
			(thermal_gap 0.5)
			(thermal_bridge_width 0.5)
			(island_removal_mode 0)
		)
		(polygon
			(pts
				(arc
					(start 348.739206 -263.686544)
					(mid 348.086426 -263.686544)
					(end 348.739206 -263.686544)
				)
			)
		)
	)
	(zone
		(layers "B.Cu" "In13.Cu" "In15.Cu")
		(hatch none 0.5)
		(connect_pads
			(clearance 0)
		)
		(min_thickness 0.25)
		(keepout
			(tracks not_allowed)
			(vias allowed)
			(pads allowed)
			(copperpour not_allowed)
			(footprints allowed)
		)
		(placement
			(enabled no)
			(sheetname "")
		)
		(fill yes
			(thermal_gap 0.5)
			(thermal_bridge_width 0.5)
			(island_removal_mode 0)
		)
		(polygon
			(pts
				(arc
					(start 429.459644 -6.713474)
					(mid 428.756064 -6.713474)
					(end 429.459644 -6.713474)
				)
			)
		)
	)
	(zone
		(layers "B.Cu" "In13.Cu" "In15.Cu")
		(hatch none 0.5)
		(connect_pads
			(clearance 0)
		)
		(min_thickness 0.25)
		(keepout
			(tracks not_allowed)
			(vias allowed)
			(pads allowed)
			(copperpour not_allowed)
			(footprints allowed)
		)
		(placement
			(enabled no)
			(sheetname "")
		)
		(fill yes
			(thermal_gap 0.5)
			(thermal_bridge_width 0.5)
			(island_removal_mode 0)
		)
		(polygon
			(pts
				(arc
					(start 265.055604 -241.516662)
					(mid 264.402824 -241.516662)
					(end 265.055604 -241.516662)
				)
			)
		)
	)
	(zone
		(layers "B.Cu" "In13.Cu" "In15.Cu")
		(hatch none 0.5)
		(connect_pads
			(clearance 0)
		)
		(min_thickness 0.25)
		(keepout
			(tracks not_allowed)
			(vias allowed)
			(pads allowed)
			(copperpour not_allowed)
			(footprints allowed)
		)
		(placement
			(enabled no)
			(sheetname "")
		)
		(fill yes
			(thermal_gap 0.5)
			(thermal_bridge_width 0.5)
			(island_removal_mode 0)
		)
		(polygon
			(pts
				(arc
					(start 100.328984 -271.011396)
					(mid 99.676204 -271.011396)
					(end 100.328984 -271.011396)
				)
			)
		)
	)
	(zone
		(layers "B.Cu" "In13.Cu" "In15.Cu")
		(hatch none 0.5)
		(connect_pads
			(clearance 0)
		)
		(min_thickness 0.25)
		(keepout
			(tracks not_allowed)
			(vias allowed)
			(pads allowed)
			(copperpour not_allowed)
			(footprints allowed)
		)
		(placement
			(enabled no)
			(sheetname "")
		)
		(fill yes
			(thermal_gap 0.5)
			(thermal_bridge_width 0.5)
			(island_removal_mode 0)
		)
		(polygon
			(pts
				(arc
					(start 99.279202 -244.73662)
					(mid 98.626422 -244.73662)
					(end 99.279202 -244.73662)
				)
			)
		)
	)
	(zone
		(layers "B.Cu" "In13.Cu" "In15.Cu")
		(hatch none 0.5)
		(connect_pads
			(clearance 0)
		)
		(min_thickness 0.25)
		(keepout
			(tracks not_allowed)
			(vias allowed)
			(pads allowed)
			(copperpour not_allowed)
			(footprints allowed)
		)
		(placement
			(enabled no)
			(sheetname "")
		)
		(fill yes
			(thermal_gap 0.5)
			(thermal_bridge_width 0.5)
			(island_removal_mode 0)
		)
		(polygon
			(pts
				(arc
					(start 373.643652 -256.361438)
					(mid 372.990872 -256.361438)
					(end 373.643652 -256.361438)
				)
			)
		)
	)
	(zone
		(layers "B.Cu" "In13.Cu" "In15.Cu")
		(hatch none 0.5)
		(connect_pads
			(clearance 0)
		)
		(min_thickness 0.25)
		(keepout
			(tracks not_allowed)
			(vias allowed)
			(pads allowed)
			(copperpour not_allowed)
			(footprints allowed)
		)
		(placement
			(enabled no)
			(sheetname "")
		)
		(fill yes
			(thermal_gap 0.5)
			(thermal_bridge_width 0.5)
			(island_removal_mode 0)
		)
		(polygon
			(pts
				(arc
					(start 455.337672 -283.166566)
					(mid 454.684892 -283.166566)
					(end 455.337672 -283.166566)
				)
			)
		)
	)
	(zone
		(layers "B.Cu" "In13.Cu" "In15.Cu")
		(hatch none 0.5)
		(connect_pads
			(clearance 0)
		)
		(min_thickness 0.25)
		(keepout
			(tracks not_allowed)
			(vias allowed)
			(pads allowed)
			(copperpour not_allowed)
			(footprints allowed)
		)
		(placement
			(enabled no)
			(sheetname "")
		)
		(fill yes
			(thermal_gap 0.5)
			(thermal_bridge_width 0.5)
			(island_removal_mode 0)
		)
		(polygon
			(pts
				(arc
					(start 346.749624 -229.272846)
					(mid 346.096844 -229.272846)
					(end 346.749624 -229.272846)
				)
			)
		)
	)
	(zone
		(layers "B.Cu" "In13.Cu" "In15.Cu")
		(hatch none 0.5)
		(connect_pads
			(clearance 0)
		)
		(min_thickness 0.25)
		(keepout
			(tracks not_allowed)
			(vias allowed)
			(pads allowed)
			(copperpour not_allowed)
			(footprints allowed)
		)
		(placement
			(enabled no)
			(sheetname "")
		)
		(fill yes
			(thermal_gap 0.5)
			(thermal_bridge_width 0.5)
			(island_removal_mode 0)
		)
		(polygon
			(pts
				(arc
					(start 53.156866 -4.962652)
					(mid 52.453286 -4.962652)
					(end 53.156866 -4.962652)
				)
			)
		)
	)
	(zone
		(layers "B.Cu" "In13.Cu" "In15.Cu")
		(hatch none 0.5)
		(connect_pads
			(clearance 0)
		)
		(min_thickness 0.25)
		(keepout
			(tracks not_allowed)
			(vias allowed)
			(pads allowed)
			(copperpour not_allowed)
			(footprints allowed)
		)
		(placement
			(enabled no)
			(sheetname "")
		)
		(fill yes
			(thermal_gap 0.5)
			(thermal_bridge_width 0.5)
			(island_removal_mode 0)
		)
		(polygon
			(pts
				(arc
					(start 21.215604 -248.31675)
					(mid 20.562824 -248.31675)
					(end 21.215604 -248.31675)
				)
			)
		)
	)
	(zone
		(layers "B.Cu" "In13.Cu" "In15.Cu")
		(hatch none 0.5)
		(connect_pads
			(clearance 0)
		)
		(min_thickness 0.25)
		(keepout
			(tracks not_allowed)
			(vias allowed)
			(pads allowed)
			(copperpour not_allowed)
			(footprints allowed)
		)
		(placement
			(enabled no)
			(sheetname "")
		)
		(fill yes
			(thermal_gap 0.5)
			(thermal_bridge_width 0.5)
			(island_removal_mode 0)
		)
		(polygon
			(pts
				(arc
					(start 207.397604 -250.016772)
					(mid 206.744824 -250.016772)
					(end 207.397604 -250.016772)
				)
			)
		)
	)
	(zone
		(layers "B.Cu" "In13.Cu" "In15.Cu")
		(hatch none 0.5)
		(connect_pads
			(clearance 0)
		)
		(min_thickness 0.25)
		(keepout
			(tracks not_allowed)
			(vias allowed)
			(pads allowed)
			(copperpour not_allowed)
			(footprints allowed)
		)
		(placement
			(enabled no)
			(sheetname "")
		)
		(fill yes
			(thermal_gap 0.5)
			(thermal_bridge_width 0.5)
			(island_removal_mode 0)
		)
		(polygon
			(pts
				(arc
					(start 99.389184 -271.011396)
					(mid 98.736404 -271.011396)
					(end 99.389184 -271.011396)
				)
			)
		)
	)
	(zone
		(layers "B.Cu" "In13.Cu" "In15.Cu")
		(hatch none 0.5)
		(connect_pads
			(clearance 0)
		)
		(min_thickness 0.25)
		(keepout
			(tracks not_allowed)
			(vias allowed)
			(pads allowed)
			(copperpour not_allowed)
			(footprints allowed)
		)
		(placement
			(enabled no)
			(sheetname "")
		)
		(fill yes
			(thermal_gap 0.5)
			(thermal_bridge_width 0.5)
			(island_removal_mode 0)
		)
		(polygon
			(pts
				(arc
					(start 269.155672 -274.66671)
					(mid 268.502892 -274.66671)
					(end 269.155672 -274.66671)
				)
			)
		)
	)
	(zone
		(layers "B.Cu" "In13.Cu" "In15.Cu")
		(hatch none 0.5)
		(connect_pads
			(clearance 0)
		)
		(min_thickness 0.25)
		(keepout
			(tracks not_allowed)
			(vias allowed)
			(pads allowed)
			(copperpour not_allowed)
			(footprints allowed)
		)
		(placement
			(enabled no)
			(sheetname "")
		)
		(fill yes
			(thermal_gap 0.5)
			(thermal_bridge_width 0.5)
			(island_removal_mode 0)
		)
		(polygon
			(pts
				(arc
					(start 451.237604 -232.166668)
					(mid 450.584824 -232.166668)
					(end 451.237604 -232.166668)
				)
			)
		)
	)
	(zone
		(layers "B.Cu" "In13.Cu" "In15.Cu")
		(hatch none 0.5)
		(connect_pads
			(clearance 0)
		)
		(min_thickness 0.25)
		(keepout
			(tracks not_allowed)
			(vias allowed)
			(pads allowed)
			(copperpour not_allowed)
			(footprints allowed)
		)
		(placement
			(enabled no)
			(sheetname "")
		)
		(fill yes
			(thermal_gap 0.5)
			(thermal_bridge_width 0.5)
			(island_removal_mode 0)
		)
		(polygon
			(pts
				(arc
					(start 455.337672 -287.416748)
					(mid 454.684892 -287.416748)
					(end 455.337672 -287.416748)
				)
			)
		)
	)
	(zone
		(layers "B.Cu" "In13.Cu" "In15.Cu")
		(hatch none 0.5)
		(connect_pads
			(clearance 0)
		)
		(min_thickness 0.25)
		(keepout
			(tracks not_allowed)
			(vias allowed)
			(pads allowed)
			(copperpour not_allowed)
			(footprints allowed)
		)
		(placement
			(enabled no)
			(sheetname "")
		)
		(fill yes
			(thermal_gap 0.5)
			(thermal_bridge_width 0.5)
			(island_removal_mode 0)
		)
		(polygon
			(pts
				(arc
					(start 347.329252 -269.38351)
					(mid 346.676472 -269.38351)
					(end 347.329252 -269.38351)
				)
			)
		)
	)
	(zone
		(layers "B.Cu" "In13.Cu" "In15.Cu")
		(hatch none 0.5)
		(connect_pads
			(clearance 0)
		)
		(min_thickness 0.25)
		(keepout
			(tracks not_allowed)
			(vias allowed)
			(pads allowed)
			(copperpour not_allowed)
			(footprints allowed)
		)
		(placement
			(enabled no)
			(sheetname "")
		)
		(fill yes
			(thermal_gap 0.5)
			(thermal_bridge_width 0.5)
			(island_removal_mode 0)
		)
		(polygon
			(pts
				(arc
					(start 373.174006 -262.058658)
					(mid 372.521226 -262.058658)
					(end 373.174006 -262.058658)
				)
			)
		)
	)
	(zone
		(layers "B.Cu" "In13.Cu" "In15.Cu")
		(hatch none 0.5)
		(connect_pads
			(clearance 0)
		)
		(min_thickness 0.25)
		(keepout
			(tracks not_allowed)
			(vias allowed)
			(pads allowed)
			(copperpour not_allowed)
			(footprints allowed)
		)
		(placement
			(enabled no)
			(sheetname "")
		)
		(fill yes
			(thermal_gap 0.5)
			(thermal_bridge_width 0.5)
			(island_removal_mode 0)
		)
		(polygon
			(pts
				(arc
					(start 17.115536 -215.166702)
					(mid 16.462756 -215.166702)
					(end 17.115536 -215.166702)
				)
			)
		)
	)
	(zone
		(layers "B.Cu" "In13.Cu" "In15.Cu")
		(hatch none 0.5)
		(connect_pads
			(clearance 0)
		)
		(min_thickness 0.25)
		(keepout
			(tracks not_allowed)
			(vias allowed)
			(pads allowed)
			(copperpour not_allowed)
			(footprints allowed)
		)
		(placement
			(enabled no)
			(sheetname "")
		)
		(fill yes
			(thermal_gap 0.5)
			(thermal_bridge_width 0.5)
			(island_removal_mode 0)
		)
		(polygon
			(pts
				(arc
					(start 265.055604 -266.1666)
					(mid 264.402824 -266.1666)
					(end 265.055604 -266.1666)
				)
			)
		)
	)
	(zone
		(layers "B.Cu" "In13.Cu" "In15.Cu")
		(hatch none 0.5)
		(connect_pads
			(clearance 0)
		)
		(min_thickness 0.25)
		(keepout
			(tracks not_allowed)
			(vias allowed)
			(pads allowed)
			(copperpour not_allowed)
			(footprints allowed)
		)
		(placement
			(enabled no)
			(sheetname "")
		)
		(fill yes
			(thermal_gap 0.5)
			(thermal_bridge_width 0.5)
			(island_removal_mode 0)
		)
		(polygon
			(pts
				(arc
					(start 346.859606 -257.175254)
					(mid 346.206826 -257.175254)
					(end 346.859606 -257.175254)
				)
			)
		)
	)
	(zone
		(layers "B.Cu" "In13.Cu" "In15.Cu")
		(hatch none 0.5)
		(connect_pads
			(clearance 0)
		)
		(min_thickness 0.25)
		(keepout
			(tracks not_allowed)
			(vias allowed)
			(pads allowed)
			(copperpour not_allowed)
			(footprints allowed)
		)
		(placement
			(enabled no)
			(sheetname "")
		)
		(fill yes
			(thermal_gap 0.5)
			(thermal_bridge_width 0.5)
			(island_removal_mode 0)
		)
		(polygon
			(pts
				(arc
					(start 404.676102 -6.713474)
					(mid 403.972522 -6.713474)
					(end 404.676102 -6.713474)
				)
			)
		)
	)
	(zone
		(layers "B.Cu" "In13.Cu" "In15.Cu")
		(hatch none 0.5)
		(connect_pads
			(clearance 0)
		)
		(min_thickness 0.25)
		(keepout
			(tracks not_allowed)
			(vias allowed)
			(pads allowed)
			(copperpour not_allowed)
			(footprints allowed)
		)
		(placement
			(enabled no)
			(sheetname "")
		)
		(fill yes
			(thermal_gap 0.5)
			(thermal_bridge_width 0.5)
			(island_removal_mode 0)
		)
		(polygon
			(pts
				(arc
					(start 124.294138 -262.058658)
					(mid 123.641358 -262.058658)
					(end 124.294138 -262.058658)
				)
			)
		)
	)
	(zone
		(layers "B.Cu" "In13.Cu" "In15.Cu")
		(hatch none 0.5)
		(connect_pads
			(clearance 0)
		)
		(min_thickness 0.25)
		(keepout
			(tracks not_allowed)
			(vias allowed)
			(pads allowed)
			(copperpour not_allowed)
			(footprints allowed)
		)
		(placement
			(enabled no)
			(sheetname "")
		)
		(fill yes
			(thermal_gap 0.5)
			(thermal_bridge_width 0.5)
			(island_removal_mode 0)
		)
		(polygon
			(pts
				(arc
					(start 125.233938 -258.80314)
					(mid 124.581158 -258.80314)
					(end 125.233938 -258.80314)
				)
			)
		)
	)
	(zone
		(layers "B.Cu" "In13.Cu" "In15.Cu")
		(hatch none 0.5)
		(connect_pads
			(clearance 0)
		)
		(min_thickness 0.25)
		(keepout
			(tracks not_allowed)
			(vias allowed)
			(pads allowed)
			(copperpour not_allowed)
			(footprints allowed)
		)
		(placement
			(enabled no)
			(sheetname "")
		)
		(fill yes
			(thermal_gap 0.5)
			(thermal_bridge_width 0.5)
			(island_removal_mode 0)
		)
		(polygon
			(pts
				(arc
					(start 123.714002 -243.108988)
					(mid 123.061222 -243.108988)
					(end 123.714002 -243.108988)
				)
			)
		)
	)
	(zone
		(layers "B.Cu" "In13.Cu" "In15.Cu")
		(hatch none 0.5)
		(connect_pads
			(clearance 0)
		)
		(min_thickness 0.25)
		(keepout
			(tracks not_allowed)
			(vias allowed)
			(pads allowed)
			(copperpour not_allowed)
			(footprints allowed)
		)
		(placement
			(enabled no)
			(sheetname "")
		)
		(fill yes
			(thermal_gap 0.5)
			(thermal_bridge_width 0.5)
			(island_removal_mode 0)
		)
		(polygon
			(pts
				(arc
					(start 269.155672 -301.866808)
					(mid 268.502892 -301.866808)
					(end 269.155672 -301.866808)
				)
			)
		)
	)
	(zone
		(layers "B.Cu" "In13.Cu" "In15.Cu")
		(hatch none 0.5)
		(connect_pads
			(clearance 0)
		)
		(min_thickness 0.25)
		(keepout
			(tracks not_allowed)
			(vias allowed)
			(pads allowed)
			(copperpour not_allowed)
			(footprints allowed)
		)
		(placement
			(enabled no)
			(sheetname "")
		)
		(fill yes
			(thermal_gap 0.5)
			(thermal_bridge_width 0.5)
			(island_removal_mode 0)
		)
		(polygon
			(pts
				(arc
					(start 269.155672 -293.366698)
					(mid 268.502892 -293.366698)
					(end 269.155672 -293.366698)
				)
			)
		)
	)
	(zone
		(layers "B.Cu" "In13.Cu" "In15.Cu")
		(hatch none 0.5)
		(connect_pads
			(clearance 0)
		)
		(min_thickness 0.25)
		(keepout
			(tracks not_allowed)
			(vias allowed)
			(pads allowed)
			(copperpour not_allowed)
			(footprints allowed)
		)
		(placement
			(enabled no)
			(sheetname "")
		)
		(fill yes
			(thermal_gap 0.5)
			(thermal_bridge_width 0.5)
			(island_removal_mode 0)
		)
		(polygon
			(pts
				(arc
					(start 346.859606 -263.686544)
					(mid 346.206826 -263.686544)
					(end 346.859606 -263.686544)
				)
			)
		)
	)
	(zone
		(layers "B.Cu" "In13.Cu" "In15.Cu")
		(hatch none 0.5)
		(connect_pads
			(clearance 0)
		)
		(min_thickness 0.25)
		(keepout
			(tracks not_allowed)
			(vias allowed)
			(pads allowed)
			(copperpour not_allowed)
			(footprints allowed)
		)
		(placement
			(enabled no)
			(sheetname "")
		)
		(fill yes
			(thermal_gap 0.5)
			(thermal_bridge_width 0.5)
			(island_removal_mode 0)
		)
		(polygon
			(pts
				(arc
					(start 207.397604 -218.566746)
					(mid 206.744824 -218.566746)
					(end 207.397604 -218.566746)
				)
			)
		)
	)
	(zone
		(layers "B.Cu" "In13.Cu" "In15.Cu")
		(hatch none 0.5)
		(connect_pads
			(clearance 0)
		)
		(min_thickness 0.25)
		(keepout
			(tracks not_allowed)
			(vias allowed)
			(pads allowed)
			(copperpour not_allowed)
			(footprints allowed)
		)
		(placement
			(enabled no)
			(sheetname "")
		)
		(fill yes
			(thermal_gap 0.5)
			(thermal_bridge_width 0.5)
			(island_removal_mode 0)
		)
		(polygon
			(pts
				(arc
					(start 203.297536 -196.466714)
					(mid 202.644756 -196.466714)
					(end 203.297536 -196.466714)
				)
			)
		)
	)
	(zone
		(layers "B.Cu" "In13.Cu" "In15.Cu")
		(hatch none 0.5)
		(connect_pads
			(clearance 0)
		)
		(min_thickness 0.25)
		(keepout
			(tracks not_allowed)
			(vias allowed)
			(pads allowed)
			(copperpour not_allowed)
			(footprints allowed)
		)
		(placement
			(enabled no)
			(sheetname "")
		)
		(fill yes
			(thermal_gap 0.5)
			(thermal_bridge_width 0.5)
			(island_removal_mode 0)
		)
		(polygon
			(pts
				(arc
					(start 342.054942 -431.889916)
					(mid 341.24519 -431.889916)
					(end 342.054942 -431.889916)
				)
			)
		)
	)
	(zone
		(layers "B.Cu" "In13.Cu" "In15.Cu")
		(hatch none 0.5)
		(connect_pads
			(clearance 0)
		)
		(min_thickness 0.25)
		(keepout
			(tracks not_allowed)
			(vias allowed)
			(pads allowed)
			(copperpour not_allowed)
			(footprints allowed)
		)
		(placement
			(enabled no)
			(sheetname "")
		)
		(fill yes
			(thermal_gap 0.5)
			(thermal_bridge_width 0.5)
			(island_removal_mode 0)
		)
		(polygon
			(pts
				(arc
					(start 390.154922 -426.089826)
					(mid 389.34517 -426.089826)
					(end 390.154922 -426.089826)
				)
			)
		)
	)
	(zone
		(layers "B.Cu" "In13.Cu" "In15.Cu")
		(hatch none 0.5)
		(connect_pads
			(clearance 0)
		)
		(min_thickness 0.25)
		(keepout
			(tracks not_allowed)
			(vias allowed)
			(pads allowed)
			(copperpour not_allowed)
			(footprints allowed)
		)
		(placement
			(enabled no)
			(sheetname "")
		)
		(fill yes
			(thermal_gap 0.5)
			(thermal_bridge_width 0.5)
			(island_removal_mode 0)
		)
		(polygon
			(pts
				(arc
					(start 399.154904 -426.089826)
					(mid 398.345152 -426.089826)
					(end 399.154904 -426.089826)
				)
			)
		)
	)
	(zone
		(layers "B.Cu" "In13.Cu" "In15.Cu")
		(hatch none 0.5)
		(connect_pads
			(clearance 0)
		)
		(min_thickness 0.25)
		(keepout
			(tracks not_allowed)
			(vias allowed)
			(pads allowed)
			(copperpour not_allowed)
			(footprints allowed)
		)
		(placement
			(enabled no)
			(sheetname "")
		)
		(fill yes
			(thermal_gap 0.5)
			(thermal_bridge_width 0.5)
			(island_removal_mode 0)
		)
		(polygon
			(pts
				(arc
					(start 455.337672 -237.266734)
					(mid 454.684892 -237.266734)
					(end 455.337672 -237.266734)
				)
			)
		)
	)
	(zone
		(layers "B.Cu" "In13.Cu" "In15.Cu")
		(hatch none 0.5)
		(connect_pads
			(clearance 0)
		)
		(min_thickness 0.25)
		(keepout
			(tracks not_allowed)
			(vias allowed)
			(pads allowed)
			(copperpour not_allowed)
			(footprints allowed)
		)
		(placement
			(enabled no)
			(sheetname "")
		)
		(fill yes
			(thermal_gap 0.5)
			(thermal_bridge_width 0.5)
			(island_removal_mode 0)
		)
		(polygon
			(pts
				(arc
					(start 98.919538 -263.686544)
					(mid 98.266758 -263.686544)
					(end 98.919538 -263.686544)
				)
			)
		)
	)
	(zone
		(layers "B.Cu" "In13.Cu" "In15.Cu")
		(hatch none 0.5)
		(connect_pads
			(clearance 0)
		)
		(min_thickness 0.25)
		(keepout
			(tracks not_allowed)
			(vias allowed)
			(pads allowed)
			(copperpour not_allowed)
			(footprints allowed)
		)
		(placement
			(enabled no)
			(sheetname "")
		)
		(fill yes
			(thermal_gap 0.5)
			(thermal_bridge_width 0.5)
			(island_removal_mode 0)
		)
		(polygon
			(pts
				(arc
					(start 401.075906 -6.713474)
					(mid 400.372326 -6.713474)
					(end 401.075906 -6.713474)
				)
			)
		)
	)
	(zone
		(layers "B.Cu" "In13.Cu" "In15.Cu")
		(hatch none 0.5)
		(connect_pads
			(clearance 0)
		)
		(min_thickness 0.25)
		(keepout
			(tracks not_allowed)
			(vias allowed)
			(pads allowed)
			(copperpour not_allowed)
			(footprints allowed)
		)
		(placement
			(enabled no)
			(sheetname "")
		)
		(fill yes
			(thermal_gap 0.5)
			(thermal_bridge_width 0.5)
			(island_removal_mode 0)
		)
		(polygon
			(pts
				(arc
					(start 203.297536 -284.016704)
					(mid 202.644756 -284.016704)
					(end 203.297536 -284.016704)
				)
			)
		)
	)
	(zone
		(layers "B.Cu" "In13.Cu" "In15.Cu")
		(hatch none 0.5)
		(connect_pads
			(clearance 0)
		)
		(min_thickness 0.25)
		(keepout
			(tracks not_allowed)
			(vias allowed)
			(pads allowed)
			(copperpour not_allowed)
			(footprints allowed)
		)
		(placement
			(enabled no)
			(sheetname "")
		)
		(fill yes
			(thermal_gap 0.5)
			(thermal_bridge_width 0.5)
			(island_removal_mode 0)
		)
		(polygon
			(pts
				(arc
					(start 143.154908 -427.289976)
					(mid 142.345156 -427.289976)
					(end 143.154908 -427.289976)
				)
			)
		)
	)
	(zone
		(layers "B.Cu" "In13.Cu" "In15.Cu")
		(hatch none 0.5)
		(connect_pads
			(clearance 0)
		)
		(min_thickness 0.25)
		(keepout
			(tracks not_allowed)
			(vias allowed)
			(pads allowed)
			(copperpour not_allowed)
			(footprints allowed)
		)
		(placement
			(enabled no)
			(sheetname "")
		)
		(fill yes
			(thermal_gap 0.5)
			(thermal_bridge_width 0.5)
			(island_removal_mode 0)
		)
		(polygon
			(pts
				(arc
					(start 261.611872 -260.21665)
					(mid 260.959092 -260.21665)
					(end 261.611872 -260.21665)
				)
			)
		)
	)
	(zone
		(layers "B.Cu" "In13.Cu" "In15.Cu")
		(hatch none 0.5)
		(connect_pads
			(clearance 0)
		)
		(min_thickness 0.25)
		(keepout
			(tracks not_allowed)
			(vias allowed)
			(pads allowed)
			(copperpour not_allowed)
			(footprints allowed)
		)
		(placement
			(enabled no)
			(sheetname "")
		)
		(fill yes
			(thermal_gap 0.5)
			(thermal_bridge_width 0.5)
			(island_removal_mode 0)
		)
		(polygon
			(pts
				(arc
					(start 393.2174 -403.883876)
					(mid 392.51382 -403.883876)
					(end 393.2174 -403.883876)
				)
			)
		)
	)
	(zone
		(layers "B.Cu" "In13.Cu" "In15.Cu")
		(hatch none 0.5)
		(connect_pads
			(clearance 0)
		)
		(min_thickness 0.25)
		(keepout
			(tracks not_allowed)
			(vias allowed)
			(pads allowed)
			(copperpour not_allowed)
			(footprints allowed)
		)
		(placement
			(enabled no)
			(sheetname "")
		)
		(fill yes
			(thermal_gap 0.5)
			(thermal_bridge_width 0.5)
			(island_removal_mode 0)
		)
		(polygon
			(pts
				(arc
					(start 56.756808 -4.962652)
					(mid 56.053228 -4.962652)
					(end 56.756808 -4.962652)
				)
			)
		)
	)
	(zone
		(layers "B.Cu" "In13.Cu" "In15.Cu")
		(hatch none 0.5)
		(connect_pads
			(clearance 0)
		)
		(min_thickness 0.25)
		(keepout
			(tracks not_allowed)
			(vias allowed)
			(pads allowed)
			(copperpour not_allowed)
			(footprints allowed)
		)
		(placement
			(enabled no)
			(sheetname "")
		)
		(fill yes
			(thermal_gap 0.5)
			(thermal_bridge_width 0.5)
			(island_removal_mode 0)
		)
		(polygon
			(pts
				(arc
					(start 21.215604 -201.56678)
					(mid 20.562824 -201.56678)
					(end 21.215604 -201.56678)
				)
			)
		)
	)
	(zone
		(layers "B.Cu" "In13.Cu" "In15.Cu")
		(hatch none 0.5)
		(connect_pads
			(clearance 0)
		)
		(min_thickness 0.25)
		(keepout
			(tracks not_allowed)
			(vias allowed)
			(pads allowed)
			(copperpour not_allowed)
			(footprints allowed)
		)
		(placement
			(enabled no)
			(sheetname "")
		)
		(fill yes
			(thermal_gap 0.5)
			(thermal_bridge_width 0.5)
			(island_removal_mode 0)
		)
		(polygon
			(pts
				(arc
					(start 373.174006 -265.314176)
					(mid 372.521226 -265.314176)
					(end 373.174006 -265.314176)
				)
			)
		)
	)
	(zone
		(layers "B.Cu" "In13.Cu" "In15.Cu")
		(hatch none 0.5)
		(connect_pads
			(clearance 0)
		)
		(min_thickness 0.25)
		(keepout
			(tracks not_allowed)
			(vias allowed)
			(pads allowed)
			(copperpour not_allowed)
			(footprints allowed)
		)
		(placement
			(enabled no)
			(sheetname "")
		)
		(fill yes
			(thermal_gap 0.5)
			(thermal_bridge_width 0.5)
			(island_removal_mode 0)
		)
		(polygon
			(pts
				(arc
					(start 411.59684 -403.883876)
					(mid 410.89326 -403.883876)
					(end 411.59684 -403.883876)
				)
			)
		)
	)
	(zone
		(layers "B.Cu" "In13.Cu" "In15.Cu")
		(hatch none 0.5)
		(connect_pads
			(clearance 0)
		)
		(min_thickness 0.25)
		(keepout
			(tracks not_allowed)
			(vias allowed)
			(pads allowed)
			(copperpour not_allowed)
			(footprints allowed)
		)
		(placement
			(enabled no)
			(sheetname "")
		)
		(fill yes
			(thermal_gap 0.5)
			(thermal_bridge_width 0.5)
			(island_removal_mode 0)
		)
		(polygon
			(pts
				(arc
					(start 371.764052 -271.011396)
					(mid 371.111272 -271.011396)
					(end 371.764052 -271.011396)
				)
			)
		)
	)
	(zone
		(layers "B.Cu" "In13.Cu" "In15.Cu")
		(hatch none 0.5)
		(connect_pads
			(clearance 0)
		)
		(min_thickness 0.25)
		(keepout
			(tracks not_allowed)
			(vias allowed)
			(pads allowed)
			(copperpour not_allowed)
			(footprints allowed)
		)
		(placement
			(enabled no)
			(sheetname "")
		)
		(fill yes
			(thermal_gap 0.5)
			(thermal_bridge_width 0.5)
			(island_removal_mode 0)
		)
		(polygon
			(pts
				(arc
					(start 451.237604 -235.566712)
					(mid 450.584824 -235.566712)
					(end 451.237604 -235.566712)
				)
			)
		)
	)
	(zone
		(layers "B.Cu" "In13.Cu" "In15.Cu")
		(hatch none 0.5)
		(connect_pads
			(clearance 0)
		)
		(min_thickness 0.25)
		(keepout
			(tracks not_allowed)
			(vias allowed)
			(pads allowed)
			(copperpour not_allowed)
			(footprints allowed)
		)
		(placement
			(enabled no)
			(sheetname "")
		)
		(fill yes
			(thermal_gap 0.5)
			(thermal_bridge_width 0.5)
			(island_removal_mode 0)
		)
		(polygon
			(pts
				(arc
					(start 408.5336 -403.883876)
					(mid 407.83002 -403.883876)
					(end 408.5336 -403.883876)
				)
			)
		)
	)
	(zone
		(layers "B.Cu" "In13.Cu" "In15.Cu")
		(hatch none 0.5)
		(connect_pads
			(clearance 0)
		)
		(min_thickness 0.25)
		(keepout
			(tracks not_allowed)
			(vias allowed)
			(pads allowed)
			(copperpour not_allowed)
			(footprints allowed)
		)
		(placement
			(enabled no)
			(sheetname "")
		)
		(fill yes
			(thermal_gap 0.5)
			(thermal_bridge_width 0.5)
			(island_removal_mode 0)
		)
		(polygon
			(pts
				(arc
					(start 20.066762 -399.416016)
					(mid 19.363182 -399.416016)
					(end 20.066762 -399.416016)
				)
			)
		)
	)
	(zone
		(layers "B.Cu" "In13.Cu" "In15.Cu")
		(hatch none 0.5)
		(connect_pads
			(clearance 0)
		)
		(min_thickness 0.25)
		(keepout
			(tracks not_allowed)
			(vias allowed)
			(pads allowed)
			(copperpour not_allowed)
			(footprints allowed)
		)
		(placement
			(enabled no)
			(sheetname "")
		)
		(fill yes
			(thermal_gap 0.5)
			(thermal_bridge_width 0.5)
			(island_removal_mode 0)
		)
		(polygon
			(pts
				(arc
					(start 115.255802 -220.319854)
					(mid 114.603022 -220.319854)
					(end 115.255802 -220.319854)
				)
			)
		)
	)
	(zone
		(layers "B.Cu" "In13.Cu" "In15.Cu")
		(hatch none 0.5)
		(connect_pads
			(clearance 0)
		)
		(min_thickness 0.25)
		(keepout
			(tracks not_allowed)
			(vias allowed)
			(pads allowed)
			(copperpour not_allowed)
			(footprints allowed)
		)
		(placement
			(enabled no)
			(sheetname "")
		)
		(fill yes
			(thermal_gap 0.5)
			(thermal_bridge_width 0.5)
			(island_removal_mode 0)
		)
		(polygon
			(pts
				(arc
					(start 99.389184 -269.38351)
					(mid 98.736404 -269.38351)
					(end 99.389184 -269.38351)
				)
			)
		)
	)
	(zone
		(layers "B.Cu" "In13.Cu" "In15.Cu")
		(hatch none 0.5)
		(connect_pads
			(clearance 0)
		)
		(min_thickness 0.25)
		(keepout
			(tracks not_allowed)
			(vias allowed)
			(pads allowed)
			(copperpour not_allowed)
			(footprints allowed)
		)
		(placement
			(enabled no)
			(sheetname "")
		)
		(fill yes
			(thermal_gap 0.5)
			(thermal_bridge_width 0.5)
			(island_removal_mode 0)
		)
		(polygon
			(pts
				(arc
					(start 372.234206 -276.708616)
					(mid 371.581426 -276.708616)
					(end 372.234206 -276.708616)
				)
			)
		)
	)
	(zone
		(layers "B.Cu" "In13.Cu" "In15.Cu")
		(hatch none 0.5)
		(connect_pads
			(clearance 0)
		)
		(min_thickness 0.25)
		(keepout
			(tracks not_allowed)
			(vias allowed)
			(pads allowed)
			(copperpour not_allowed)
			(footprints allowed)
		)
		(placement
			(enabled no)
			(sheetname "")
		)
		(fill yes
			(thermal_gap 0.5)
			(thermal_bridge_width 0.5)
			(island_removal_mode 0)
		)
		(polygon
			(pts
				(arc
					(start 265.055604 -294.216582)
					(mid 264.402824 -294.216582)
					(end 265.055604 -294.216582)
				)
			)
		)
	)
	(zone
		(layers "B.Cu" "In13.Cu" "In15.Cu")
		(hatch none 0.5)
		(connect_pads
			(clearance 0)
		)
		(min_thickness 0.25)
		(keepout
			(tracks not_allowed)
			(vias allowed)
			(pads allowed)
			(copperpour not_allowed)
			(footprints allowed)
		)
		(placement
			(enabled no)
			(sheetname "")
		)
		(fill yes
			(thermal_gap 0.5)
			(thermal_bridge_width 0.5)
			(island_removal_mode 0)
		)
		(polygon
			(pts
				(arc
					(start 91.400884 -281.59202)
					(mid 90.748104 -281.59202)
					(end 91.400884 -281.59202)
				)
			)
		)
	)
	(zone
		(layers "B.Cu" "In13.Cu" "In15.Cu")
		(hatch none 0.5)
		(connect_pads
			(clearance 0)
		)
		(min_thickness 0.25)
		(keepout
			(tracks not_allowed)
			(vias allowed)
			(pads allowed)
			(copperpour not_allowed)
			(footprints allowed)
		)
		(placement
			(enabled no)
			(sheetname "")
		)
		(fill yes
			(thermal_gap 0.5)
			(thermal_bridge_width 0.5)
			(island_removal_mode 0)
		)
		(polygon
			(pts
				(arc
					(start 203.297536 -278.916638)
					(mid 202.644756 -278.916638)
					(end 203.297536 -278.916638)
				)
			)
		)
	)
	(zone
		(layers "B.Cu" "In13.Cu" "In15.Cu")
		(hatch none 0.5)
		(connect_pads
			(clearance 0)
		)
		(min_thickness 0.25)
		(keepout
			(tracks not_allowed)
			(vias allowed)
			(pads allowed)
			(copperpour not_allowed)
			(footprints allowed)
		)
		(placement
			(enabled no)
			(sheetname "")
		)
		(fill yes
			(thermal_gap 0.5)
			(thermal_bridge_width 0.5)
			(island_removal_mode 0)
		)
		(polygon
			(pts
				(arc
					(start 352.028252 -277.522432)
					(mid 351.375472 -277.522432)
					(end 352.028252 -277.522432)
				)
			)
		)
	)
	(zone
		(layers "B.Cu" "In13.Cu" "In15.Cu")
		(hatch none 0.5)
		(connect_pads
			(clearance 0)
		)
		(min_thickness 0.25)
		(keepout
			(tracks not_allowed)
			(vias allowed)
			(pads allowed)
			(copperpour not_allowed)
			(footprints allowed)
		)
		(placement
			(enabled no)
			(sheetname "")
		)
		(fill yes
			(thermal_gap 0.5)
			(thermal_bridge_width 0.5)
			(island_removal_mode 0)
		)
		(polygon
			(pts
				(arc
					(start 265.055604 -275.516594)
					(mid 264.402824 -275.516594)
					(end 265.055604 -275.516594)
				)
			)
		)
	)
	(zone
		(layers "B.Cu" "In13.Cu" "In15.Cu")
		(hatch none 0.5)
		(connect_pads
			(clearance 0)
		)
		(min_thickness 0.25)
		(keepout
			(tracks not_allowed)
			(vias allowed)
			(pads allowed)
			(copperpour not_allowed)
			(footprints allowed)
		)
		(placement
			(enabled no)
			(sheetname "")
		)
		(fill yes
			(thermal_gap 0.5)
			(thermal_bridge_width 0.5)
			(island_removal_mode 0)
		)
		(polygon
			(pts
				(arc
					(start 372.234206 -266.941808)
					(mid 371.581426 -266.941808)
					(end 372.234206 -266.941808)
				)
			)
		)
	)
	(zone
		(layers "B.Cu" "In13.Cu" "In15.Cu")
		(hatch none 0.5)
		(connect_pads
			(clearance 0)
		)
		(min_thickness 0.25)
		(keepout
			(tracks not_allowed)
			(vias allowed)
			(pads allowed)
			(copperpour not_allowed)
			(footprints allowed)
		)
		(placement
			(enabled no)
			(sheetname "")
		)
		(fill yes
			(thermal_gap 0.5)
			(thermal_bridge_width 0.5)
			(island_removal_mode 0)
		)
		(polygon
			(pts
				(arc
					(start 265.055604 -224.516696)
					(mid 264.402824 -224.516696)
					(end 265.055604 -224.516696)
				)
			)
		)
	)
	(zone
		(layers "B.Cu" "In13.Cu" "In15.Cu")
		(hatch none 0.5)
		(connect_pads
			(clearance 0)
		)
		(min_thickness 0.25)
		(keepout
			(tracks not_allowed)
			(vias allowed)
			(pads allowed)
			(copperpour not_allowed)
			(footprints allowed)
		)
		(placement
			(enabled no)
			(sheetname "")
		)
		(fill yes
			(thermal_gap 0.5)
			(thermal_bridge_width 0.5)
			(island_removal_mode 0)
		)
		(polygon
			(pts
				(arc
					(start 451.237604 -228.766624)
					(mid 450.584824 -228.766624)
					(end 451.237604 -228.766624)
				)
			)
		)
	)
	(zone
		(layers "B.Cu" "In13.Cu" "In15.Cu")
		(hatch none 0.5)
		(connect_pads
			(clearance 0)
		)
		(min_thickness 0.25)
		(keepout
			(tracks not_allowed)
			(vias allowed)
			(pads allowed)
			(copperpour not_allowed)
			(footprints allowed)
		)
		(placement
			(enabled no)
			(sheetname "")
		)
		(fill yes
			(thermal_gap 0.5)
			(thermal_bridge_width 0.5)
			(island_removal_mode 0)
		)
		(polygon
			(pts
				(arc
					(start 140.154914 -428.28972)
					(mid 139.345162 -428.28972)
					(end 140.154914 -428.28972)
				)
			)
		)
	)
	(zone
		(layers "B.Cu" "In13.Cu" "In15.Cu")
		(hatch none 0.5)
		(connect_pads
			(clearance 0)
		)
		(min_thickness 0.25)
		(keepout
			(tracks not_allowed)
			(vias allowed)
			(pads allowed)
			(copperpour not_allowed)
			(footprints allowed)
		)
		(placement
			(enabled no)
			(sheetname "")
		)
		(fill yes
			(thermal_gap 0.5)
			(thermal_bridge_width 0.5)
			(island_removal_mode 0)
		)
		(polygon
			(pts
				(arc
					(start 64.511428 -403.883876)
					(mid 63.807848 -403.883876)
					(end 64.511428 -403.883876)
				)
			)
		)
	)
	(zone
		(layers "B.Cu" "In13.Cu" "In15.Cu")
		(hatch none 0.5)
		(connect_pads
			(clearance 0)
		)
		(min_thickness 0.25)
		(keepout
			(tracks not_allowed)
			(vias allowed)
			(pads allowed)
			(copperpour not_allowed)
			(footprints allowed)
		)
		(placement
			(enabled no)
			(sheetname "")
		)
		(fill yes
			(thermal_gap 0.5)
			(thermal_bridge_width 0.5)
			(island_removal_mode 0)
		)
		(polygon
			(pts
				(arc
					(start 451.237604 -272.966688)
					(mid 450.584824 -272.966688)
					(end 451.237604 -272.966688)
				)
			)
		)
	)
	(zone
		(layers "B.Cu" "In13.Cu" "In15.Cu")
		(hatch none 0.5)
		(connect_pads
			(clearance 0)
		)
		(min_thickness 0.25)
		(keepout
			(tracks not_allowed)
			(vias allowed)
			(pads allowed)
			(copperpour not_allowed)
			(footprints allowed)
		)
		(placement
			(enabled no)
			(sheetname "")
		)
		(fill yes
			(thermal_gap 0.5)
			(thermal_bridge_width 0.5)
			(island_removal_mode 0)
		)
		(polygon
			(pts
				(arc
					(start 347.21927 -236.597952)
					(mid 346.56649 -236.597952)
					(end 347.21927 -236.597952)
				)
			)
		)
	)
	(zone
		(layers "B.Cu" "In13.Cu" "In15.Cu")
		(hatch none 0.5)
		(connect_pads
			(clearance 0)
		)
		(min_thickness 0.25)
		(keepout
			(tracks not_allowed)
			(vias allowed)
			(pads allowed)
			(copperpour not_allowed)
			(footprints allowed)
		)
		(placement
			(enabled no)
			(sheetname "")
		)
		(fill yes
			(thermal_gap 0.5)
			(thermal_bridge_width 0.5)
			(island_removal_mode 0)
		)
		(polygon
			(pts
				(arc
					(start 139.749784 -403.883876)
					(mid 139.046204 -403.883876)
					(end 139.749784 -403.883876)
				)
			)
		)
	)
	(zone
		(layers "B.Cu" "In13.Cu" "In15.Cu")
		(hatch none 0.5)
		(connect_pads
			(clearance 0)
		)
		(min_thickness 0.25)
		(keepout
			(tracks not_allowed)
			(vias allowed)
			(pads allowed)
			(copperpour not_allowed)
			(footprints allowed)
		)
		(placement
			(enabled no)
			(sheetname "")
		)
		(fill yes
			(thermal_gap 0.5)
			(thermal_bridge_width 0.5)
			(island_removal_mode 0)
		)
		(polygon
			(pts
				(arc
					(start 155.065984 -403.883876)
					(mid 154.362404 -403.883876)
					(end 155.065984 -403.883876)
				)
			)
		)
	)
	(zone
		(layers "B.Cu" "In13.Cu" "In15.Cu")
		(hatch none 0.5)
		(connect_pads
			(clearance 0)
		)
		(min_thickness 0.25)
		(keepout
			(tracks not_allowed)
			(vias allowed)
			(pads allowed)
			(copperpour not_allowed)
			(footprints allowed)
		)
		(placement
			(enabled no)
			(sheetname "")
		)
		(fill yes
			(thermal_gap 0.5)
			(thermal_bridge_width 0.5)
			(island_removal_mode 0)
		)
		(polygon
			(pts
				(arc
					(start 374.113806 -265.314176)
					(mid 373.461026 -265.314176)
					(end 374.113806 -265.314176)
				)
			)
		)
	)
	(zone
		(layers "B.Cu" "In13.Cu" "In15.Cu")
		(hatch none 0.5)
		(connect_pads
			(clearance 0)
		)
		(min_thickness 0.25)
		(keepout
			(tracks not_allowed)
			(vias allowed)
			(pads allowed)
			(copperpour not_allowed)
			(footprints allowed)
		)
		(placement
			(enabled no)
			(sheetname "")
		)
		(fill yes
			(thermal_gap 0.5)
			(thermal_bridge_width 0.5)
			(island_removal_mode 0)
		)
		(polygon
			(pts
				(arc
					(start 98.919538 -268.569694)
					(mid 98.266758 -268.569694)
					(end 98.919538 -268.569694)
				)
			)
		)
	)
	(zone
		(layers "B.Cu" "In13.Cu" "In15.Cu")
		(hatch none 0.5)
		(connect_pads
			(clearance 0)
		)
		(min_thickness 0.25)
		(keepout
			(tracks not_allowed)
			(vias allowed)
			(pads allowed)
			(copperpour not_allowed)
			(footprints allowed)
		)
		(placement
			(enabled no)
			(sheetname "")
		)
		(fill yes
			(thermal_gap 0.5)
			(thermal_bridge_width 0.5)
			(island_removal_mode 0)
		)
		(polygon
			(pts
				(arc
					(start 99.389184 -266.128246)
					(mid 98.736404 -266.128246)
					(end 99.389184 -266.128246)
				)
			)
		)
	)
	(zone
		(layers "B.Cu" "In13.Cu" "In15.Cu")
		(hatch none 0.5)
		(connect_pads
			(clearance 0)
		)
		(min_thickness 0.25)
		(keepout
			(tracks not_allowed)
			(vias allowed)
			(pads allowed)
			(copperpour not_allowed)
			(footprints allowed)
		)
		(placement
			(enabled no)
			(sheetname "")
		)
		(fill yes
			(thermal_gap 0.5)
			(thermal_bridge_width 0.5)
			(island_removal_mode 0)
		)
		(polygon
			(pts
				(arc
					(start 21.215604 -301.866808)
					(mid 20.562824 -301.866808)
					(end 21.215604 -301.866808)
				)
			)
		)
	)
	(zone
		(layers "B.Cu" "In13.Cu" "In15.Cu")
		(hatch none 0.5)
		(connect_pads
			(clearance 0)
		)
		(min_thickness 0.25)
		(keepout
			(tracks not_allowed)
			(vias allowed)
			(pads allowed)
			(copperpour not_allowed)
			(footprints allowed)
		)
		(placement
			(enabled no)
			(sheetname "")
		)
		(fill yes
			(thermal_gap 0.5)
			(thermal_bridge_width 0.5)
			(island_removal_mode 0)
		)
		(polygon
			(pts
				(arc
					(start 207.397604 -272.11655)
					(mid 206.744824 -272.11655)
					(end 207.397604 -272.11655)
				)
			)
		)
	)
	(zone
		(layers "B.Cu" "In13.Cu" "In15.Cu")
		(hatch none 0.5)
		(connect_pads
			(clearance 0)
		)
		(min_thickness 0.25)
		(keepout
			(tracks not_allowed)
			(vias allowed)
			(pads allowed)
			(copperpour not_allowed)
			(footprints allowed)
		)
		(placement
			(enabled no)
			(sheetname "")
		)
		(fill yes
			(thermal_gap 0.5)
			(thermal_bridge_width 0.5)
			(island_removal_mode 0)
		)
		(polygon
			(pts
				(arc
					(start 348.15907 -239.853216)
					(mid 347.50629 -239.853216)
					(end 348.15907 -239.853216)
				)
			)
		)
	)
	(zone
		(layers "B.Cu" "In13.Cu" "In15.Cu")
		(hatch none 0.5)
		(connect_pads
			(clearance 0)
		)
		(min_thickness 0.25)
		(keepout
			(tracks not_allowed)
			(vias allowed)
			(pads allowed)
			(copperpour not_allowed)
			(footprints allowed)
		)
		(placement
			(enabled no)
			(sheetname "")
		)
		(fill yes
			(thermal_gap 0.5)
			(thermal_bridge_width 0.5)
			(island_removal_mode 0)
		)
		(polygon
			(pts
				(arc
					(start 88.581484 -284.847538)
					(mid 87.928704 -284.847538)
					(end 88.581484 -284.847538)
				)
			)
		)
	)
	(zone
		(layers "B.Cu" "In13.Cu" "In15.Cu")
		(hatch none 0.5)
		(connect_pads
			(clearance 0)
		)
		(min_thickness 0.25)
		(keepout
			(tracks not_allowed)
			(vias allowed)
			(pads allowed)
			(copperpour not_allowed)
			(footprints allowed)
		)
		(placement
			(enabled no)
			(sheetname "")
		)
		(fill yes
			(thermal_gap 0.5)
			(thermal_bridge_width 0.5)
			(island_removal_mode 0)
		)
		(polygon
			(pts
				(arc
					(start 402.880576 -4.95173)
					(mid 402.176996 -4.95173)
					(end 402.880576 -4.95173)
				)
			)
		)
	)
	(zone
		(layers "B.Cu" "In13.Cu" "In15.Cu")
		(hatch none 0.5)
		(connect_pads
			(clearance 0)
		)
		(min_thickness 0.25)
		(keepout
			(tracks not_allowed)
			(vias allowed)
			(pads allowed)
			(copperpour not_allowed)
			(footprints allowed)
		)
		(placement
			(enabled no)
			(sheetname "")
		)
		(fill yes
			(thermal_gap 0.5)
			(thermal_bridge_width 0.5)
			(island_removal_mode 0)
		)
		(polygon
			(pts
				(arc
					(start 451.237604 -262.76681)
					(mid 450.584824 -262.76681)
					(end 451.237604 -262.76681)
				)
			)
		)
	)
	(zone
		(layers "B.Cu" "In13.Cu" "In15.Cu")
		(hatch none 0.5)
		(connect_pads
			(clearance 0)
		)
		(min_thickness 0.25)
		(keepout
			(tracks not_allowed)
			(vias allowed)
			(pads allowed)
			(copperpour not_allowed)
			(footprints allowed)
		)
		(placement
			(enabled no)
			(sheetname "")
		)
		(fill yes
			(thermal_gap 0.5)
			(thermal_bridge_width 0.5)
			(island_removal_mode 0)
		)
		(polygon
			(pts
				(arc
					(start 431.264314 -4.95173)
					(mid 430.560734 -4.95173)
					(end 431.264314 -4.95173)
				)
			)
		)
	)
	(zone
		(layers "B.Cu" "In13.Cu" "In15.Cu")
		(hatch none 0.5)
		(connect_pads
			(clearance 0)
		)
		(min_thickness 0.25)
		(keepout
			(tracks not_allowed)
			(vias allowed)
			(pads allowed)
			(copperpour not_allowed)
			(footprints allowed)
		)
		(placement
			(enabled no)
			(sheetname "")
		)
		(fill yes
			(thermal_gap 0.5)
			(thermal_bridge_width 0.5)
			(island_removal_mode 0)
		)
		(polygon
			(pts
				(arc
					(start 269.155672 -290.816792)
					(mid 268.502892 -290.816792)
					(end 269.155672 -290.816792)
				)
			)
		)
	)
	(zone
		(layers "B.Cu" "In13.Cu" "In15.Cu")
		(hatch none 0.5)
		(connect_pads
			(clearance 0)
		)
		(min_thickness 0.25)
		(keepout
			(tracks not_allowed)
			(vias allowed)
			(pads allowed)
			(copperpour not_allowed)
			(footprints allowed)
		)
		(placement
			(enabled no)
			(sheetname "")
		)
		(fill yes
			(thermal_gap 0.5)
			(thermal_bridge_width 0.5)
			(island_removal_mode 0)
		)
		(polygon
			(pts
				(arc
					(start 347.21927 -244.73662)
					(mid 346.56649 -244.73662)
					(end 347.21927 -244.73662)
				)
			)
		)
	)
	(zone
		(layers "B.Cu" "In13.Cu" "In15.Cu")
		(hatch none 0.5)
		(connect_pads
			(clearance 0)
		)
		(min_thickness 0.25)
		(keepout
			(tracks not_allowed)
			(vias allowed)
			(pads allowed)
			(copperpour not_allowed)
			(footprints allowed)
		)
		(placement
			(enabled no)
			(sheetname "")
		)
		(fill yes
			(thermal_gap 0.5)
			(thermal_bridge_width 0.5)
			(island_removal_mode 0)
		)
		(polygon
			(pts
				(arc
					(start 100.689156 -240.667286)
					(mid 100.036376 -240.667286)
					(end 100.689156 -240.667286)
				)
			)
		)
	)
	(zone
		(layers "B.Cu" "In13.Cu" "In15.Cu")
		(hatch none 0.5)
		(connect_pads
			(clearance 0)
		)
		(min_thickness 0.25)
		(keepout
			(tracks not_allowed)
			(vias allowed)
			(pads allowed)
			(copperpour not_allowed)
			(footprints allowed)
		)
		(placement
			(enabled no)
			(sheetname "")
		)
		(fill yes
			(thermal_gap 0.5)
			(thermal_bridge_width 0.5)
			(island_removal_mode 0)
		)
		(polygon
			(pts
				(arc
					(start 203.297536 -238.116618)
					(mid 202.644756 -238.116618)
					(end 203.297536 -238.116618)
				)
			)
		)
	)
	(zone
		(layers "B.Cu" "In13.Cu" "In15.Cu")
		(hatch none 0.5)
		(connect_pads
			(clearance 0)
		)
		(min_thickness 0.25)
		(keepout
			(tracks not_allowed)
			(vias allowed)
			(pads allowed)
			(copperpour not_allowed)
			(footprints allowed)
		)
		(placement
			(enabled no)
			(sheetname "")
		)
		(fill yes
			(thermal_gap 0.5)
			(thermal_bridge_width 0.5)
			(island_removal_mode 0)
		)
		(polygon
			(pts
				(arc
					(start 40.14216 -6.724396)
					(mid 39.43858 -6.724396)
					(end 40.14216 -6.724396)
				)
			)
		)
	)
	(zone
		(layers "B.Cu" "In13.Cu" "In15.Cu")
		(hatch none 0.5)
		(connect_pads
			(clearance 0)
		)
		(min_thickness 0.25)
		(keepout
			(tracks not_allowed)
			(vias allowed)
			(pads allowed)
			(copperpour not_allowed)
			(footprints allowed)
		)
		(placement
			(enabled no)
			(sheetname "")
		)
		(fill yes
			(thermal_gap 0.5)
			(thermal_bridge_width 0.5)
			(island_removal_mode 0)
		)
		(polygon
			(pts
				(arc
					(start 17.115536 -275.516594)
					(mid 16.462756 -275.516594)
					(end 17.115536 -275.516594)
				)
			)
		)
	)
	(zone
		(layers "B.Cu" "In13.Cu" "In15.Cu")
		(hatch none 0.5)
		(connect_pads
			(clearance 0)
		)
		(min_thickness 0.25)
		(keepout
			(tracks not_allowed)
			(vias allowed)
			(pads allowed)
			(copperpour not_allowed)
			(footprints allowed)
		)
		(placement
			(enabled no)
			(sheetname "")
		)
		(fill yes
			(thermal_gap 0.5)
			(thermal_bridge_width 0.5)
			(island_removal_mode 0)
		)
		(polygon
			(pts
				(arc
					(start 125.593602 -241.481102)
					(mid 124.940822 -241.481102)
					(end 125.593602 -241.481102)
				)
			)
		)
	)
	(zone
		(layers "B.Cu" "In13.Cu" "In15.Cu")
		(hatch none 0.5)
		(connect_pads
			(clearance 0)
		)
		(min_thickness 0.25)
		(keepout
			(tracks not_allowed)
			(vias allowed)
			(pads allowed)
			(copperpour not_allowed)
			(footprints allowed)
		)
		(placement
			(enabled no)
			(sheetname "")
		)
		(fill yes
			(thermal_gap 0.5)
			(thermal_bridge_width 0.5)
			(island_removal_mode 0)
		)
		(polygon
			(pts
				(arc
					(start 17.115536 -297.616626)
					(mid 16.462756 -297.616626)
					(end 17.115536 -297.616626)
				)
			)
		)
	)
	(zone
		(layers "B.Cu" "In13.Cu" "In15.Cu")
		(hatch none 0.5)
		(connect_pads
			(clearance 0)
		)
		(min_thickness 0.25)
		(keepout
			(tracks not_allowed)
			(vias allowed)
			(pads allowed)
			(copperpour not_allowed)
			(footprints allowed)
		)
		(placement
			(enabled no)
			(sheetname "")
		)
		(fill yes
			(thermal_gap 0.5)
			(thermal_bridge_width 0.5)
			(island_removal_mode 0)
		)
		(polygon
			(pts
				(arc
					(start 151.154892 -426.089826)
					(mid 150.34514 -426.089826)
					(end 151.154892 -426.089826)
				)
			)
		)
	)
	(zone
		(layers "B.Cu" "In13.Cu" "In15.Cu")
		(hatch none 0.5)
		(connect_pads
			(clearance 0)
		)
		(min_thickness 0.25)
		(keepout
			(tracks not_allowed)
			(vias allowed)
			(pads allowed)
			(copperpour not_allowed)
			(footprints allowed)
		)
		(placement
			(enabled no)
			(sheetname "")
		)
		(fill yes
			(thermal_gap 0.5)
			(thermal_bridge_width 0.5)
			(island_removal_mode 0)
		)
		(polygon
			(pts
				(arc
					(start 371.65407 -246.364506)
					(mid 371.00129 -246.364506)
					(end 371.65407 -246.364506)
				)
			)
		)
	)
	(zone
		(layers "B.Cu" "In13.Cu" "In15.Cu")
		(hatch none 0.5)
		(connect_pads
			(clearance 0)
		)
		(min_thickness 0.25)
		(keepout
			(tracks not_allowed)
			(vias allowed)
			(pads allowed)
			(copperpour not_allowed)
			(footprints allowed)
		)
		(placement
			(enabled no)
			(sheetname "")
		)
		(fill yes
			(thermal_gap 0.5)
			(thermal_bridge_width 0.5)
			(island_removal_mode 0)
		)
		(polygon
			(pts
				(arc
					(start 455.337672 -306.116736)
					(mid 454.684892 -306.116736)
					(end 455.337672 -306.116736)
				)
			)
		)
	)
	(zone
		(layers "B.Cu" "In13.Cu" "In15.Cu")
		(hatch none 0.5)
		(connect_pads
			(clearance 0)
		)
		(min_thickness 0.25)
		(keepout
			(tracks not_allowed)
			(vias allowed)
			(pads allowed)
			(copperpour not_allowed)
			(footprints allowed)
		)
		(placement
			(enabled no)
			(sheetname "")
		)
		(fill yes
			(thermal_gap 0.5)
			(thermal_bridge_width 0.5)
			(island_removal_mode 0)
		)
		(polygon
			(pts
				(arc
					(start 21.215604 -220.266768)
					(mid 20.562824 -220.266768)
					(end 21.215604 -220.266768)
				)
			)
		)
	)
	(zone
		(layers "B.Cu" "In13.Cu" "In15.Cu")
		(hatch none 0.5)
		(connect_pads
			(clearance 0)
		)
		(min_thickness 0.25)
		(keepout
			(tracks not_allowed)
			(vias allowed)
			(pads allowed)
			(copperpour not_allowed)
			(footprints allowed)
		)
		(placement
			(enabled no)
			(sheetname "")
		)
		(fill yes
			(thermal_gap 0.5)
			(thermal_bridge_width 0.5)
			(island_removal_mode 0)
		)
		(polygon
			(pts
				(arc
					(start 269.155672 -289.11677)
					(mid 268.502892 -289.11677)
					(end 269.155672 -289.11677)
				)
			)
		)
	)
	(zone
		(layers "B.Cu" "In13.Cu" "In15.Cu")
		(hatch none 0.5)
		(connect_pads
			(clearance 0)
		)
		(min_thickness 0.25)
		(keepout
			(tracks not_allowed)
			(vias allowed)
			(pads allowed)
			(copperpour not_allowed)
			(footprints allowed)
		)
		(placement
			(enabled no)
			(sheetname "")
		)
		(fill yes
			(thermal_gap 0.5)
			(thermal_bridge_width 0.5)
			(island_removal_mode 0)
		)
		(polygon
			(pts
				(arc
					(start 125.233938 -263.686544)
					(mid 124.581158 -263.686544)
					(end 125.233938 -263.686544)
				)
			)
		)
	)
	(zone
		(layers "B.Cu" "In13.Cu" "In15.Cu")
		(hatch none 0.5)
		(connect_pads
			(clearance 0)
		)
		(min_thickness 0.25)
		(keepout
			(tracks not_allowed)
			(vias allowed)
			(pads allowed)
			(copperpour not_allowed)
			(footprints allowed)
		)
		(placement
			(enabled no)
			(sheetname "")
		)
		(fill yes
			(thermal_gap 0.5)
			(thermal_bridge_width 0.5)
			(island_removal_mode 0)
		)
		(polygon
			(pts
				(arc
					(start 347.21927 -228.45903)
					(mid 346.56649 -228.45903)
					(end 347.21927 -228.45903)
				)
			)
		)
	)
	(zone
		(layers "B.Cu" "In13.Cu" "In15.Cu")
		(hatch none 0.5)
		(connect_pads
			(clearance 0)
		)
		(min_thickness 0.25)
		(keepout
			(tracks not_allowed)
			(vias allowed)
			(pads allowed)
			(copperpour not_allowed)
			(footprints allowed)
		)
		(placement
			(enabled no)
			(sheetname "")
		)
		(fill yes
			(thermal_gap 0.5)
			(thermal_bridge_width 0.5)
			(island_removal_mode 0)
		)
		(polygon
			(pts
				(arc
					(start 101.158802 -234.970066)
					(mid 100.506022 -234.970066)
					(end 101.158802 -234.970066)
				)
			)
		)
	)
	(zone
		(layers "B.Cu" "In13.Cu" "In15.Cu")
		(hatch none 0.5)
		(connect_pads
			(clearance 0)
		)
		(min_thickness 0.25)
		(keepout
			(tracks not_allowed)
			(vias allowed)
			(pads allowed)
			(copperpour not_allowed)
			(footprints allowed)
		)
		(placement
			(enabled no)
			(sheetname "")
		)
		(fill yes
			(thermal_gap 0.5)
			(thermal_bridge_width 0.5)
			(island_removal_mode 0)
		)
		(polygon
			(pts
				(arc
					(start 17.115536 -282.316682)
					(mid 16.462756 -282.316682)
					(end 17.115536 -282.316682)
				)
			)
		)
	)
	(zone
		(layers "B.Cu" "In13.Cu" "In15.Cu")
		(hatch none 0.5)
		(connect_pads
			(clearance 0)
		)
		(min_thickness 0.25)
		(keepout
			(tracks not_allowed)
			(vias allowed)
			(pads allowed)
			(copperpour not_allowed)
			(footprints allowed)
		)
		(placement
			(enabled no)
			(sheetname "")
		)
		(fill yes
			(thermal_gap 0.5)
			(thermal_bridge_width 0.5)
			(island_removal_mode 0)
		)
		(polygon
			(pts
				(arc
					(start 269.155672 -267.016738)
					(mid 268.502892 -267.016738)
					(end 269.155672 -267.016738)
				)
			)
		)
	)
	(zone
		(layers "B.Cu" "In13.Cu" "In15.Cu")
		(hatch none 0.5)
		(connect_pads
			(clearance 0)
		)
		(min_thickness 0.25)
		(keepout
			(tracks not_allowed)
			(vias allowed)
			(pads allowed)
			(copperpour not_allowed)
			(footprints allowed)
		)
		(placement
			(enabled no)
			(sheetname "")
		)
		(fill yes
			(thermal_gap 0.5)
			(thermal_bridge_width 0.5)
			(island_removal_mode 0)
		)
		(polygon
			(pts
				(arc
					(start 353.79787 -220.319854)
					(mid 353.14509 -220.319854)
					(end 353.79787 -220.319854)
				)
			)
		)
	)
	(zone
		(layers "B.Cu" "In13.Cu" "In15.Cu")
		(hatch none 0.5)
		(connect_pads
			(clearance 0)
		)
		(min_thickness 0.25)
		(keepout
			(tracks not_allowed)
			(vias allowed)
			(pads allowed)
			(copperpour not_allowed)
			(footprints allowed)
		)
		(placement
			(enabled no)
			(sheetname "")
		)
		(fill yes
			(thermal_gap 0.5)
			(thermal_bridge_width 0.5)
			(island_removal_mode 0)
		)
		(polygon
			(pts
				(arc
					(start 346.859606 -276.708616)
					(mid 346.206826 -276.708616)
					(end 346.859606 -276.708616)
				)
			)
		)
	)
	(zone
		(layers "B.Cu" "In13.Cu" "In15.Cu")
		(hatch none 0.5)
		(connect_pads
			(clearance 0)
		)
		(min_thickness 0.25)
		(keepout
			(tracks not_allowed)
			(vias allowed)
			(pads allowed)
			(copperpour not_allowed)
			(footprints allowed)
		)
		(placement
			(enabled no)
			(sheetname "")
		)
		(fill yes
			(thermal_gap 0.5)
			(thermal_bridge_width 0.5)
			(island_removal_mode 0)
		)
		(polygon
			(pts
				(arc
					(start 111.496602 -220.319854)
					(mid 110.843822 -220.319854)
					(end 111.496602 -220.319854)
				)
			)
		)
	)
	(zone
		(layers "B.Cu" "In13.Cu" "In15.Cu")
		(hatch none 0.5)
		(connect_pads
			(clearance 0)
		)
		(min_thickness 0.25)
		(keepout
			(tracks not_allowed)
			(vias allowed)
			(pads allowed)
			(copperpour not_allowed)
			(footprints allowed)
		)
		(placement
			(enabled no)
			(sheetname "")
		)
		(fill yes
			(thermal_gap 0.5)
			(thermal_bridge_width 0.5)
			(island_removal_mode 0)
		)
		(polygon
			(pts
				(arc
					(start 95.990156 -248.806208)
					(mid 95.337376 -248.806208)
					(end 95.990156 -248.806208)
				)
			)
		)
	)
	(zone
		(layers "B.Cu" "In13.Cu" "In15.Cu")
		(hatch none 0.5)
		(connect_pads
			(clearance 0)
		)
		(min_thickness 0.25)
		(keepout
			(tracks not_allowed)
			(vias allowed)
			(pads allowed)
			(copperpour not_allowed)
			(footprints allowed)
		)
		(placement
			(enabled no)
			(sheetname "")
		)
		(fill yes
			(thermal_gap 0.5)
			(thermal_bridge_width 0.5)
			(island_removal_mode 0)
		)
		(polygon
			(pts
				(arc
					(start 371.65407 -243.108988)
					(mid 371.00129 -243.108988)
					(end 371.65407 -243.108988)
				)
			)
		)
	)
	(zone
		(layers "B.Cu" "In13.Cu" "In15.Cu")
		(hatch none 0.5)
		(connect_pads
			(clearance 0)
		)
		(min_thickness 0.25)
		(keepout
			(tracks not_allowed)
			(vias allowed)
			(pads allowed)
			(copperpour not_allowed)
			(footprints allowed)
		)
		(placement
			(enabled no)
			(sheetname "")
		)
		(fill yes
			(thermal_gap 0.5)
			(thermal_bridge_width 0.5)
			(island_removal_mode 0)
		)
		(polygon
			(pts
				(arc
					(start 319.054988 -430.889918)
					(mid 318.245236 -430.889918)
					(end 319.054988 -430.889918)
				)
			)
		)
	)
	(zone
		(layers "B.Cu" "In13.Cu" "In15.Cu")
		(hatch none 0.5)
		(connect_pads
			(clearance 0)
		)
		(min_thickness 0.25)
		(keepout
			(tracks not_allowed)
			(vias allowed)
			(pads allowed)
			(copperpour not_allowed)
			(footprints allowed)
		)
		(placement
			(enabled no)
			(sheetname "")
		)
		(fill yes
			(thermal_gap 0.5)
			(thermal_bridge_width 0.5)
			(island_removal_mode 0)
		)
		(polygon
			(pts
				(arc
					(start 342.436958 -410.030168)
					(mid 341.733378 -410.030168)
					(end 342.436958 -410.030168)
				)
			)
		)
	)
	(zone
		(layers "B.Cu" "In13.Cu" "In15.Cu")
		(hatch none 0.5)
		(connect_pads
			(clearance 0)
		)
		(min_thickness 0.25)
		(keepout
			(tracks not_allowed)
			(vias allowed)
			(pads allowed)
			(copperpour not_allowed)
			(footprints allowed)
		)
		(placement
			(enabled no)
			(sheetname "")
		)
		(fill yes
			(thermal_gap 0.5)
			(thermal_bridge_width 0.5)
			(island_removal_mode 0)
		)
		(polygon
			(pts
				(arc
					(start 371.764052 -254.733552)
					(mid 371.111272 -254.733552)
					(end 371.764052 -254.733552)
				)
			)
		)
	)
	(zone
		(layers "B.Cu" "In13.Cu" "In15.Cu")
		(hatch none 0.5)
		(connect_pads
			(clearance 0)
		)
		(min_thickness 0.25)
		(keepout
			(tracks not_allowed)
			(vias allowed)
			(pads allowed)
			(copperpour not_allowed)
			(footprints allowed)
		)
		(placement
			(enabled no)
			(sheetname "")
		)
		(fill yes
			(thermal_gap 0.5)
			(thermal_bridge_width 0.5)
			(island_removal_mode 0)
		)
		(polygon
			(pts
				(arc
					(start 349.09887 -239.853216)
					(mid 348.44609 -239.853216)
					(end 349.09887 -239.853216)
				)
			)
		)
	)
	(zone
		(layers "B.Cu" "In13.Cu" "In15.Cu")
		(hatch none 0.5)
		(connect_pads
			(clearance 0)
		)
		(min_thickness 0.25)
		(keepout
			(tracks not_allowed)
			(vias allowed)
			(pads allowed)
			(copperpour not_allowed)
			(footprints allowed)
		)
		(placement
			(enabled no)
			(sheetname "")
		)
		(fill yes
			(thermal_gap 0.5)
			(thermal_bridge_width 0.5)
			(island_removal_mode 0)
		)
		(polygon
			(pts
				(arc
					(start 123.714002 -238.225584)
					(mid 123.061222 -238.225584)
					(end 123.714002 -238.225584)
				)
			)
		)
	)
	(zone
		(layers "B.Cu" "In13.Cu" "In15.Cu")
		(hatch none 0.5)
		(connect_pads
			(clearance 0)
		)
		(min_thickness 0.25)
		(keepout
			(tracks not_allowed)
			(vias allowed)
			(pads allowed)
			(copperpour not_allowed)
			(footprints allowed)
		)
		(placement
			(enabled no)
			(sheetname "")
		)
		(fill yes
			(thermal_gap 0.5)
			(thermal_bridge_width 0.5)
			(island_removal_mode 0)
		)
		(polygon
			(pts
				(arc
					(start 347.329252 -259.616956)
					(mid 346.676472 -259.616956)
					(end 347.329252 -259.616956)
				)
			)
		)
	)
	(zone
		(layers "B.Cu" "In13.Cu" "In15.Cu")
		(hatch none 0.5)
		(connect_pads
			(clearance 0)
		)
		(min_thickness 0.25)
		(keepout
			(tracks not_allowed)
			(vias allowed)
			(pads allowed)
			(copperpour not_allowed)
			(footprints allowed)
		)
		(placement
			(enabled no)
			(sheetname "")
		)
		(fill yes
			(thermal_gap 0.5)
			(thermal_bridge_width 0.5)
			(island_removal_mode 0)
		)
		(polygon
			(pts
				(arc
					(start 17.115536 -227.91674)
					(mid 16.462756 -227.91674)
					(end 17.115536 -227.91674)
				)
			)
		)
	)
	(zone
		(layers "B.Cu" "In13.Cu" "In15.Cu")
		(hatch none 0.5)
		(connect_pads
			(clearance 0)
		)
		(min_thickness 0.25)
		(keepout
			(tracks not_allowed)
			(vias allowed)
			(pads allowed)
			(copperpour not_allowed)
			(footprints allowed)
		)
		(placement
			(enabled no)
			(sheetname "")
		)
		(fill yes
			(thermal_gap 0.5)
			(thermal_bridge_width 0.5)
			(island_removal_mode 0)
		)
		(polygon
			(pts
				(arc
					(start 123.823984 -254.733552)
					(mid 123.171204 -254.733552)
					(end 123.823984 -254.733552)
				)
			)
		)
	)
	(zone
		(layers "B.Cu" "In13.Cu" "In15.Cu")
		(hatch none 0.5)
		(connect_pads
			(clearance 0)
		)
		(min_thickness 0.25)
		(keepout
			(tracks not_allowed)
			(vias allowed)
			(pads allowed)
			(copperpour not_allowed)
			(footprints allowed)
		)
		(placement
			(enabled no)
			(sheetname "")
		)
		(fill yes
			(thermal_gap 0.5)
			(thermal_bridge_width 0.5)
			(island_removal_mode 0)
		)
		(polygon
			(pts
				(arc
					(start 332.054962 -430.889918)
					(mid 331.24521 -430.889918)
					(end 332.054962 -430.889918)
				)
			)
		)
	)
	(zone
		(layers "B.Cu" "In13.Cu" "In15.Cu")
		(hatch none 0.5)
		(connect_pads
			(clearance 0)
		)
		(min_thickness 0.25)
		(keepout
			(tracks not_allowed)
			(vias allowed)
			(pads allowed)
			(copperpour not_allowed)
			(footprints allowed)
		)
		(placement
			(enabled no)
			(sheetname "")
		)
		(fill yes
			(thermal_gap 0.5)
			(thermal_bridge_width 0.5)
			(island_removal_mode 0)
		)
		(polygon
			(pts
				(arc
					(start 104.918002 -221.94774)
					(mid 104.265222 -221.94774)
					(end 104.918002 -221.94774)
				)
			)
		)
	)
	(zone
		(layers "B.Cu" "In13.Cu" "In15.Cu")
		(hatch none 0.5)
		(connect_pads
			(clearance 0)
		)
		(min_thickness 0.25)
		(keepout
			(tracks not_allowed)
			(vias allowed)
			(pads allowed)
			(copperpour not_allowed)
			(footprints allowed)
		)
		(placement
			(enabled no)
			(sheetname "")
		)
		(fill yes
			(thermal_gap 0.5)
			(thermal_bridge_width 0.5)
			(island_removal_mode 0)
		)
		(polygon
			(pts
				(arc
					(start 39.27856 -6.724396)
					(mid 38.57498 -6.724396)
					(end 39.27856 -6.724396)
				)
			)
		)
	)
	(zone
		(layers "B.Cu" "In13.Cu" "In15.Cu")
		(hatch none 0.5)
		(connect_pads
			(clearance 0)
		)
		(min_thickness 0.25)
		(keepout
			(tracks not_allowed)
			(vias allowed)
			(pads allowed)
			(copperpour not_allowed)
			(footprints allowed)
		)
		(placement
			(enabled no)
			(sheetname "")
		)
		(fill yes
			(thermal_gap 0.5)
			(thermal_bridge_width 0.5)
			(island_removal_mode 0)
		)
		(polygon
			(pts
				(arc
					(start 346.27947 -244.73662)
					(mid 345.62669 -244.73662)
					(end 346.27947 -244.73662)
				)
			)
		)
	)
	(zone
		(layers "B.Cu" "In13.Cu" "In15.Cu")
		(hatch none 0.5)
		(connect_pads
			(clearance 0)
		)
		(min_thickness 0.25)
		(keepout
			(tracks not_allowed)
			(vias allowed)
			(pads allowed)
			(copperpour not_allowed)
			(footprints allowed)
		)
		(placement
			(enabled no)
			(sheetname "")
		)
		(fill yes
			(thermal_gap 0.5)
			(thermal_bridge_width 0.5)
			(island_removal_mode 0)
		)
		(polygon
			(pts
				(arc
					(start 343.46007 -247.992138)
					(mid 342.80729 -247.992138)
					(end 343.46007 -247.992138)
				)
			)
		)
	)
	(zone
		(layers "B.Cu" "In13.Cu" "In15.Cu")
		(hatch none 0.5)
		(connect_pads
			(clearance 0)
		)
		(min_thickness 0.25)
		(keepout
			(tracks not_allowed)
			(vias allowed)
			(pads allowed)
			(copperpour not_allowed)
			(footprints allowed)
		)
		(placement
			(enabled no)
			(sheetname "")
		)
		(fill yes
			(thermal_gap 0.5)
			(thermal_bridge_width 0.5)
			(island_removal_mode 0)
		)
		(polygon
			(pts
				(arc
					(start 147.1549 -427.289976)
					(mid 146.345148 -427.289976)
					(end 147.1549 -427.289976)
				)
			)
		)
	)
	(zone
		(layers "B.Cu" "In13.Cu" "In15.Cu")
		(hatch none 0.5)
		(connect_pads
			(clearance 0)
		)
		(min_thickness 0.25)
		(keepout
			(tracks not_allowed)
			(vias allowed)
			(pads allowed)
			(copperpour not_allowed)
			(footprints allowed)
		)
		(placement
			(enabled no)
			(sheetname "")
		)
		(fill yes
			(thermal_gap 0.5)
			(thermal_bridge_width 0.5)
			(island_removal_mode 0)
		)
		(polygon
			(pts
				(arc
					(start 132.759704 -403.883876)
					(mid 132.056124 -403.883876)
					(end 132.759704 -403.883876)
				)
			)
		)
	)
	(zone
		(layers "B.Cu" "In13.Cu" "In15.Cu")
		(hatch none 0.5)
		(connect_pads
			(clearance 0)
		)
		(min_thickness 0.25)
		(keepout
			(tracks not_allowed)
			(vias allowed)
			(pads allowed)
			(copperpour not_allowed)
			(footprints allowed)
		)
		(placement
			(enabled no)
			(sheetname "")
		)
		(fill yes
			(thermal_gap 0.5)
			(thermal_bridge_width 0.5)
			(island_removal_mode 0)
		)
		(polygon
			(pts
				(arc
					(start 76.764388 -403.883876)
					(mid 76.060808 -403.883876)
					(end 76.764388 -403.883876)
				)
			)
		)
	)
	(zone
		(layers "B.Cu" "In13.Cu" "In15.Cu")
		(hatch none 0.5)
		(connect_pads
			(clearance 0)
		)
		(min_thickness 0.25)
		(keepout
			(tracks not_allowed)
			(vias allowed)
			(pads allowed)
			(copperpour not_allowed)
			(footprints allowed)
		)
		(placement
			(enabled no)
			(sheetname "")
		)
		(fill yes
			(thermal_gap 0.5)
			(thermal_bridge_width 0.5)
			(island_removal_mode 0)
		)
		(polygon
			(pts
				(arc
					(start 98.449384 -267.755878)
					(mid 97.796604 -267.755878)
					(end 98.449384 -267.755878)
				)
			)
		)
	)
	(zone
		(layers "B.Cu" "In13.Cu" "In15.Cu")
		(hatch none 0.5)
		(connect_pads
			(clearance 0)
		)
		(min_thickness 0.25)
		(keepout
			(tracks not_allowed)
			(vias allowed)
			(pads allowed)
			(copperpour not_allowed)
			(footprints allowed)
		)
		(placement
			(enabled no)
			(sheetname "")
		)
		(fill yes
			(thermal_gap 0.5)
			(thermal_bridge_width 0.5)
			(island_removal_mode 0)
		)
		(polygon
			(pts
				(arc
					(start 207.397604 -295.06672)
					(mid 206.744824 -295.06672)
					(end 207.397604 -295.06672)
				)
			)
		)
	)
	(zone
		(layers "B.Cu" "In13.Cu" "In15.Cu")
		(hatch none 0.5)
		(connect_pads
			(clearance 0)
		)
		(min_thickness 0.25)
		(keepout
			(tracks not_allowed)
			(vias allowed)
			(pads allowed)
			(copperpour not_allowed)
			(footprints allowed)
		)
		(placement
			(enabled no)
			(sheetname "")
		)
		(fill yes
			(thermal_gap 0.5)
			(thermal_bridge_width 0.5)
			(island_removal_mode 0)
		)
		(polygon
			(pts
				(arc
					(start 126.063756 -227.64496)
					(mid 125.410976 -227.64496)
					(end 126.063756 -227.64496)
				)
			)
		)
	)
	(zone
		(layers "B.Cu" "In13.Cu" "In15.Cu")
		(hatch none 0.5)
		(connect_pads
			(clearance 0)
		)
		(min_thickness 0.25)
		(keepout
			(tracks not_allowed)
			(vias allowed)
			(pads allowed)
			(copperpour not_allowed)
			(footprints allowed)
		)
		(placement
			(enabled no)
			(sheetname "")
		)
		(fill yes
			(thermal_gap 0.5)
			(thermal_bridge_width 0.5)
			(island_removal_mode 0)
		)
		(polygon
			(pts
				(arc
					(start 346.389452 -280.778204)
					(mid 345.736672 -280.778204)
					(end 346.389452 -280.778204)
				)
			)
		)
	)
	(zone
		(layers "B.Cu" "In13.Cu" "In15.Cu")
		(hatch none 0.5)
		(connect_pads
			(clearance 0)
		)
		(min_thickness 0.25)
		(keepout
			(tracks not_allowed)
			(vias allowed)
			(pads allowed)
			(copperpour not_allowed)
			(footprints allowed)
		)
		(placement
			(enabled no)
			(sheetname "")
		)
		(fill yes
			(thermal_gap 0.5)
			(thermal_bridge_width 0.5)
			(island_removal_mode 0)
		)
		(polygon
			(pts
				(arc
					(start 357.55707 -220.319854)
					(mid 356.90429 -220.319854)
					(end 357.55707 -220.319854)
				)
			)
		)
	)
	(zone
		(layers "B.Cu" "In13.Cu" "In15.Cu")
		(hatch none 0.5)
		(connect_pads
			(clearance 0)
		)
		(min_thickness 0.25)
		(keepout
			(tracks not_allowed)
			(vias allowed)
			(pads allowed)
			(copperpour not_allowed)
			(footprints allowed)
		)
		(placement
			(enabled no)
			(sheetname "")
		)
		(fill yes
			(thermal_gap 0.5)
			(thermal_bridge_width 0.5)
			(island_removal_mode 0)
		)
		(polygon
			(pts
				(arc
					(start 348.739206 -271.825212)
					(mid 348.086426 -271.825212)
					(end 348.739206 -271.825212)
				)
			)
		)
	)
	(zone
		(layers "B.Cu" "In13.Cu" "In15.Cu")
		(hatch none 0.5)
		(connect_pads
			(clearance 0)
		)
		(min_thickness 0.25)
		(keepout
			(tracks not_allowed)
			(vias allowed)
			(pads allowed)
			(copperpour not_allowed)
			(footprints allowed)
		)
		(placement
			(enabled no)
			(sheetname "")
		)
		(fill yes
			(thermal_gap 0.5)
			(thermal_bridge_width 0.5)
			(island_removal_mode 0)
		)
		(polygon
			(pts
				(arc
					(start 125.123956 -234.15625)
					(mid 124.471176 -234.15625)
					(end 125.123956 -234.15625)
				)
			)
		)
	)
	(zone
		(layers "B.Cu" "In13.Cu" "In15.Cu")
		(hatch none 0.5)
		(connect_pads
			(clearance 0)
		)
		(min_thickness 0.25)
		(keepout
			(tracks not_allowed)
			(vias allowed)
			(pads allowed)
			(copperpour not_allowed)
			(footprints allowed)
		)
		(placement
			(enabled no)
			(sheetname "")
		)
		(fill yes
			(thermal_gap 0.5)
			(thermal_bridge_width 0.5)
			(island_removal_mode 0)
		)
		(polygon
			(pts
				(arc
					(start 394.154914 -427.289976)
					(mid 393.345162 -427.289976)
					(end 394.154914 -427.289976)
				)
			)
		)
	)
	(zone
		(layers "B.Cu" "In13.Cu" "In15.Cu")
		(hatch none 0.5)
		(connect_pads
			(clearance 0)
		)
		(min_thickness 0.25)
		(keepout
			(tracks not_allowed)
			(vias allowed)
			(pads allowed)
			(copperpour not_allowed)
			(footprints allowed)
		)
		(placement
			(enabled no)
			(sheetname "")
		)
		(fill yes
			(thermal_gap 0.5)
			(thermal_bridge_width 0.5)
			(island_removal_mode 0)
		)
		(polygon
			(pts
				(arc
					(start 342.054942 -430.689766)
					(mid 341.24519 -430.689766)
					(end 342.054942 -430.689766)
				)
			)
		)
	)
	(zone
		(layers "B.Cu" "In13.Cu" "In15.Cu")
		(hatch none 0.5)
		(connect_pads
			(clearance 0)
		)
		(min_thickness 0.25)
		(keepout
			(tracks not_allowed)
			(vias allowed)
			(pads allowed)
			(copperpour not_allowed)
			(footprints allowed)
		)
		(placement
			(enabled no)
			(sheetname "")
		)
		(fill yes
			(thermal_gap 0.5)
			(thermal_bridge_width 0.5)
			(island_removal_mode 0)
		)
		(polygon
			(pts
				(arc
					(start 373.064024 -243.922804)
					(mid 372.411244 -243.922804)
					(end 373.064024 -243.922804)
				)
			)
		)
	)
	(zone
		(layers "B.Cu" "In13.Cu" "In15.Cu")
		(hatch none 0.5)
		(connect_pads
			(clearance 0)
		)
		(min_thickness 0.25)
		(keepout
			(tracks not_allowed)
			(vias allowed)
			(pads allowed)
			(copperpour not_allowed)
			(footprints allowed)
		)
		(placement
			(enabled no)
			(sheetname "")
		)
		(fill yes
			(thermal_gap 0.5)
			(thermal_bridge_width 0.5)
			(island_removal_mode 0)
		)
		(polygon
			(pts
				(arc
					(start 346.054934 -431.889916)
					(mid 345.245182 -431.889916)
					(end 346.054934 -431.889916)
				)
			)
		)
	)
	(zone
		(layers "B.Cu" "In13.Cu" "In15.Cu")
		(hatch none 0.5)
		(connect_pads
			(clearance 0)
		)
		(min_thickness 0.25)
		(keepout
			(tracks not_allowed)
			(vias allowed)
			(pads allowed)
			(copperpour not_allowed)
			(footprints allowed)
		)
		(placement
			(enabled no)
			(sheetname "")
		)
		(fill yes
			(thermal_gap 0.5)
			(thermal_bridge_width 0.5)
			(island_removal_mode 0)
		)
		(polygon
			(pts
				(arc
					(start 207.397604 -281.466544)
					(mid 206.744824 -281.466544)
					(end 207.397604 -281.466544)
				)
			)
		)
	)
	(zone
		(layers "B.Cu" "In13.Cu" "In15.Cu")
		(hatch none 0.5)
		(connect_pads
			(clearance 0)
		)
		(min_thickness 0.25)
		(keepout
			(tracks not_allowed)
			(vias allowed)
			(pads allowed)
			(copperpour not_allowed)
			(footprints allowed)
		)
		(placement
			(enabled no)
			(sheetname "")
		)
		(fill yes
			(thermal_gap 0.5)
			(thermal_bridge_width 0.5)
			(island_removal_mode 0)
		)
		(polygon
			(pts
				(arc
					(start 98.809556 -243.922804)
					(mid 98.156776 -243.922804)
					(end 98.809556 -243.922804)
				)
			)
		)
	)
	(zone
		(layers "B.Cu" "In13.Cu" "In15.Cu")
		(hatch none 0.5)
		(connect_pads
			(clearance 0)
		)
		(min_thickness 0.25)
		(keepout
			(tracks not_allowed)
			(vias allowed)
			(pads allowed)
			(copperpour not_allowed)
			(footprints allowed)
		)
		(placement
			(enabled no)
			(sheetname "")
		)
		(fill yes
			(thermal_gap 0.5)
			(thermal_bridge_width 0.5)
			(island_removal_mode 0)
		)
		(polygon
			(pts
				(arc
					(start 371.764052 -275.8948)
					(mid 371.111272 -275.8948)
					(end 371.764052 -275.8948)
				)
			)
		)
	)
	(zone
		(layers "B.Cu" "In13.Cu" "In15.Cu")
		(hatch none 0.5)
		(connect_pads
			(clearance 0)
		)
		(min_thickness 0.25)
		(keepout
			(tracks not_allowed)
			(vias allowed)
			(pads allowed)
			(copperpour not_allowed)
			(footprints allowed)
		)
		(placement
			(enabled no)
			(sheetname "")
		)
		(fill yes
			(thermal_gap 0.5)
			(thermal_bridge_width 0.5)
			(island_removal_mode 0)
		)
		(polygon
			(pts
				(arc
					(start 128.154938 -427.089824)
					(mid 127.345186 -427.089824)
					(end 128.154938 -427.089824)
				)
			)
		)
	)
	(zone
		(layers "B.Cu" "In13.Cu" "In15.Cu")
		(hatch none 0.5)
		(connect_pads
			(clearance 0)
		)
		(min_thickness 0.25)
		(keepout
			(tracks not_allowed)
			(vias allowed)
			(pads allowed)
			(copperpour not_allowed)
			(footprints allowed)
		)
		(placement
			(enabled no)
			(sheetname "")
		)
		(fill yes
			(thermal_gap 0.5)
			(thermal_bridge_width 0.5)
			(island_removal_mode 0)
		)
		(polygon
			(pts
				(arc
					(start 124.294138 -270.19758)
					(mid 123.641358 -270.19758)
					(end 124.294138 -270.19758)
				)
			)
		)
	)
	(zone
		(layers "B.Cu" "In13.Cu" "In15.Cu")
		(hatch none 0.5)
		(connect_pads
			(clearance 0)
		)
		(min_thickness 0.25)
		(keepout
			(tracks not_allowed)
			(vias allowed)
			(pads allowed)
			(copperpour not_allowed)
			(footprints allowed)
		)
		(placement
			(enabled no)
			(sheetname "")
		)
		(fill yes
			(thermal_gap 0.5)
			(thermal_bridge_width 0.5)
			(island_removal_mode 0)
		)
		(polygon
			(pts
				(arc
					(start 371.65407 -233.34218)
					(mid 371.00129 -233.34218)
					(end 371.65407 -233.34218)
				)
			)
		)
	)
	(zone
		(layers "B.Cu" "In13.Cu" "In15.Cu")
		(hatch none 0.5)
		(connect_pads
			(clearance 0)
		)
		(min_thickness 0.25)
		(keepout
			(tracks not_allowed)
			(vias allowed)
			(pads allowed)
			(copperpour not_allowed)
			(footprints allowed)
		)
		(placement
			(enabled no)
			(sheetname "")
		)
		(fill yes
			(thermal_gap 0.5)
			(thermal_bridge_width 0.5)
			(island_removal_mode 0)
		)
		(polygon
			(pts
				(arc
					(start 265.055604 -306.96662)
					(mid 264.402824 -306.96662)
					(end 265.055604 -306.96662)
				)
			)
		)
	)
	(zone
		(layers "B.Cu" "In13.Cu" "In15.Cu")
		(hatch none 0.5)
		(connect_pads
			(clearance 0)
		)
		(min_thickness 0.25)
		(keepout
			(tracks not_allowed)
			(vias allowed)
			(pads allowed)
			(copperpour not_allowed)
			(footprints allowed)
		)
		(placement
			(enabled no)
			(sheetname "")
		)
		(fill yes
			(thermal_gap 0.5)
			(thermal_bridge_width 0.5)
			(island_removal_mode 0)
		)
		(polygon
			(pts
				(arc
					(start 207.397604 -276.366732)
					(mid 206.744824 -276.366732)
					(end 207.397604 -276.366732)
				)
			)
		)
	)
	(zone
		(layers "B.Cu" "In13.Cu" "In15.Cu")
		(hatch none 0.5)
		(connect_pads
			(clearance 0)
		)
		(min_thickness 0.25)
		(keepout
			(tracks not_allowed)
			(vias allowed)
			(pads allowed)
			(copperpour not_allowed)
			(footprints allowed)
		)
		(placement
			(enabled no)
			(sheetname "")
		)
		(fill yes
			(thermal_gap 0.5)
			(thermal_bridge_width 0.5)
			(island_removal_mode 0)
		)
		(polygon
			(pts
				(arc
					(start 17.115536 -222.816674)
					(mid 16.462756 -222.816674)
					(end 17.115536 -222.816674)
				)
			)
		)
	)
	(zone
		(layers "B.Cu" "In13.Cu" "In15.Cu")
		(hatch none 0.5)
		(connect_pads
			(clearance 0)
		)
		(min_thickness 0.25)
		(keepout
			(tracks not_allowed)
			(vias allowed)
			(pads allowed)
			(copperpour not_allowed)
			(footprints allowed)
		)
		(placement
			(enabled no)
			(sheetname "")
		)
		(fill yes
			(thermal_gap 0.5)
			(thermal_bridge_width 0.5)
			(island_removal_mode 0)
		)
		(polygon
			(pts
				(arc
					(start 21.215604 -263.616694)
					(mid 20.562824 -263.616694)
					(end 21.215604 -263.616694)
				)
			)
		)
	)
	(zone
		(layers "B.Cu" "In13.Cu" "In15.Cu")
		(hatch none 0.5)
		(connect_pads
			(clearance 0)
		)
		(min_thickness 0.25)
		(keepout
			(tracks not_allowed)
			(vias allowed)
			(pads allowed)
			(copperpour not_allowed)
			(footprints allowed)
		)
		(placement
			(enabled no)
			(sheetname "")
		)
		(fill yes
			(thermal_gap 0.5)
			(thermal_bridge_width 0.5)
			(island_removal_mode 0)
		)
		(polygon
			(pts
				(arc
					(start 269.155672 -221.96679)
					(mid 268.502892 -221.96679)
					(end 269.155672 -221.96679)
				)
			)
		)
	)
	(zone
		(layers "B.Cu" "In13.Cu" "In15.Cu")
		(hatch none 0.5)
		(connect_pads
			(clearance 0)
		)
		(min_thickness 0.25)
		(keepout
			(tracks not_allowed)
			(vias allowed)
			(pads allowed)
			(copperpour not_allowed)
			(footprints allowed)
		)
		(placement
			(enabled no)
			(sheetname "")
		)
		(fill yes
			(thermal_gap 0.5)
			(thermal_bridge_width 0.5)
			(island_removal_mode 0)
		)
		(polygon
			(pts
				(arc
					(start 349.208852 -267.755878)
					(mid 348.556072 -267.755878)
					(end 349.208852 -267.755878)
				)
			)
		)
	)
	(zone
		(layers "B.Cu" "In13.Cu" "In15.Cu")
		(hatch none 0.5)
		(connect_pads
			(clearance 0)
		)
		(min_thickness 0.25)
		(keepout
			(tracks not_allowed)
			(vias allowed)
			(pads allowed)
			(copperpour not_allowed)
			(footprints allowed)
		)
		(placement
			(enabled no)
			(sheetname "")
		)
		(fill yes
			(thermal_gap 0.5)
			(thermal_bridge_width 0.5)
			(island_removal_mode 0)
		)
		(polygon
			(pts
				(arc
					(start 372.124224 -237.411514)
					(mid 371.471444 -237.411514)
					(end 372.124224 -237.411514)
				)
			)
		)
	)
	(zone
		(layers "B.Cu" "In13.Cu" "In15.Cu")
		(hatch none 0.5)
		(connect_pads
			(clearance 0)
		)
		(min_thickness 0.25)
		(keepout
			(tracks not_allowed)
			(vias allowed)
			(pads allowed)
			(copperpour not_allowed)
			(footprints allowed)
		)
		(placement
			(enabled no)
			(sheetname "")
		)
		(fill yes
			(thermal_gap 0.5)
			(thermal_bridge_width 0.5)
			(island_removal_mode 0)
		)
		(polygon
			(pts
				(arc
					(start 372.234206 -257.175254)
					(mid 371.581426 -257.175254)
					(end 372.234206 -257.175254)
				)
			)
		)
	)
	(zone
		(layers "B.Cu" "In13.Cu" "In15.Cu")
		(hatch none 0.5)
		(connect_pads
			(clearance 0)
		)
		(min_thickness 0.25)
		(keepout
			(tracks not_allowed)
			(vias allowed)
			(pads allowed)
			(copperpour not_allowed)
			(footprints allowed)
		)
		(placement
			(enabled no)
			(sheetname "")
		)
		(fill yes
			(thermal_gap 0.5)
			(thermal_bridge_width 0.5)
			(island_removal_mode 0)
		)
		(polygon
			(pts
				(arc
					(start 265.055604 -286.56661)
					(mid 264.402824 -286.56661)
					(end 265.055604 -286.56661)
				)
			)
		)
	)
	(zone
		(layers "B.Cu" "In13.Cu" "In15.Cu")
		(hatch none 0.5)
		(connect_pads
			(clearance 0)
		)
		(min_thickness 0.25)
		(keepout
			(tracks not_allowed)
			(vias allowed)
			(pads allowed)
			(copperpour not_allowed)
			(footprints allowed)
		)
		(placement
			(enabled no)
			(sheetname "")
		)
		(fill yes
			(thermal_gap 0.5)
			(thermal_bridge_width 0.5)
			(island_removal_mode 0)
		)
		(polygon
			(pts
				(arc
					(start 207.397604 -203.266802)
					(mid 206.744824 -203.266802)
					(end 207.397604 -203.266802)
				)
			)
		)
	)
	(zone
		(layers "B.Cu" "In13.Cu" "In15.Cu")
		(hatch none 0.5)
		(connect_pads
			(clearance 0)
		)
		(min_thickness 0.25)
		(keepout
			(tracks not_allowed)
			(vias allowed)
			(pads allowed)
			(copperpour not_allowed)
			(footprints allowed)
		)
		(placement
			(enabled no)
			(sheetname "")
		)
		(fill yes
			(thermal_gap 0.5)
			(thermal_bridge_width 0.5)
			(island_removal_mode 0)
		)
		(polygon
			(pts
				(arc
					(start 419.190678 -4.95173)
					(mid 418.487098 -4.95173)
					(end 419.190678 -4.95173)
				)
			)
		)
	)
	(zone
		(layers "B.Cu" "In13.Cu" "In15.Cu")
		(hatch none 0.5)
		(connect_pads
			(clearance 0)
		)
		(min_thickness 0.25)
		(keepout
			(tracks not_allowed)
			(vias allowed)
			(pads allowed)
			(copperpour not_allowed)
			(footprints allowed)
		)
		(placement
			(enabled no)
			(sheetname "")
		)
		(fill yes
			(thermal_gap 0.5)
			(thermal_bridge_width 0.5)
			(island_removal_mode 0)
		)
		(polygon
			(pts
				(arc
					(start 375.41327 -246.364506)
					(mid 374.76049 -246.364506)
					(end 375.41327 -246.364506)
				)
			)
		)
	)
	(zone
		(layers "B.Cu" "In13.Cu" "In15.Cu")
		(hatch none 0.5)
		(connect_pads
			(clearance 0)
		)
		(min_thickness 0.25)
		(keepout
			(tracks not_allowed)
			(vias allowed)
			(pads allowed)
			(copperpour not_allowed)
			(footprints allowed)
		)
		(placement
			(enabled no)
			(sheetname "")
		)
		(fill yes
			(thermal_gap 0.5)
			(thermal_bridge_width 0.5)
			(island_removal_mode 0)
		)
		(polygon
			(pts
				(arc
					(start 21.215604 -214.316564)
					(mid 20.562824 -214.316564)
					(end 21.215604 -214.316564)
				)
			)
		)
	)
	(zone
		(layers "B.Cu" "In13.Cu" "In15.Cu")
		(hatch none 0.5)
		(connect_pads
			(clearance 0)
		)
		(min_thickness 0.25)
		(keepout
			(tracks not_allowed)
			(vias allowed)
			(pads allowed)
			(copperpour not_allowed)
			(footprints allowed)
		)
		(placement
			(enabled no)
			(sheetname "")
		)
		(fill yes
			(thermal_gap 0.5)
			(thermal_bridge_width 0.5)
			(island_removal_mode 0)
		)
		(polygon
			(pts
				(arc
					(start 409.154884 -428.28972)
					(mid 408.345132 -428.28972)
					(end 409.154884 -428.28972)
				)
			)
		)
	)
	(zone
		(layers "B.Cu" "In13.Cu" "In15.Cu")
		(hatch none 0.5)
		(connect_pads
			(clearance 0)
		)
		(min_thickness 0.25)
		(keepout
			(tracks not_allowed)
			(vias allowed)
			(pads allowed)
			(copperpour not_allowed)
			(footprints allowed)
		)
		(placement
			(enabled no)
			(sheetname "")
		)
		(fill yes
			(thermal_gap 0.5)
			(thermal_bridge_width 0.5)
			(island_removal_mode 0)
		)
		(polygon
			(pts
				(arc
					(start 269.155672 -300.166786)
					(mid 268.502892 -300.166786)
					(end 269.155672 -300.166786)
				)
			)
		)
	)
	(zone
		(layers "B.Cu" "In13.Cu" "In15.Cu")
		(hatch none 0.5)
		(connect_pads
			(clearance 0)
		)
		(min_thickness 0.25)
		(keepout
			(tracks not_allowed)
			(vias allowed)
			(pads allowed)
			(copperpour not_allowed)
			(footprints allowed)
		)
		(placement
			(enabled no)
			(sheetname "")
		)
		(fill yes
			(thermal_gap 0.5)
			(thermal_bridge_width 0.5)
			(island_removal_mode 0)
		)
		(polygon
			(pts
				(arc
					(start 203.297536 -264.466578)
					(mid 202.644756 -264.466578)
					(end 203.297536 -264.466578)
				)
			)
		)
	)
	(zone
		(layers "B.Cu" "In13.Cu" "In15.Cu")
		(hatch none 0.5)
		(connect_pads
			(clearance 0)
		)
		(min_thickness 0.25)
		(keepout
			(tracks not_allowed)
			(vias allowed)
			(pads allowed)
			(copperpour not_allowed)
			(footprints allowed)
		)
		(placement
			(enabled no)
			(sheetname "")
		)
		(fill yes
			(thermal_gap 0.5)
			(thermal_bridge_width 0.5)
			(island_removal_mode 0)
		)
		(polygon
			(pts
				(arc
					(start 269.155672 -276.366732)
					(mid 268.502892 -276.366732)
					(end 269.155672 -276.366732)
				)
			)
		)
	)
	(zone
		(layers "B.Cu" "In13.Cu" "In15.Cu")
		(hatch none 0.5)
		(connect_pads
			(clearance 0)
		)
		(min_thickness 0.25)
		(keepout
			(tracks not_allowed)
			(vias allowed)
			(pads allowed)
			(copperpour not_allowed)
			(footprints allowed)
		)
		(placement
			(enabled no)
			(sheetname "")
		)
		(fill yes
			(thermal_gap 0.5)
			(thermal_bridge_width 0.5)
			(island_removal_mode 0)
		)
		(polygon
			(pts
				(arc
					(start 362.726224 -221.133924)
					(mid 362.073444 -221.133924)
					(end 362.726224 -221.133924)
				)
			)
		)
	)
	(zone
		(layers "B.Cu" "In13.Cu" "In15.Cu")
		(hatch none 0.5)
		(connect_pads
			(clearance 0)
		)
		(min_thickness 0.25)
		(keepout
			(tracks not_allowed)
			(vias allowed)
			(pads allowed)
			(copperpour not_allowed)
			(footprints allowed)
		)
		(placement
			(enabled no)
			(sheetname "")
		)
		(fill yes
			(thermal_gap 0.5)
			(thermal_bridge_width 0.5)
			(island_removal_mode 0)
		)
		(polygon
			(pts
				(arc
					(start 269.155672 -195.616576)
					(mid 268.502892 -195.616576)
					(end 269.155672 -195.616576)
				)
			)
		)
	)
	(zone
		(layers "B.Cu" "In13.Cu" "In15.Cu")
		(hatch none 0.5)
		(connect_pads
			(clearance 0)
		)
		(min_thickness 0.25)
		(keepout
			(tracks not_allowed)
			(vias allowed)
			(pads allowed)
			(copperpour not_allowed)
			(footprints allowed)
		)
		(placement
			(enabled no)
			(sheetname "")
		)
		(fill yes
			(thermal_gap 0.5)
			(thermal_bridge_width 0.5)
			(island_removal_mode 0)
		)
		(polygon
			(pts
				(arc
					(start 113.846356 -221.133924)
					(mid 113.193576 -221.133924)
					(end 113.846356 -221.133924)
				)
			)
		)
	)
	(zone
		(layers "B.Cu" "In13.Cu" "In15.Cu")
		(hatch none 0.5)
		(connect_pads
			(clearance 0)
		)
		(min_thickness 0.25)
		(keepout
			(tracks not_allowed)
			(vias allowed)
			(pads allowed)
			(copperpour not_allowed)
			(footprints allowed)
		)
		(placement
			(enabled no)
			(sheetname "")
		)
		(fill yes
			(thermal_gap 0.5)
			(thermal_bridge_width 0.5)
			(island_removal_mode 0)
		)
		(polygon
			(pts
				(arc
					(start 98.449384 -262.872474)
					(mid 97.796604 -262.872474)
					(end 98.449384 -262.872474)
				)
			)
		)
	)
	(zone
		(layers "B.Cu" "In13.Cu" "In15.Cu")
		(hatch none 0.5)
		(connect_pads
			(clearance 0)
		)
		(min_thickness 0.25)
		(keepout
			(tracks not_allowed)
			(vias allowed)
			(pads allowed)
			(copperpour not_allowed)
			(footprints allowed)
		)
		(placement
			(enabled no)
			(sheetname "")
		)
		(fill yes
			(thermal_gap 0.5)
			(thermal_bridge_width 0.5)
			(island_removal_mode 0)
		)
		(polygon
			(pts
				(arc
					(start 349.09887 -230.086662)
					(mid 348.44609 -230.086662)
					(end 349.09887 -230.086662)
				)
			)
		)
	)
	(zone
		(layers "B.Cu" "In13.Cu" "In15.Cu")
		(hatch none 0.5)
		(connect_pads
			(clearance 0)
		)
		(min_thickness 0.25)
		(keepout
			(tracks not_allowed)
			(vias allowed)
			(pads allowed)
			(copperpour not_allowed)
			(footprints allowed)
		)
		(placement
			(enabled no)
			(sheetname "")
		)
		(fill yes
			(thermal_gap 0.5)
			(thermal_bridge_width 0.5)
			(island_removal_mode 0)
		)
		(polygon
			(pts
				(arc
					(start 104.088184 -279.150318)
					(mid 103.435404 -279.150318)
					(end 104.088184 -279.150318)
				)
			)
		)
	)
	(zone
		(layers "B.Cu" "In13.Cu" "In15.Cu")
		(hatch none 0.5)
		(connect_pads
			(clearance 0)
		)
		(min_thickness 0.25)
		(keepout
			(tracks not_allowed)
			(vias allowed)
			(pads allowed)
			(copperpour not_allowed)
			(footprints allowed)
		)
		(placement
			(enabled no)
			(sheetname "")
		)
		(fill yes
			(thermal_gap 0.5)
			(thermal_bridge_width 0.5)
			(island_removal_mode 0)
		)
		(polygon
			(pts
				(arc
					(start 269.155672 -223.666558)
					(mid 268.502892 -223.666558)
					(end 269.155672 -223.666558)
				)
			)
		)
	)
	(zone
		(layers "B.Cu" "In13.Cu" "In15.Cu")
		(hatch none 0.5)
		(connect_pads
			(clearance 0)
		)
		(min_thickness 0.25)
		(keepout
			(tracks not_allowed)
			(vias allowed)
			(pads allowed)
			(copperpour not_allowed)
			(footprints allowed)
		)
		(placement
			(enabled no)
			(sheetname "")
		)
		(fill yes
			(thermal_gap 0.5)
			(thermal_bridge_width 0.5)
			(island_removal_mode 0)
		)
		(polygon
			(pts
				(arc
					(start 305.678078 -410.030168)
					(mid 304.974498 -410.030168)
					(end 305.678078 -410.030168)
				)
			)
		)
	)
	(zone
		(layers "B.Cu" "In13.Cu" "In15.Cu")
		(hatch none 0.5)
		(connect_pads
			(clearance 0)
		)
		(min_thickness 0.25)
		(keepout
			(tracks not_allowed)
			(vias allowed)
			(pads allowed)
			(copperpour not_allowed)
			(footprints allowed)
		)
		(placement
			(enabled no)
			(sheetname "")
		)
		(fill yes
			(thermal_gap 0.5)
			(thermal_bridge_width 0.5)
			(island_removal_mode 0)
		)
		(polygon
			(pts
				(arc
					(start 455.337672 -197.316598)
					(mid 454.684892 -197.316598)
					(end 455.337672 -197.316598)
				)
			)
		)
	)
	(zone
		(layers "B.Cu" "In13.Cu" "In15.Cu")
		(hatch none 0.5)
		(connect_pads
			(clearance 0)
		)
		(min_thickness 0.25)
		(keepout
			(tracks not_allowed)
			(vias allowed)
			(pads allowed)
			(copperpour not_allowed)
			(footprints allowed)
		)
		(placement
			(enabled no)
			(sheetname "")
		)
		(fill yes
			(thermal_gap 0.5)
			(thermal_bridge_width 0.5)
			(island_removal_mode 0)
		)
		(polygon
			(pts
				(arc
					(start 384.154934 -428.28972)
					(mid 383.345182 -428.28972)
					(end 384.154934 -428.28972)
				)
			)
		)
	)
	(zone
		(layers "B.Cu" "In13.Cu" "In15.Cu")
		(hatch none 0.5)
		(connect_pads
			(clearance 0)
		)
		(min_thickness 0.25)
		(keepout
			(tracks not_allowed)
			(vias allowed)
			(pads allowed)
			(copperpour not_allowed)
			(footprints allowed)
		)
		(placement
			(enabled no)
			(sheetname "")
		)
		(fill yes
			(thermal_gap 0.5)
			(thermal_bridge_width 0.5)
			(island_removal_mode 0)
		)
		(polygon
			(pts
				(arc
					(start 98.919538 -273.453098)
					(mid 98.266758 -273.453098)
					(end 98.919538 -273.453098)
				)
			)
		)
	)
	(zone
		(layers "B.Cu" "In13.Cu" "In15.Cu")
		(hatch none 0.5)
		(connect_pads
			(clearance 0)
		)
		(min_thickness 0.25)
		(keepout
			(tracks not_allowed)
			(vias allowed)
			(pads allowed)
			(copperpour not_allowed)
			(footprints allowed)
		)
		(placement
			(enabled no)
			(sheetname "")
		)
		(fill yes
			(thermal_gap 0.5)
			(thermal_bridge_width 0.5)
			(island_removal_mode 0)
		)
		(polygon
			(pts
				(arc
					(start 336.991706 -282.405836)
					(mid 336.338926 -282.405836)
					(end 336.991706 -282.405836)
				)
			)
		)
	)
	(zone
		(layers "B.Cu" "In13.Cu" "In15.Cu")
		(hatch none 0.5)
		(connect_pads
			(clearance 0)
		)
		(min_thickness 0.25)
		(keepout
			(tracks not_allowed)
			(vias allowed)
			(pads allowed)
			(copperpour not_allowed)
			(footprints allowed)
		)
		(placement
			(enabled no)
			(sheetname "")
		)
		(fill yes
			(thermal_gap 0.5)
			(thermal_bridge_width 0.5)
			(island_removal_mode 0)
		)
		(polygon
			(pts
				(arc
					(start 106.907584 -282.405836)
					(mid 106.254804 -282.405836)
					(end 106.907584 -282.405836)
				)
			)
		)
	)
	(zone
		(layers "B.Cu" "In13.Cu" "In15.Cu")
		(hatch none 0.5)
		(connect_pads
			(clearance 0)
		)
		(min_thickness 0.25)
		(keepout
			(tracks not_allowed)
			(vias allowed)
			(pads allowed)
			(copperpour not_allowed)
			(footprints allowed)
		)
		(placement
			(enabled no)
			(sheetname "")
		)
		(fill yes
			(thermal_gap 0.5)
			(thermal_bridge_width 0.5)
			(island_removal_mode 0)
		)
		(polygon
			(pts
				(arc
					(start 123.714002 -241.481102)
					(mid 123.061222 -241.481102)
					(end 123.714002 -241.481102)
				)
			)
		)
	)
	(zone
		(layers "B.Cu" "In13.Cu" "In15.Cu")
		(hatch none 0.5)
		(connect_pads
			(clearance 0)
		)
		(min_thickness 0.25)
		(keepout
			(tracks not_allowed)
			(vias allowed)
			(pads allowed)
			(copperpour not_allowed)
			(footprints allowed)
		)
		(placement
			(enabled no)
			(sheetname "")
		)
		(fill yes
			(thermal_gap 0.5)
			(thermal_bridge_width 0.5)
			(island_removal_mode 0)
		)
		(polygon
			(pts
				(arc
					(start 352.85807 -221.94774)
					(mid 352.20529 -221.94774)
					(end 352.85807 -221.94774)
				)
			)
		)
	)
	(zone
		(layers "B.Cu" "In13.Cu" "In15.Cu")
		(hatch none 0.5)
		(connect_pads
			(clearance 0)
		)
		(min_thickness 0.25)
		(keepout
			(tracks not_allowed)
			(vias allowed)
			(pads allowed)
			(copperpour not_allowed)
			(footprints allowed)
		)
		(placement
			(enabled no)
			(sheetname "")
		)
		(fill yes
			(thermal_gap 0.5)
			(thermal_bridge_width 0.5)
			(island_removal_mode 0)
		)
		(polygon
			(pts
				(arc
					(start 407.154888 -426.089826)
					(mid 406.345136 -426.089826)
					(end 407.154888 -426.089826)
				)
			)
		)
	)
	(zone
		(layers "B.Cu" "In13.Cu" "In15.Cu")
		(hatch none 0.5)
		(connect_pads
			(clearance 0)
		)
		(min_thickness 0.25)
		(keepout
			(tracks not_allowed)
			(vias allowed)
			(pads allowed)
			(copperpour not_allowed)
			(footprints allowed)
		)
		(placement
			(enabled no)
			(sheetname "")
		)
		(fill yes
			(thermal_gap 0.5)
			(thermal_bridge_width 0.5)
			(island_removal_mode 0)
		)
		(polygon
			(pts
				(arc
					(start 312.668158 -410.030168)
					(mid 311.964578 -410.030168)
					(end 312.668158 -410.030168)
				)
			)
		)
	)
	(zone
		(layers "B.Cu" "In13.Cu" "In15.Cu")
		(hatch none 0.5)
		(connect_pads
			(clearance 0)
		)
		(min_thickness 0.25)
		(keepout
			(tracks not_allowed)
			(vias allowed)
			(pads allowed)
			(copperpour not_allowed)
			(footprints allowed)
		)
		(placement
			(enabled no)
			(sheetname "")
		)
		(fill yes
			(thermal_gap 0.5)
			(thermal_bridge_width 0.5)
			(island_removal_mode 0)
		)
		(polygon
			(pts
				(arc
					(start 97.869756 -247.178322)
					(mid 97.216976 -247.178322)
					(end 97.869756 -247.178322)
				)
			)
		)
	)
	(zone
		(layers "B.Cu" "In13.Cu" "In15.Cu")
		(hatch none 0.5)
		(connect_pads
			(clearance 0)
		)
		(min_thickness 0.25)
		(keepout
			(tracks not_allowed)
			(vias allowed)
			(pads allowed)
			(copperpour not_allowed)
			(footprints allowed)
		)
		(placement
			(enabled no)
			(sheetname "")
		)
		(fill yes
			(thermal_gap 0.5)
			(thermal_bridge_width 0.5)
			(island_removal_mode 0)
		)
		(polygon
			(pts
				(arc
					(start 207.397604 -300.166532)
					(mid 206.744824 -300.166532)
					(end 207.397604 -300.166532)
				)
			)
		)
	)
	(zone
		(layers "B.Cu" "In13.Cu" "In15.Cu")
		(hatch none 0.5)
		(connect_pads
			(clearance 0)
		)
		(min_thickness 0.25)
		(keepout
			(tracks not_allowed)
			(vias allowed)
			(pads allowed)
			(copperpour not_allowed)
			(footprints allowed)
		)
		(placement
			(enabled no)
			(sheetname "")
		)
		(fill yes
			(thermal_gap 0.5)
			(thermal_bridge_width 0.5)
			(island_removal_mode 0)
		)
		(polygon
			(pts
				(arc
					(start 265.055604 -271.266666)
					(mid 264.402824 -271.266666)
					(end 265.055604 -271.266666)
				)
			)
		)
	)
	(zone
		(layers "B.Cu" "In13.Cu" "In15.Cu")
		(hatch none 0.5)
		(connect_pads
			(clearance 0)
		)
		(min_thickness 0.25)
		(keepout
			(tracks not_allowed)
			(vias allowed)
			(pads allowed)
			(copperpour not_allowed)
			(footprints allowed)
		)
		(placement
			(enabled no)
			(sheetname "")
		)
		(fill yes
			(thermal_gap 0.5)
			(thermal_bridge_width 0.5)
			(island_removal_mode 0)
		)
		(polygon
			(pts
				(arc
					(start 355.207824 -221.133924)
					(mid 354.555044 -221.133924)
					(end 355.207824 -221.133924)
				)
			)
		)
	)
	(zone
		(layers "B.Cu" "In13.Cu" "In15.Cu")
		(hatch none 0.5)
		(connect_pads
			(clearance 0)
		)
		(min_thickness 0.25)
		(keepout
			(tracks not_allowed)
			(vias allowed)
			(pads allowed)
			(copperpour not_allowed)
			(footprints allowed)
		)
		(placement
			(enabled no)
			(sheetname "")
		)
		(fill yes
			(thermal_gap 0.5)
			(thermal_bridge_width 0.5)
			(island_removal_mode 0)
		)
		(polygon
			(pts
				(arc
					(start 346.27947 -239.853216)
					(mid 345.62669 -239.853216)
					(end 346.27947 -239.853216)
				)
			)
		)
	)
	(zone
		(layers "B.Cu" "In13.Cu" "In15.Cu")
		(hatch none 0.5)
		(connect_pads
			(clearance 0)
		)
		(min_thickness 0.25)
		(keepout
			(tracks not_allowed)
			(vias allowed)
			(pads allowed)
			(copperpour not_allowed)
			(footprints allowed)
		)
		(placement
			(enabled no)
			(sheetname "")
		)
		(fill yes
			(thermal_gap 0.5)
			(thermal_bridge_width 0.5)
			(island_removal_mode 0)
		)
		(polygon
			(pts
				(arc
					(start 99.389184 -274.266914)
					(mid 98.736404 -274.266914)
					(end 99.389184 -274.266914)
				)
			)
		)
	)
	(zone
		(layers "B.Cu" "In13.Cu" "In15.Cu")
		(hatch none 0.5)
		(connect_pads
			(clearance 0)
		)
		(min_thickness 0.25)
		(keepout
			(tracks not_allowed)
			(vias allowed)
			(pads allowed)
			(copperpour not_allowed)
			(footprints allowed)
		)
		(placement
			(enabled no)
			(sheetname "")
		)
		(fill yes
			(thermal_gap 0.5)
			(thermal_bridge_width 0.5)
			(island_removal_mode 0)
		)
		(polygon
			(pts
				(arc
					(start 455.337672 -279.766776)
					(mid 454.684892 -279.766776)
					(end 455.337672 -279.766776)
				)
			)
		)
	)
	(zone
		(layers "B.Cu" "In13.Cu" "In15.Cu")
		(hatch none 0.5)
		(connect_pads
			(clearance 0)
		)
		(min_thickness 0.25)
		(keepout
			(tracks not_allowed)
			(vias allowed)
			(pads allowed)
			(copperpour not_allowed)
			(footprints allowed)
		)
		(placement
			(enabled no)
			(sheetname "")
		)
		(fill yes
			(thermal_gap 0.5)
			(thermal_bridge_width 0.5)
			(island_removal_mode 0)
		)
		(polygon
			(pts
				(arc
					(start 346.749624 -230.900478)
					(mid 346.096844 -230.900478)
					(end 346.749624 -230.900478)
				)
			)
		)
	)
	(zone
		(layers "B.Cu" "In13.Cu" "In15.Cu")
		(hatch none 0.5)
		(connect_pads
			(clearance 0)
		)
		(min_thickness 0.25)
		(keepout
			(tracks not_allowed)
			(vias allowed)
			(pads allowed)
			(copperpour not_allowed)
			(footprints allowed)
		)
		(placement
			(enabled no)
			(sheetname "")
		)
		(fill yes
			(thermal_gap 0.5)
			(thermal_bridge_width 0.5)
			(island_removal_mode 0)
		)
		(polygon
			(pts
				(arc
					(start 106.327956 -221.133924)
					(mid 105.675176 -221.133924)
					(end 106.327956 -221.133924)
				)
			)
		)
	)
	(zone
		(layers "B.Cu" "In13.Cu" "In15.Cu")
		(hatch none 0.5)
		(connect_pads
			(clearance 0)
		)
		(min_thickness 0.25)
		(keepout
			(tracks not_allowed)
			(vias allowed)
			(pads allowed)
			(copperpour not_allowed)
			(footprints allowed)
		)
		(placement
			(enabled no)
			(sheetname "")
		)
		(fill yes
			(thermal_gap 0.5)
			(thermal_bridge_width 0.5)
			(island_removal_mode 0)
		)
		(polygon
			(pts
				(arc
					(start 347.329252 -262.872474)
					(mid 346.676472 -262.872474)
					(end 347.329252 -262.872474)
				)
			)
		)
	)
	(zone
		(layers "B.Cu" "In13.Cu" "In15.Cu")
		(hatch none 0.5)
		(connect_pads
			(clearance 0)
		)
		(min_thickness 0.25)
		(keepout
			(tracks not_allowed)
			(vias allowed)
			(pads allowed)
			(copperpour not_allowed)
			(footprints allowed)
		)
		(placement
			(enabled no)
			(sheetname "")
		)
		(fill yes
			(thermal_gap 0.5)
			(thermal_bridge_width 0.5)
			(island_removal_mode 0)
		)
		(polygon
			(pts
				(arc
					(start 21.215604 -290.816792)
					(mid 20.562824 -290.816792)
					(end 21.215604 -290.816792)
				)
			)
		)
	)
	(zone
		(layers "B.Cu" "In13.Cu" "In15.Cu")
		(hatch none 0.5)
		(connect_pads
			(clearance 0)
		)
		(min_thickness 0.25)
		(keepout
			(tracks not_allowed)
			(vias allowed)
			(pads allowed)
			(copperpour not_allowed)
			(footprints allowed)
		)
		(placement
			(enabled no)
			(sheetname "")
		)
		(fill yes
			(thermal_gap 0.5)
			(thermal_bridge_width 0.5)
			(island_removal_mode 0)
		)
		(polygon
			(pts
				(arc
					(start 123.569984 -403.883876)
					(mid 122.866404 -403.883876)
					(end 123.569984 -403.883876)
				)
			)
		)
	)
	(zone
		(layers "B.Cu" "In13.Cu" "In15.Cu")
		(hatch none 0.5)
		(connect_pads
			(clearance 0)
		)
		(min_thickness 0.25)
		(keepout
			(tracks not_allowed)
			(vias allowed)
			(pads allowed)
			(copperpour not_allowed)
			(footprints allowed)
		)
		(placement
			(enabled no)
			(sheetname "")
		)
		(fill yes
			(thermal_gap 0.5)
			(thermal_bridge_width 0.5)
			(island_removal_mode 0)
		)
		(polygon
			(pts
				(arc
					(start 336.310478 -410.030168)
					(mid 335.606898 -410.030168)
					(end 336.310478 -410.030168)
				)
			)
		)
	)
	(zone
		(layers "B.Cu" "In13.Cu" "In15.Cu")
		(hatch none 0.5)
		(connect_pads
			(clearance 0)
		)
		(min_thickness 0.25)
		(keepout
			(tracks not_allowed)
			(vias allowed)
			(pads allowed)
			(copperpour not_allowed)
			(footprints allowed)
		)
		(placement
			(enabled no)
			(sheetname "")
		)
		(fill yes
			(thermal_gap 0.5)
			(thermal_bridge_width 0.5)
			(island_removal_mode 0)
		)
		(polygon
			(pts
				(arc
					(start 99.389184 -262.872474)
					(mid 98.736404 -262.872474)
					(end 99.389184 -262.872474)
				)
			)
		)
	)
	(zone
		(layers "B.Cu" "In13.Cu" "In15.Cu")
		(hatch none 0.5)
		(connect_pads
			(clearance 0)
		)
		(min_thickness 0.25)
		(keepout
			(tracks not_allowed)
			(vias allowed)
			(pads allowed)
			(copperpour not_allowed)
			(footprints allowed)
		)
		(placement
			(enabled no)
			(sheetname "")
		)
		(fill yes
			(thermal_gap 0.5)
			(thermal_bridge_width 0.5)
			(island_removal_mode 0)
		)
		(polygon
			(pts
				(arc
					(start 99.389184 -272.639282)
					(mid 98.736404 -272.639282)
					(end 99.389184 -272.639282)
				)
			)
		)
	)
	(zone
		(layers "B.Cu" "In13.Cu" "In15.Cu")
		(hatch none 0.5)
		(connect_pads
			(clearance 0)
		)
		(min_thickness 0.25)
		(keepout
			(tracks not_allowed)
			(vias allowed)
			(pads allowed)
			(copperpour not_allowed)
			(footprints allowed)
		)
		(placement
			(enabled no)
			(sheetname "")
		)
		(fill yes
			(thermal_gap 0.5)
			(thermal_bridge_width 0.5)
			(island_removal_mode 0)
		)
		(polygon
			(pts
				(arc
					(start 101.158802 -239.853216)
					(mid 100.506022 -239.853216)
					(end 101.158802 -239.853216)
				)
			)
		)
	)
	(zone
		(layers "B.Cu" "In13.Cu" "In15.Cu")
		(hatch none 0.5)
		(connect_pads
			(clearance 0)
		)
		(min_thickness 0.25)
		(keepout
			(tracks not_allowed)
			(vias allowed)
			(pads allowed)
			(copperpour not_allowed)
			(footprints allowed)
		)
		(placement
			(enabled no)
			(sheetname "")
		)
		(fill yes
			(thermal_gap 0.5)
			(thermal_bridge_width 0.5)
			(island_removal_mode 0)
		)
		(polygon
			(pts
				(arc
					(start 455.337672 -236.416596)
					(mid 454.684892 -236.416596)
					(end 455.337672 -236.416596)
				)
			)
		)
	)
	(zone
		(layers "B.Cu" "In13.Cu" "In15.Cu")
		(hatch none 0.5)
		(connect_pads
			(clearance 0)
		)
		(min_thickness 0.25)
		(keepout
			(tracks not_allowed)
			(vias allowed)
			(pads allowed)
			(copperpour not_allowed)
			(footprints allowed)
		)
		(placement
			(enabled no)
			(sheetname "")
		)
		(fill yes
			(thermal_gap 0.5)
			(thermal_bridge_width 0.5)
			(island_removal_mode 0)
		)
		(polygon
			(pts
				(arc
					(start 207.397604 -260.21665)
					(mid 206.744824 -260.21665)
					(end 207.397604 -260.21665)
				)
			)
		)
	)
	(zone
		(layers "B.Cu" "In13.Cu" "In15.Cu")
		(hatch none 0.5)
		(connect_pads
			(clearance 0)
		)
		(min_thickness 0.25)
		(keepout
			(tracks not_allowed)
			(vias allowed)
			(pads allowed)
			(copperpour not_allowed)
			(footprints allowed)
		)
		(placement
			(enabled no)
			(sheetname "")
		)
		(fill yes
			(thermal_gap 0.5)
			(thermal_bridge_width 0.5)
			(island_removal_mode 0)
		)
		(polygon
			(pts
				(arc
					(start 371.184424 -242.294918)
					(mid 370.531644 -242.294918)
					(end 371.184424 -242.294918)
				)
			)
		)
	)
	(zone
		(layers "B.Cu" "In13.Cu" "In15.Cu")
		(hatch none 0.5)
		(connect_pads
			(clearance 0)
		)
		(min_thickness 0.25)
		(keepout
			(tracks not_allowed)
			(vias allowed)
			(pads allowed)
			(copperpour not_allowed)
			(footprints allowed)
		)
		(placement
			(enabled no)
			(sheetname "")
		)
		(fill yes
			(thermal_gap 0.5)
			(thermal_bridge_width 0.5)
			(island_removal_mode 0)
		)
		(polygon
			(pts
				(arc
					(start 125.703584 -275.8948)
					(mid 125.050804 -275.8948)
					(end 125.703584 -275.8948)
				)
			)
		)
	)
	(zone
		(layers "B.Cu" "In13.Cu" "In15.Cu")
		(hatch none 0.5)
		(connect_pads
			(clearance 0)
		)
		(min_thickness 0.25)
		(keepout
			(tracks not_allowed)
			(vias allowed)
			(pads allowed)
			(copperpour not_allowed)
			(footprints allowed)
		)
		(placement
			(enabled no)
			(sheetname "")
		)
		(fill yes
			(thermal_gap 0.5)
			(thermal_bridge_width 0.5)
			(island_removal_mode 0)
		)
		(polygon
			(pts
				(arc
					(start 346.749624 -235.783882)
					(mid 346.096844 -235.783882)
					(end 346.749624 -235.783882)
				)
			)
		)
	)
	(zone
		(layers "B.Cu" "In13.Cu" "In15.Cu")
		(hatch none 0.5)
		(connect_pads
			(clearance 0)
		)
		(min_thickness 0.25)
		(keepout
			(tracks not_allowed)
			(vias allowed)
			(pads allowed)
			(copperpour not_allowed)
			(footprints allowed)
		)
		(placement
			(enabled no)
			(sheetname "")
		)
		(fill yes
			(thermal_gap 0.5)
			(thermal_bridge_width 0.5)
			(island_removal_mode 0)
		)
		(polygon
			(pts
				(arc
					(start 455.337672 -261.916672)
					(mid 454.684892 -261.916672)
					(end 455.337672 -261.916672)
				)
			)
		)
	)
	(zone
		(layers "B.Cu" "In13.Cu" "In15.Cu")
		(hatch none 0.5)
		(connect_pads
			(clearance 0)
		)
		(min_thickness 0.25)
		(keepout
			(tracks not_allowed)
			(vias allowed)
			(pads allowed)
			(copperpour not_allowed)
			(footprints allowed)
		)
		(placement
			(enabled no)
			(sheetname "")
		)
		(fill yes
			(thermal_gap 0.5)
			(thermal_bridge_width 0.5)
			(island_removal_mode 0)
		)
		(polygon
			(pts
				(arc
					(start 100.219002 -246.364506)
					(mid 99.566222 -246.364506)
					(end 100.219002 -246.364506)
				)
			)
		)
	)
	(zone
		(layers "B.Cu" "In13.Cu" "In15.Cu")
		(hatch none 0.5)
		(connect_pads
			(clearance 0)
		)
		(min_thickness 0.25)
		(keepout
			(tracks not_allowed)
			(vias allowed)
			(pads allowed)
			(copperpour not_allowed)
			(footprints allowed)
		)
		(placement
			(enabled no)
			(sheetname "")
		)
		(fill yes
			(thermal_gap 0.5)
			(thermal_bridge_width 0.5)
			(island_removal_mode 0)
		)
		(polygon
			(pts
				(arc
					(start 124.433584 -403.883876)
					(mid 123.730004 -403.883876)
					(end 124.433584 -403.883876)
				)
			)
		)
	)
	(zone
		(layers "B.Cu" "In13.Cu" "In15.Cu")
		(hatch none 0.5)
		(connect_pads
			(clearance 0)
		)
		(min_thickness 0.25)
		(keepout
			(tracks not_allowed)
			(vias allowed)
			(pads allowed)
			(copperpour not_allowed)
			(footprints allowed)
		)
		(placement
			(enabled no)
			(sheetname "")
		)
		(fill yes
			(thermal_gap 0.5)
			(thermal_bridge_width 0.5)
			(island_removal_mode 0)
		)
		(polygon
			(pts
				(arc
					(start 321.054984 -431.889916)
					(mid 320.245232 -431.889916)
					(end 321.054984 -431.889916)
				)
			)
		)
	)
	(zone
		(layers "B.Cu" "In13.Cu" "In15.Cu")
		(hatch none 0.5)
		(connect_pads
			(clearance 0)
		)
		(min_thickness 0.25)
		(keepout
			(tracks not_allowed)
			(vias allowed)
			(pads allowed)
			(copperpour not_allowed)
			(footprints allowed)
		)
		(placement
			(enabled no)
			(sheetname "")
		)
		(fill yes
			(thermal_gap 0.5)
			(thermal_bridge_width 0.5)
			(island_removal_mode 0)
		)
		(polygon
			(pts
				(arc
					(start 265.055604 -235.566712)
					(mid 264.402824 -235.566712)
					(end 265.055604 -235.566712)
				)
			)
		)
	)
	(zone
		(layers "B.Cu" "In13.Cu" "In15.Cu")
		(hatch none 0.5)
		(connect_pads
			(clearance 0)
		)
		(min_thickness 0.25)
		(keepout
			(tracks not_allowed)
			(vias allowed)
			(pads allowed)
			(copperpour not_allowed)
			(footprints allowed)
		)
		(placement
			(enabled no)
			(sheetname "")
		)
		(fill yes
			(thermal_gap 0.5)
			(thermal_bridge_width 0.5)
			(island_removal_mode 0)
		)
		(polygon
			(pts
				(arc
					(start 126.173738 -270.19758)
					(mid 125.520958 -270.19758)
					(end 126.173738 -270.19758)
				)
			)
		)
	)
	(zone
		(layers "B.Cu" "In13.Cu" "In15.Cu")
		(hatch none 0.5)
		(connect_pads
			(clearance 0)
		)
		(min_thickness 0.25)
		(keepout
			(tracks not_allowed)
			(vias allowed)
			(pads allowed)
			(copperpour not_allowed)
			(footprints allowed)
		)
		(placement
			(enabled no)
			(sheetname "")
		)
		(fill yes
			(thermal_gap 0.5)
			(thermal_bridge_width 0.5)
			(island_removal_mode 0)
		)
		(polygon
			(pts
				(arc
					(start 21.215604 -278.066754)
					(mid 20.562824 -278.066754)
					(end 21.215604 -278.066754)
				)
			)
		)
	)
	(zone
		(layers "B.Cu" "In13.Cu" "In15.Cu")
		(hatch none 0.5)
		(connect_pads
			(clearance 0)
		)
		(min_thickness 0.25)
		(keepout
			(tracks not_allowed)
			(vias allowed)
			(pads allowed)
			(copperpour not_allowed)
			(footprints allowed)
		)
		(placement
			(enabled no)
			(sheetname "")
		)
		(fill yes
			(thermal_gap 0.5)
			(thermal_bridge_width 0.5)
			(island_removal_mode 0)
		)
		(polygon
			(pts
				(arc
					(start 124.294138 -257.175254)
					(mid 123.641358 -257.175254)
					(end 124.294138 -257.175254)
				)
			)
		)
	)
	(zone
		(layers "B.Cu" "In13.Cu" "In15.Cu")
		(hatch none 0.5)
		(connect_pads
			(clearance 0)
		)
		(min_thickness 0.25)
		(keepout
			(tracks not_allowed)
			(vias allowed)
			(pads allowed)
			(copperpour not_allowed)
			(footprints allowed)
		)
		(placement
			(enabled no)
			(sheetname "")
		)
		(fill yes
			(thermal_gap 0.5)
			(thermal_bridge_width 0.5)
			(island_removal_mode 0)
		)
		(polygon
			(pts
				(arc
					(start 143.154908 -426.089826)
					(mid 142.345156 -426.089826)
					(end 143.154908 -426.089826)
				)
			)
		)
	)
	(zone
		(layers "B.Cu" "In13.Cu" "In15.Cu")
		(hatch none 0.5)
		(connect_pads
			(clearance 0)
		)
		(min_thickness 0.25)
		(keepout
			(tracks not_allowed)
			(vias allowed)
			(pads allowed)
			(copperpour not_allowed)
			(footprints allowed)
		)
		(placement
			(enabled no)
			(sheetname "")
		)
		(fill yes
			(thermal_gap 0.5)
			(thermal_bridge_width 0.5)
			(island_removal_mode 0)
		)
		(polygon
			(pts
				(arc
					(start 92.080588 -403.883876)
					(mid 91.377008 -403.883876)
					(end 92.080588 -403.883876)
				)
			)
		)
	)
	(zone
		(layers "B.Cu" "In13.Cu" "In15.Cu")
		(hatch none 0.5)
		(connect_pads
			(clearance 0)
		)
		(min_thickness 0.25)
		(keepout
			(tracks not_allowed)
			(vias allowed)
			(pads allowed)
			(copperpour not_allowed)
			(footprints allowed)
		)
		(placement
			(enabled no)
			(sheetname "")
		)
		(fill yes
			(thermal_gap 0.5)
			(thermal_bridge_width 0.5)
			(island_removal_mode 0)
		)
		(polygon
			(pts
				(arc
					(start 101.268784 -262.872474)
					(mid 100.616004 -262.872474)
					(end 101.268784 -262.872474)
				)
			)
		)
	)
	(zone
		(layers "B.Cu" "In13.Cu" "In15.Cu")
		(hatch none 0.5)
		(connect_pads
			(clearance 0)
		)
		(min_thickness 0.25)
		(keepout
			(tracks not_allowed)
			(vias allowed)
			(pads allowed)
			(copperpour not_allowed)
			(footprints allowed)
		)
		(placement
			(enabled no)
			(sheetname "")
		)
		(fill yes
			(thermal_gap 0.5)
			(thermal_bridge_width 0.5)
			(island_removal_mode 0)
		)
		(polygon
			(pts
				(arc
					(start 451.237604 -226.216718)
					(mid 450.584824 -226.216718)
					(end 451.237604 -226.216718)
				)
			)
		)
	)
	(zone
		(layers "B.Cu" "In13.Cu" "In15.Cu")
		(hatch none 0.5)
		(connect_pads
			(clearance 0)
		)
		(min_thickness 0.25)
		(keepout
			(tracks not_allowed)
			(vias allowed)
			(pads allowed)
			(copperpour not_allowed)
			(footprints allowed)
		)
		(placement
			(enabled no)
			(sheetname "")
		)
		(fill yes
			(thermal_gap 0.5)
			(thermal_bridge_width 0.5)
			(island_removal_mode 0)
		)
		(polygon
			(pts
				(arc
					(start 50.488596 -6.724396)
					(mid 49.785016 -6.724396)
					(end 50.488596 -6.724396)
				)
			)
		)
	)
	(zone
		(layers "B.Cu" "In13.Cu" "In15.Cu")
		(hatch none 0.5)
		(connect_pads
			(clearance 0)
		)
		(min_thickness 0.25)
		(keepout
			(tracks not_allowed)
			(vias allowed)
			(pads allowed)
			(copperpour not_allowed)
			(footprints allowed)
		)
		(placement
			(enabled no)
			(sheetname "")
		)
		(fill yes
			(thermal_gap 0.5)
			(thermal_bridge_width 0.5)
			(island_removal_mode 0)
		)
		(polygon
			(pts
				(arc
					(start 61.054996 -431.889916)
					(mid 60.245244 -431.889916)
					(end 61.054996 -431.889916)
				)
			)
		)
	)
	(zone
		(layers "B.Cu" "In13.Cu" "In15.Cu")
		(hatch none 0.5)
		(connect_pads
			(clearance 0)
		)
		(min_thickness 0.25)
		(keepout
			(tracks not_allowed)
			(vias allowed)
			(pads allowed)
			(copperpour not_allowed)
			(footprints allowed)
		)
		(placement
			(enabled no)
			(sheetname "")
		)
		(fill yes
			(thermal_gap 0.5)
			(thermal_bridge_width 0.5)
			(island_removal_mode 0)
		)
		(polygon
			(pts
				(arc
					(start 377.9012 -403.883876)
					(mid 377.19762 -403.883876)
					(end 377.9012 -403.883876)
				)
			)
		)
	)
	(zone
		(layers "B.Cu" "In13.Cu" "In15.Cu")
		(hatch none 0.5)
		(connect_pads
			(clearance 0)
		)
		(min_thickness 0.25)
		(keepout
			(tracks not_allowed)
			(vias allowed)
			(pads allowed)
			(copperpour not_allowed)
			(footprints allowed)
		)
		(placement
			(enabled no)
			(sheetname "")
		)
		(fill yes
			(thermal_gap 0.5)
			(thermal_bridge_width 0.5)
			(island_removal_mode 0)
		)
		(polygon
			(pts
				(arc
					(start 413.154876 -428.28972)
					(mid 412.345124 -428.28972)
					(end 413.154876 -428.28972)
				)
			)
		)
	)
	(zone
		(layers "B.Cu" "In13.Cu" "In15.Cu")
		(hatch none 0.5)
		(connect_pads
			(clearance 0)
		)
		(min_thickness 0.25)
		(keepout
			(tracks not_allowed)
			(vias allowed)
			(pads allowed)
			(copperpour not_allowed)
			(footprints allowed)
		)
		(placement
			(enabled no)
			(sheetname "")
		)
		(fill yes
			(thermal_gap 0.5)
			(thermal_bridge_width 0.5)
			(island_removal_mode 0)
		)
		(polygon
			(pts
				(arc
					(start 207.397604 -259.366766)
					(mid 206.744824 -259.366766)
					(end 207.397604 -259.366766)
				)
			)
		)
	)
	(zone
		(layers "B.Cu" "In13.Cu" "In15.Cu")
		(hatch none 0.5)
		(connect_pads
			(clearance 0)
		)
		(min_thickness 0.25)
		(keepout
			(tracks not_allowed)
			(vias allowed)
			(pads allowed)
			(copperpour not_allowed)
			(footprints allowed)
		)
		(placement
			(enabled no)
			(sheetname "")
		)
		(fill yes
			(thermal_gap 0.5)
			(thermal_bridge_width 0.5)
			(island_removal_mode 0)
		)
		(polygon
			(pts
				(arc
					(start 269.155672 -237.266734)
					(mid 268.502892 -237.266734)
					(end 269.155672 -237.266734)
				)
			)
		)
	)
	(zone
		(layers "B.Cu" "In13.Cu" "In15.Cu")
		(hatch none 0.5)
		(connect_pads
			(clearance 0)
		)
		(min_thickness 0.25)
		(keepout
			(tracks not_allowed)
			(vias allowed)
			(pads allowed)
			(copperpour not_allowed)
			(footprints allowed)
		)
		(placement
			(enabled no)
			(sheetname "")
		)
		(fill yes
			(thermal_gap 0.5)
			(thermal_bridge_width 0.5)
			(island_removal_mode 0)
		)
		(polygon
			(pts
				(arc
					(start 108.677202 -221.94774)
					(mid 108.024422 -221.94774)
					(end 108.677202 -221.94774)
				)
			)
		)
	)
	(zone
		(layers "B.Cu" "In13.Cu" "In15.Cu")
		(hatch none 0.5)
		(connect_pads
			(clearance 0)
		)
		(min_thickness 0.25)
		(keepout
			(tracks not_allowed)
			(vias allowed)
			(pads allowed)
			(copperpour not_allowed)
			(footprints allowed)
		)
		(placement
			(enabled no)
			(sheetname "")
		)
		(fill yes
			(thermal_gap 0.5)
			(thermal_bridge_width 0.5)
			(island_removal_mode 0)
		)
		(polygon
			(pts
				(arc
					(start 451.237604 -306.96662)
					(mid 450.584824 -306.96662)
					(end 451.237604 -306.96662)
				)
			)
		)
	)
	(zone
		(layers "B.Cu" "In13.Cu" "In15.Cu")
		(hatch none 0.5)
		(connect_pads
			(clearance 0)
		)
		(min_thickness 0.25)
		(keepout
			(tracks not_allowed)
			(vias allowed)
			(pads allowed)
			(copperpour not_allowed)
			(footprints allowed)
		)
		(placement
			(enabled no)
			(sheetname "")
		)
		(fill yes
			(thermal_gap 0.5)
			(thermal_bridge_width 0.5)
			(island_removal_mode 0)
		)
		(polygon
			(pts
				(arc
					(start 127.496824 -403.883876)
					(mid 126.793244 -403.883876)
					(end 127.496824 -403.883876)
				)
			)
		)
	)
	(zone
		(layers "B.Cu" "In13.Cu" "In15.Cu")
		(hatch none 0.5)
		(connect_pads
			(clearance 0)
		)
		(min_thickness 0.25)
		(keepout
			(tracks not_allowed)
			(vias allowed)
			(pads allowed)
			(copperpour not_allowed)
			(footprints allowed)
		)
		(placement
			(enabled no)
			(sheetname "")
		)
		(fill yes
			(thermal_gap 0.5)
			(thermal_bridge_width 0.5)
			(island_removal_mode 0)
		)
		(polygon
			(pts
				(arc
					(start 125.233938 -260.430772)
					(mid 124.581158 -260.430772)
					(end 125.233938 -260.430772)
				)
			)
		)
	)
	(zone
		(layers "B.Cu" "In13.Cu" "In15.Cu")
		(hatch none 0.5)
		(connect_pads
			(clearance 0)
		)
		(min_thickness 0.25)
		(keepout
			(tracks not_allowed)
			(vias allowed)
			(pads allowed)
			(copperpour not_allowed)
			(footprints allowed)
		)
		(placement
			(enabled no)
			(sheetname "")
		)
		(fill yes
			(thermal_gap 0.5)
			(thermal_bridge_width 0.5)
			(island_removal_mode 0)
		)
		(polygon
			(pts
				(arc
					(start 203.297536 -293.366698)
					(mid 202.644756 -293.366698)
					(end 203.297536 -293.366698)
				)
			)
		)
	)
	(zone
		(layers "B.Cu" "In13.Cu" "In15.Cu")
		(hatch none 0.5)
		(connect_pads
			(clearance 0)
		)
		(min_thickness 0.25)
		(keepout
			(tracks not_allowed)
			(vias allowed)
			(pads allowed)
			(copperpour not_allowed)
			(footprints allowed)
		)
		(placement
			(enabled no)
			(sheetname "")
		)
		(fill yes
			(thermal_gap 0.5)
			(thermal_bridge_width 0.5)
			(island_removal_mode 0)
		)
		(polygon
			(pts
				(arc
					(start 207.397604 -289.11677)
					(mid 206.744824 -289.11677)
					(end 207.397604 -289.11677)
				)
			)
		)
	)
	(zone
		(layers "B.Cu" "In13.Cu" "In15.Cu")
		(hatch none 0.5)
		(connect_pads
			(clearance 0)
		)
		(min_thickness 0.25)
		(keepout
			(tracks not_allowed)
			(vias allowed)
			(pads allowed)
			(copperpour not_allowed)
			(footprints allowed)
		)
		(placement
			(enabled no)
			(sheetname "")
		)
		(fill yes
			(thermal_gap 0.5)
			(thermal_bridge_width 0.5)
			(island_removal_mode 0)
		)
		(polygon
			(pts
				(arc
					(start 373.174006 -266.941808)
					(mid 372.521226 -266.941808)
					(end 373.174006 -266.941808)
				)
			)
		)
	)
	(zone
		(layers "B.Cu" "In13.Cu" "In15.Cu")
		(hatch none 0.5)
		(connect_pads
			(clearance 0)
		)
		(min_thickness 0.25)
		(keepout
			(tracks not_allowed)
			(vias allowed)
			(pads allowed)
			(copperpour not_allowed)
			(footprints allowed)
		)
		(placement
			(enabled no)
			(sheetname "")
		)
		(fill yes
			(thermal_gap 0.5)
			(thermal_bridge_width 0.5)
			(island_removal_mode 0)
		)
		(polygon
			(pts
				(arc
					(start 451.237604 -278.916638)
					(mid 450.584824 -278.916638)
					(end 451.237604 -278.916638)
				)
			)
		)
	)
	(zone
		(layers "B.Cu" "In13.Cu" "In15.Cu")
		(hatch none 0.5)
		(connect_pads
			(clearance 0)
		)
		(min_thickness 0.25)
		(keepout
			(tracks not_allowed)
			(vias allowed)
			(pads allowed)
			(copperpour not_allowed)
			(footprints allowed)
		)
		(placement
			(enabled no)
			(sheetname "")
		)
		(fill yes
			(thermal_gap 0.5)
			(thermal_bridge_width 0.5)
			(island_removal_mode 0)
		)
		(polygon
			(pts
				(arc
					(start 327.984358 -410.030168)
					(mid 327.280778 -410.030168)
					(end 327.984358 -410.030168)
				)
			)
		)
	)
	(zone
		(layers "B.Cu" "In13.Cu" "In15.Cu")
		(hatch none 0.5)
		(connect_pads
			(clearance 0)
		)
		(min_thickness 0.25)
		(keepout
			(tracks not_allowed)
			(vias allowed)
			(pads allowed)
			(copperpour not_allowed)
			(footprints allowed)
		)
		(placement
			(enabled no)
			(sheetname "")
		)
		(fill yes
			(thermal_gap 0.5)
			(thermal_bridge_width 0.5)
			(island_removal_mode 0)
		)
		(polygon
			(pts
				(arc
					(start 415.590736 -4.95173)
					(mid 414.887156 -4.95173)
					(end 415.590736 -4.95173)
				)
			)
		)
	)
	(zone
		(layers "B.Cu" "In13.Cu" "In15.Cu")
		(hatch none 0.5)
		(connect_pads
			(clearance 0)
		)
		(min_thickness 0.25)
		(keepout
			(tracks not_allowed)
			(vias allowed)
			(pads allowed)
			(copperpour not_allowed)
			(footprints allowed)
		)
		(placement
			(enabled no)
			(sheetname "")
		)
		(fill yes
			(thermal_gap 0.5)
			(thermal_bridge_width 0.5)
			(island_removal_mode 0)
		)
		(polygon
			(pts
				(arc
					(start 78.054962 -431.889916)
					(mid 77.24521 -431.889916)
					(end 78.054962 -431.889916)
				)
			)
		)
	)
	(zone
		(layers "B.Cu" "In13.Cu" "In15.Cu")
		(hatch none 0.5)
		(connect_pads
			(clearance 0)
		)
		(min_thickness 0.25)
		(keepout
			(tracks not_allowed)
			(vias allowed)
			(pads allowed)
			(copperpour not_allowed)
			(footprints allowed)
		)
		(placement
			(enabled no)
			(sheetname "")
		)
		(fill yes
			(thermal_gap 0.5)
			(thermal_bridge_width 0.5)
			(island_removal_mode 0)
		)
		(polygon
			(pts
				(arc
					(start 428.596044 -6.713474)
					(mid 427.892464 -6.713474)
					(end 428.596044 -6.713474)
				)
			)
		)
	)
	(zone
		(layers "B.Cu" "In13.Cu" "In15.Cu")
		(hatch none 0.5)
		(connect_pads
			(clearance 0)
		)
		(min_thickness 0.25)
		(keepout
			(tracks not_allowed)
			(vias allowed)
			(pads allowed)
			(copperpour not_allowed)
			(footprints allowed)
		)
		(placement
			(enabled no)
			(sheetname "")
		)
		(fill yes
			(thermal_gap 0.5)
			(thermal_bridge_width 0.5)
			(island_removal_mode 0)
		)
		(polygon
			(pts
				(arc
					(start 136.154922 -427.089824)
					(mid 135.34517 -427.089824)
					(end 136.154922 -427.089824)
				)
			)
		)
	)
	(zone
		(layers "B.Cu" "In13.Cu" "In15.Cu")
		(hatch none 0.5)
		(connect_pads
			(clearance 0)
		)
		(min_thickness 0.25)
		(keepout
			(tracks not_allowed)
			(vias allowed)
			(pads allowed)
			(copperpour not_allowed)
			(footprints allowed)
		)
		(placement
			(enabled no)
			(sheetname "")
		)
		(fill yes
			(thermal_gap 0.5)
			(thermal_bridge_width 0.5)
			(island_removal_mode 0)
		)
		(polygon
			(pts
				(arc
					(start 126.063756 -237.411514)
					(mid 125.410976 -237.411514)
					(end 126.063756 -237.411514)
				)
			)
		)
	)
	(zone
		(layers "B.Cu" "In13.Cu" "In15.Cu")
		(hatch none 0.5)
		(connect_pads
			(clearance 0)
		)
		(min_thickness 0.25)
		(keepout
			(tracks not_allowed)
			(vias allowed)
			(pads allowed)
			(copperpour not_allowed)
			(footprints allowed)
		)
		(placement
			(enabled no)
			(sheetname "")
		)
		(fill yes
			(thermal_gap 0.5)
			(thermal_bridge_width 0.5)
			(island_removal_mode 0)
		)
		(polygon
			(pts
				(arc
					(start 125.123956 -227.64496)
					(mid 124.471176 -227.64496)
					(end 125.123956 -227.64496)
				)
			)
		)
	)
	(zone
		(layers "B.Cu" "In13.Cu" "In15.Cu")
		(hatch none 0.5)
		(connect_pads
			(clearance 0)
		)
		(min_thickness 0.25)
		(keepout
			(tracks not_allowed)
			(vias allowed)
			(pads allowed)
			(copperpour not_allowed)
			(footprints allowed)
		)
		(placement
			(enabled no)
			(sheetname "")
		)
		(fill yes
			(thermal_gap 0.5)
			(thermal_bridge_width 0.5)
			(island_removal_mode 0)
		)
		(polygon
			(pts
				(arc
					(start 363.19587 -220.319854)
					(mid 362.54309 -220.319854)
					(end 363.19587 -220.319854)
				)
			)
		)
	)
	(zone
		(layers "B.Cu" "In13.Cu" "In15.Cu")
		(hatch none 0.5)
		(connect_pads
			(clearance 0)
		)
		(min_thickness 0.25)
		(keepout
			(tracks not_allowed)
			(vias allowed)
			(pads allowed)
			(copperpour not_allowed)
			(footprints allowed)
		)
		(placement
			(enabled no)
			(sheetname "")
		)
		(fill yes
			(thermal_gap 0.5)
			(thermal_bridge_width 0.5)
			(island_removal_mode 0)
		)
		(polygon
			(pts
				(arc
					(start 23.832058 -6.724396)
					(mid 23.128478 -6.724396)
					(end 23.832058 -6.724396)
				)
			)
		)
	)
	(zone
		(layers "B.Cu" "In13.Cu" "In15.Cu")
		(hatch none 0.5)
		(connect_pads
			(clearance 0)
		)
		(min_thickness 0.25)
		(keepout
			(tracks not_allowed)
			(vias allowed)
			(pads allowed)
			(copperpour not_allowed)
			(footprints allowed)
		)
		(placement
			(enabled no)
			(sheetname "")
		)
		(fill yes
			(thermal_gap 0.5)
			(thermal_bridge_width 0.5)
			(island_removal_mode 0)
		)
		(polygon
			(pts
				(arc
					(start 334.054958 -431.889916)
					(mid 333.245206 -431.889916)
					(end 334.054958 -431.889916)
				)
			)
		)
	)
	(zone
		(layers "B.Cu" "In13.Cu" "In15.Cu")
		(hatch none 0.5)
		(connect_pads
			(clearance 0)
		)
		(min_thickness 0.25)
		(keepout
			(tracks not_allowed)
			(vias allowed)
			(pads allowed)
			(copperpour not_allowed)
			(footprints allowed)
		)
		(placement
			(enabled no)
			(sheetname "")
		)
		(fill yes
			(thermal_gap 0.5)
			(thermal_bridge_width 0.5)
			(island_removal_mode 0)
		)
		(polygon
			(pts
				(arc
					(start 373.174006 -258.80314)
					(mid 372.521226 -258.80314)
					(end 373.174006 -258.80314)
				)
			)
		)
	)
	(zone
		(layers "B.Cu" "In13.Cu" "In15.Cu")
		(hatch none 0.5)
		(connect_pads
			(clearance 0)
		)
		(min_thickness 0.25)
		(keepout
			(tracks not_allowed)
			(vias allowed)
			(pads allowed)
			(copperpour not_allowed)
			(footprints allowed)
		)
		(placement
			(enabled no)
			(sheetname "")
		)
		(fill yes
			(thermal_gap 0.5)
			(thermal_bridge_width 0.5)
			(island_removal_mode 0)
		)
		(polygon
			(pts
				(arc
					(start 451.237604 -219.41663)
					(mid 450.584824 -219.41663)
					(end 451.237604 -219.41663)
				)
			)
		)
	)
	(zone
		(layers "B.Cu" "In13.Cu" "In15.Cu")
		(hatch none 0.5)
		(connect_pads
			(clearance 0)
		)
		(min_thickness 0.25)
		(keepout
			(tracks not_allowed)
			(vias allowed)
			(pads allowed)
			(copperpour not_allowed)
			(footprints allowed)
		)
		(placement
			(enabled no)
			(sheetname "")
		)
		(fill yes
			(thermal_gap 0.5)
			(thermal_bridge_width 0.5)
			(island_removal_mode 0)
		)
		(polygon
			(pts
				(arc
					(start 405.539702 -6.713474)
					(mid 404.836122 -6.713474)
					(end 405.539702 -6.713474)
				)
			)
		)
	)
	(zone
		(layers "B.Cu" "In13.Cu" "In15.Cu")
		(hatch none 0.5)
		(connect_pads
			(clearance 0)
		)
		(min_thickness 0.25)
		(keepout
			(tracks not_allowed)
			(vias allowed)
			(pads allowed)
			(copperpour not_allowed)
			(footprints allowed)
		)
		(placement
			(enabled no)
			(sheetname "")
		)
		(fill yes
			(thermal_gap 0.5)
			(thermal_bridge_width 0.5)
			(island_removal_mode 0)
		)
		(polygon
			(pts
				(arc
					(start 405.154892 -428.28972)
					(mid 404.34514 -428.28972)
					(end 405.154892 -428.28972)
				)
			)
		)
	)
	(zone
		(layers "B.Cu" "In13.Cu" "In15.Cu")
		(hatch none 0.5)
		(connect_pads
			(clearance 0)
		)
		(min_thickness 0.25)
		(keepout
			(tracks not_allowed)
			(vias allowed)
			(pads allowed)
			(copperpour not_allowed)
			(footprints allowed)
		)
		(placement
			(enabled no)
			(sheetname "")
		)
		(fill yes
			(thermal_gap 0.5)
			(thermal_bridge_width 0.5)
			(island_removal_mode 0)
		)
		(polygon
			(pts
				(arc
					(start 451.237604 -266.1666)
					(mid 450.584824 -266.1666)
					(end 451.237604 -266.1666)
				)
			)
		)
	)
	(zone
		(layers "B.Cu" "In13.Cu" "In15.Cu")
		(hatch none 0.5)
		(connect_pads
			(clearance 0)
		)
		(min_thickness 0.25)
		(keepout
			(tracks not_allowed)
			(vias allowed)
			(pads allowed)
			(copperpour not_allowed)
			(footprints allowed)
		)
		(placement
			(enabled no)
			(sheetname "")
		)
		(fill yes
			(thermal_gap 0.5)
			(thermal_bridge_width 0.5)
			(island_removal_mode 0)
		)
		(polygon
			(pts
				(arc
					(start 94.220284 -283.219906)
					(mid 93.567504 -283.219906)
					(end 94.220284 -283.219906)
				)
			)
		)
	)
	(zone
		(layers "B.Cu" "In13.Cu" "In15.Cu")
		(hatch none 0.5)
		(connect_pads
			(clearance 0)
		)
		(min_thickness 0.25)
		(keepout
			(tracks not_allowed)
			(vias allowed)
			(pads allowed)
			(copperpour not_allowed)
			(footprints allowed)
		)
		(placement
			(enabled no)
			(sheetname "")
		)
		(fill yes
			(thermal_gap 0.5)
			(thermal_bridge_width 0.5)
			(island_removal_mode 0)
		)
		(polygon
			(pts
				(arc
					(start 109.617002 -220.319854)
					(mid 108.964222 -220.319854)
					(end 109.617002 -220.319854)
				)
			)
		)
	)
	(zone
		(layers "B.Cu" "In13.Cu" "In15.Cu")
		(hatch none 0.5)
		(connect_pads
			(clearance 0)
		)
		(min_thickness 0.25)
		(keepout
			(tracks not_allowed)
			(vias allowed)
			(pads allowed)
			(copperpour not_allowed)
			(footprints allowed)
		)
		(placement
			(enabled no)
			(sheetname "")
		)
		(fill yes
			(thermal_gap 0.5)
			(thermal_bridge_width 0.5)
			(island_removal_mode 0)
		)
		(polygon
			(pts
				(arc
					(start 372.124224 -239.0394)
					(mid 371.471444 -239.0394)
					(end 372.124224 -239.0394)
				)
			)
		)
	)
	(zone
		(layers "B.Cu" "In13.Cu" "In15.Cu")
		(hatch none 0.5)
		(connect_pads
			(clearance 0)
		)
		(min_thickness 0.25)
		(keepout
			(tracks not_allowed)
			(vias allowed)
			(pads allowed)
			(copperpour not_allowed)
			(footprints allowed)
		)
		(placement
			(enabled no)
			(sheetname "")
		)
		(fill yes
			(thermal_gap 0.5)
			(thermal_bridge_width 0.5)
			(island_removal_mode 0)
		)
		(polygon
			(pts
				(arc
					(start 451.237604 -196.466714)
					(mid 450.584824 -196.466714)
					(end 451.237604 -196.466714)
				)
			)
		)
	)
	(zone
		(layers "B.Cu" "In13.Cu" "In15.Cu")
		(hatch none 0.5)
		(connect_pads
			(clearance 0)
		)
		(min_thickness 0.25)
		(keepout
			(tracks not_allowed)
			(vias allowed)
			(pads allowed)
			(copperpour not_allowed)
			(footprints allowed)
		)
		(placement
			(enabled no)
			(sheetname "")
		)
		(fill yes
			(thermal_gap 0.5)
			(thermal_bridge_width 0.5)
			(island_removal_mode 0)
		)
		(polygon
			(pts
				(arc
					(start 348.563438 -410.030168)
					(mid 347.859858 -410.030168)
					(end 348.563438 -410.030168)
				)
			)
		)
	)
	(zone
		(layers "B.Cu" "In13.Cu" "In15.Cu")
		(hatch none 0.5)
		(connect_pads
			(clearance 0)
		)
		(min_thickness 0.25)
		(keepout
			(tracks not_allowed)
			(vias allowed)
			(pads allowed)
			(copperpour not_allowed)
			(footprints allowed)
		)
		(placement
			(enabled no)
			(sheetname "")
		)
		(fill yes
			(thermal_gap 0.5)
			(thermal_bridge_width 0.5)
			(island_removal_mode 0)
		)
		(polygon
			(pts
				(arc
					(start 88.054942 -429.689768)
					(mid 87.24519 -429.689768)
					(end 88.054942 -429.689768)
				)
			)
		)
	)
	(zone
		(layers "B.Cu" "In13.Cu" "In15.Cu")
		(hatch none 0.5)
		(connect_pads
			(clearance 0)
		)
		(min_thickness 0.25)
		(keepout
			(tracks not_allowed)
			(vias allowed)
			(pads allowed)
			(copperpour not_allowed)
			(footprints allowed)
		)
		(placement
			(enabled no)
			(sheetname "")
		)
		(fill yes
			(thermal_gap 0.5)
			(thermal_bridge_width 0.5)
			(island_removal_mode 0)
		)
		(polygon
			(pts
				(arc
					(start 104.088184 -280.778204)
					(mid 103.435404 -280.778204)
					(end 104.088184 -280.778204)
				)
			)
		)
	)
	(zone
		(layers "B.Cu" "In13.Cu" "In15.Cu")
		(hatch none 0.5)
		(connect_pads
			(clearance 0)
		)
		(min_thickness 0.25)
		(keepout
			(tracks not_allowed)
			(vias allowed)
			(pads allowed)
			(copperpour not_allowed)
			(footprints allowed)
		)
		(placement
			(enabled no)
			(sheetname "")
		)
		(fill yes
			(thermal_gap 0.5)
			(thermal_bridge_width 0.5)
			(island_removal_mode 0)
		)
		(polygon
			(pts
				(arc
					(start 373.064024 -234.15625)
					(mid 372.411244 -234.15625)
					(end 373.064024 -234.15625)
				)
			)
		)
	)
	(zone
		(layers "B.Cu" "In13.Cu" "In15.Cu")
		(hatch none 0.5)
		(connect_pads
			(clearance 0)
		)
		(min_thickness 0.25)
		(keepout
			(tracks not_allowed)
			(vias allowed)
			(pads allowed)
			(copperpour not_allowed)
			(footprints allowed)
		)
		(placement
			(enabled no)
			(sheetname "")
		)
		(fill yes
			(thermal_gap 0.5)
			(thermal_bridge_width 0.5)
			(island_removal_mode 0)
		)
		(polygon
			(pts
				(arc
					(start 86.054946 -430.689766)
					(mid 85.245194 -430.689766)
					(end 86.054946 -430.689766)
				)
			)
		)
	)
	(zone
		(layers "B.Cu" "In13.Cu" "In15.Cu")
		(hatch none 0.5)
		(connect_pads
			(clearance 0)
		)
		(min_thickness 0.25)
		(keepout
			(tracks not_allowed)
			(vias allowed)
			(pads allowed)
			(copperpour not_allowed)
			(footprints allowed)
		)
		(placement
			(enabled no)
			(sheetname "")
		)
		(fill yes
			(thermal_gap 0.5)
			(thermal_bridge_width 0.5)
			(island_removal_mode 0)
		)
		(polygon
			(pts
				(arc
					(start 348.629224 -243.922804)
					(mid 347.976444 -243.922804)
					(end 348.629224 -243.922804)
				)
			)
		)
	)
	(zone
		(layers "B.Cu" "In13.Cu" "In15.Cu")
		(hatch none 0.5)
		(connect_pads
			(clearance 0)
		)
		(min_thickness 0.25)
		(keepout
			(tracks not_allowed)
			(vias allowed)
			(pads allowed)
			(copperpour not_allowed)
			(footprints allowed)
		)
		(placement
			(enabled no)
			(sheetname "")
		)
		(fill yes
			(thermal_gap 0.5)
			(thermal_bridge_width 0.5)
			(island_removal_mode 0)
		)
		(polygon
			(pts
				(arc
					(start 455.337672 -290.816538)
					(mid 454.684892 -290.816538)
					(end 455.337672 -290.816538)
				)
			)
		)
	)
	(zone
		(layers "B.Cu" "In13.Cu" "In15.Cu")
		(hatch none 0.5)
		(connect_pads
			(clearance 0)
		)
		(min_thickness 0.25)
		(keepout
			(tracks not_allowed)
			(vias allowed)
			(pads allowed)
			(copperpour not_allowed)
			(footprints allowed)
		)
		(placement
			(enabled no)
			(sheetname "")
		)
		(fill yes
			(thermal_gap 0.5)
			(thermal_bridge_width 0.5)
			(island_removal_mode 0)
		)
		(polygon
			(pts
				(arc
					(start 21.215604 -293.366698)
					(mid 20.562824 -293.366698)
					(end 21.215604 -293.366698)
				)
			)
		)
	)
	(zone
		(layers "B.Cu" "In13.Cu" "In15.Cu")
		(hatch none 0.5)
		(connect_pads
			(clearance 0)
		)
		(min_thickness 0.25)
		(keepout
			(tracks not_allowed)
			(vias allowed)
			(pads allowed)
			(copperpour not_allowed)
			(footprints allowed)
		)
		(placement
			(enabled no)
			(sheetname "")
		)
		(fill yes
			(thermal_gap 0.5)
			(thermal_bridge_width 0.5)
			(island_removal_mode 0)
		)
		(polygon
			(pts
				(arc
					(start 126.154942 -427.289976)
					(mid 125.34519 -427.289976)
					(end 126.154942 -427.289976)
				)
			)
		)
	)
	(zone
		(layers "B.Cu" "In13.Cu" "In15.Cu")
		(hatch none 0.5)
		(connect_pads
			(clearance 0)
		)
		(min_thickness 0.25)
		(keepout
			(tracks not_allowed)
			(vias allowed)
			(pads allowed)
			(copperpour not_allowed)
			(footprints allowed)
		)
		(placement
			(enabled no)
			(sheetname "")
		)
		(fill yes
			(thermal_gap 0.5)
			(thermal_bridge_width 0.5)
			(island_removal_mode 0)
		)
		(polygon
			(pts
				(arc
					(start 417.386008 -6.713474)
					(mid 416.682428 -6.713474)
					(end 417.386008 -6.713474)
				)
			)
		)
	)
	(zone
		(layers "B.Cu" "In13.Cu" "In15.Cu")
		(hatch none 0.5)
		(connect_pads
			(clearance 0)
		)
		(min_thickness 0.25)
		(keepout
			(tracks not_allowed)
			(vias allowed)
			(pads allowed)
			(copperpour not_allowed)
			(footprints allowed)
		)
		(placement
			(enabled no)
			(sheetname "")
		)
		(fill yes
			(thermal_gap 0.5)
			(thermal_bridge_width 0.5)
			(island_removal_mode 0)
		)
		(polygon
			(pts
				(arc
					(start 21.215604 -223.666558)
					(mid 20.562824 -223.666558)
					(end 21.215604 -223.666558)
				)
			)
		)
	)
	(zone
		(layers "B.Cu" "In13.Cu" "In15.Cu")
		(hatch none 0.5)
		(connect_pads
			(clearance 0)
		)
		(min_thickness 0.25)
		(keepout
			(tracks not_allowed)
			(vias allowed)
			(pads allowed)
			(copperpour not_allowed)
			(footprints allowed)
		)
		(placement
			(enabled no)
			(sheetname "")
		)
		(fill yes
			(thermal_gap 0.5)
			(thermal_bridge_width 0.5)
			(island_removal_mode 0)
		)
		(polygon
			(pts
				(arc
					(start 357.666798 -275.8948)
					(mid 357.014018 -275.8948)
					(end 357.666798 -275.8948)
				)
			)
		)
	)
	(zone
		(layers "B.Cu" "In13.Cu" "In15.Cu")
		(hatch none 0.5)
		(connect_pads
			(clearance 0)
		)
		(min_thickness 0.25)
		(keepout
			(tracks not_allowed)
			(vias allowed)
			(pads allowed)
			(copperpour not_allowed)
			(footprints allowed)
		)
		(placement
			(enabled no)
			(sheetname "")
		)
		(fill yes
			(thermal_gap 0.5)
			(thermal_bridge_width 0.5)
			(island_removal_mode 0)
		)
		(polygon
			(pts
				(arc
					(start 414.649666 -6.713474)
					(mid 413.946086 -6.713474)
					(end 414.649666 -6.713474)
				)
			)
		)
	)
	(zone
		(layers "B.Cu" "In13.Cu" "In15.Cu")
		(hatch none 0.5)
		(connect_pads
			(clearance 0)
		)
		(min_thickness 0.25)
		(keepout
			(tracks not_allowed)
			(vias allowed)
			(pads allowed)
			(copperpour not_allowed)
			(footprints allowed)
		)
		(placement
			(enabled no)
			(sheetname "")
		)
		(fill yes
			(thermal_gap 0.5)
			(thermal_bridge_width 0.5)
			(island_removal_mode 0)
		)
		(polygon
			(pts
				(arc
					(start 99.279202 -238.225584)
					(mid 98.626422 -238.225584)
					(end 99.279202 -238.225584)
				)
			)
		)
	)
	(zone
		(layers "B.Cu" "In13.Cu" "In15.Cu")
		(hatch none 0.5)
		(connect_pads
			(clearance 0)
		)
		(min_thickness 0.25)
		(keepout
			(tracks not_allowed)
			(vias allowed)
			(pads allowed)
			(copperpour not_allowed)
			(footprints allowed)
		)
		(placement
			(enabled no)
			(sheetname "")
		)
		(fill yes
			(thermal_gap 0.5)
			(thermal_bridge_width 0.5)
			(island_removal_mode 0)
		)
		(polygon
			(pts
				(arc
					(start 86.701884 -286.475424)
					(mid 86.049104 -286.475424)
					(end 86.701884 -286.475424)
				)
			)
		)
	)
	(zone
		(layers "B.Cu" "In13.Cu" "In15.Cu")
		(hatch none 0.5)
		(connect_pads
			(clearance 0)
		)
		(min_thickness 0.25)
		(keepout
			(tracks not_allowed)
			(vias allowed)
			(pads allowed)
			(copperpour not_allowed)
			(footprints allowed)
		)
		(placement
			(enabled no)
			(sheetname "")
		)
		(fill yes
			(thermal_gap 0.5)
			(thermal_bridge_width 0.5)
			(island_removal_mode 0)
		)
		(polygon
			(pts
				(arc
					(start 17.115536 -238.116618)
					(mid 16.462756 -238.116618)
					(end 17.115536 -238.116618)
				)
			)
		)
	)
	(zone
		(layers "B.Cu" "In13.Cu" "In15.Cu")
		(hatch none 0.5)
		(connect_pads
			(clearance 0)
		)
		(min_thickness 0.25)
		(keepout
			(tracks not_allowed)
			(vias allowed)
			(pads allowed)
			(copperpour not_allowed)
			(footprints allowed)
		)
		(placement
			(enabled no)
			(sheetname "")
		)
		(fill yes
			(thermal_gap 0.5)
			(thermal_bridge_width 0.5)
			(island_removal_mode 0)
		)
		(polygon
			(pts
				(arc
					(start 269.155672 -197.316598)
					(mid 268.502892 -197.316598)
					(end 269.155672 -197.316598)
				)
			)
		)
	)
	(zone
		(layers "B.Cu" "In13.Cu" "In15.Cu")
		(hatch none 0.5)
		(connect_pads
			(clearance 0)
		)
		(min_thickness 0.25)
		(keepout
			(tracks not_allowed)
			(vias allowed)
			(pads allowed)
			(copperpour not_allowed)
			(footprints allowed)
		)
		(placement
			(enabled no)
			(sheetname "")
		)
		(fill yes
			(thermal_gap 0.5)
			(thermal_bridge_width 0.5)
			(island_removal_mode 0)
		)
		(polygon
			(pts
				(arc
					(start 100.328984 -261.244842)
					(mid 99.676204 -261.244842)
					(end 100.328984 -261.244842)
				)
			)
		)
	)
	(zone
		(layers "B.Cu" "In13.Cu" "In15.Cu")
		(hatch none 0.5)
		(connect_pads
			(clearance 0)
		)
		(min_thickness 0.25)
		(keepout
			(tracks not_allowed)
			(vias allowed)
			(pads allowed)
			(copperpour not_allowed)
			(footprints allowed)
		)
		(placement
			(enabled no)
			(sheetname "")
		)
		(fill yes
			(thermal_gap 0.5)
			(thermal_bridge_width 0.5)
			(island_removal_mode 0)
		)
		(polygon
			(pts
				(arc
					(start 346.389452 -272.639282)
					(mid 345.736672 -272.639282)
					(end 346.389452 -272.639282)
				)
			)
		)
	)
	(zone
		(layers "B.Cu" "In13.Cu" "In15.Cu")
		(hatch none 0.5)
		(connect_pads
			(clearance 0)
		)
		(min_thickness 0.25)
		(keepout
			(tracks not_allowed)
			(vias allowed)
			(pads allowed)
			(copperpour not_allowed)
			(footprints allowed)
		)
		(placement
			(enabled no)
			(sheetname "")
		)
		(fill yes
			(thermal_gap 0.5)
			(thermal_bridge_width 0.5)
			(island_removal_mode 0)
		)
		(polygon
			(pts
				(arc
					(start 125.123956 -235.783882)
					(mid 124.471176 -235.783882)
					(end 125.123956 -235.783882)
				)
			)
		)
	)
	(zone
		(layers "B.Cu" "In13.Cu" "In15.Cu")
		(hatch none 0.5)
		(connect_pads
			(clearance 0)
		)
		(min_thickness 0.25)
		(keepout
			(tracks not_allowed)
			(vias allowed)
			(pads allowed)
			(copperpour not_allowed)
			(footprints allowed)
		)
		(placement
			(enabled no)
			(sheetname "")
		)
		(fill yes
			(thermal_gap 0.5)
			(thermal_bridge_width 0.5)
			(island_removal_mode 0)
		)
		(polygon
			(pts
				(arc
					(start 261.611872 -259.366766)
					(mid 260.959092 -259.366766)
					(end 261.611872 -259.366766)
				)
			)
		)
	)
	(zone
		(layers "B.Cu" "In13.Cu" "In15.Cu")
		(hatch none 0.5)
		(connect_pads
			(clearance 0)
		)
		(min_thickness 0.25)
		(keepout
			(tracks not_allowed)
			(vias allowed)
			(pads allowed)
			(copperpour not_allowed)
			(footprints allowed)
		)
		(placement
			(enabled no)
			(sheetname "")
		)
		(fill yes
			(thermal_gap 0.5)
			(thermal_bridge_width 0.5)
			(island_removal_mode 0)
		)
		(polygon
			(pts
				(arc
					(start 374.003824 -237.411514)
					(mid 373.351044 -237.411514)
					(end 374.003824 -237.411514)
				)
			)
		)
	)
	(zone
		(layers "B.Cu" "In13.Cu" "In15.Cu")
		(hatch none 0.5)
		(connect_pads
			(clearance 0)
		)
		(min_thickness 0.25)
		(keepout
			(tracks not_allowed)
			(vias allowed)
			(pads allowed)
			(copperpour not_allowed)
			(footprints allowed)
		)
		(placement
			(enabled no)
			(sheetname "")
		)
		(fill yes
			(thermal_gap 0.5)
			(thermal_bridge_width 0.5)
			(island_removal_mode 0)
		)
		(polygon
			(pts
				(arc
					(start 123.823984 -275.8948)
					(mid 123.171204 -275.8948)
					(end 123.823984 -275.8948)
				)
			)
		)
	)
	(zone
		(layers "B.Cu" "In13.Cu" "In15.Cu")
		(hatch none 0.5)
		(connect_pads
			(clearance 0)
		)
		(min_thickness 0.25)
		(keepout
			(tracks not_allowed)
			(vias allowed)
			(pads allowed)
			(copperpour not_allowed)
			(footprints allowed)
		)
		(placement
			(enabled no)
			(sheetname "")
		)
		(fill yes
			(thermal_gap 0.5)
			(thermal_bridge_width 0.5)
			(island_removal_mode 0)
		)
		(polygon
			(pts
				(arc
					(start 347.21927 -233.34218)
					(mid 346.56649 -233.34218)
					(end 347.21927 -233.34218)
				)
			)
		)
	)
	(zone
		(layers "B.Cu" "In13.Cu" "In15.Cu")
		(hatch none 0.5)
		(connect_pads
			(clearance 0)
		)
		(min_thickness 0.25)
		(keepout
			(tracks not_allowed)
			(vias allowed)
			(pads allowed)
			(copperpour not_allowed)
			(footprints allowed)
		)
		(placement
			(enabled no)
			(sheetname "")
		)
		(fill yes
			(thermal_gap 0.5)
			(thermal_bridge_width 0.5)
			(island_removal_mode 0)
		)
		(polygon
			(pts
				(arc
					(start 348.15907 -234.970066)
					(mid 347.50629 -234.970066)
					(end 348.15907 -234.970066)
				)
			)
		)
	)
	(zone
		(layers "B.Cu" "In13.Cu" "In15.Cu")
		(hatch none 0.5)
		(connect_pads
			(clearance 0)
		)
		(min_thickness 0.25)
		(keepout
			(tracks not_allowed)
			(vias allowed)
			(pads allowed)
			(copperpour not_allowed)
			(footprints allowed)
		)
		(placement
			(enabled no)
			(sheetname "")
		)
		(fill yes
			(thermal_gap 0.5)
			(thermal_bridge_width 0.5)
			(island_removal_mode 0)
		)
		(polygon
			(pts
				(arc
					(start 348.15907 -241.481102)
					(mid 347.50629 -241.481102)
					(end 348.15907 -241.481102)
				)
			)
		)
	)
	(zone
		(layers "B.Cu" "In13.Cu" "In15.Cu")
		(hatch none 0.5)
		(connect_pads
			(clearance 0)
		)
		(min_thickness 0.25)
		(keepout
			(tracks not_allowed)
			(vias allowed)
			(pads allowed)
			(copperpour not_allowed)
			(footprints allowed)
		)
		(placement
			(enabled no)
			(sheetname "")
		)
		(fill yes
			(thermal_gap 0.5)
			(thermal_bridge_width 0.5)
			(island_removal_mode 0)
		)
		(polygon
			(pts
				(arc
					(start 269.155672 -246.616728)
					(mid 268.502892 -246.616728)
					(end 269.155672 -246.616728)
				)
			)
		)
	)
	(zone
		(layers "B.Cu" "In13.Cu" "In15.Cu")
		(hatch none 0.5)
		(connect_pads
			(clearance 0)
		)
		(min_thickness 0.25)
		(keepout
			(tracks not_allowed)
			(vias allowed)
			(pads allowed)
			(copperpour not_allowed)
			(footprints allowed)
		)
		(placement
			(enabled no)
			(sheetname "")
		)
		(fill yes
			(thermal_gap 0.5)
			(thermal_bridge_width 0.5)
			(island_removal_mode 0)
		)
		(polygon
			(pts
				(arc
					(start 21.215604 -285.716726)
					(mid 20.562824 -285.716726)
					(end 21.215604 -285.716726)
				)
			)
		)
	)
	(zone
		(layers "B.Cu" "In13.Cu" "In15.Cu")
		(hatch none 0.5)
		(connect_pads
			(clearance 0)
		)
		(min_thickness 0.25)
		(keepout
			(tracks not_allowed)
			(vias allowed)
			(pads allowed)
			(copperpour not_allowed)
			(footprints allowed)
		)
		(placement
			(enabled no)
			(sheetname "")
		)
		(fill yes
			(thermal_gap 0.5)
			(thermal_bridge_width 0.5)
			(island_removal_mode 0)
		)
		(polygon
			(pts
				(arc
					(start 118.075202 -221.94774)
					(mid 117.422422 -221.94774)
					(end 118.075202 -221.94774)
				)
			)
		)
	)
	(zone
		(layers "B.Cu" "In13.Cu" "In15.Cu")
		(hatch none 0.5)
		(connect_pads
			(clearance 0)
		)
		(min_thickness 0.25)
		(keepout
			(tracks not_allowed)
			(vias allowed)
			(pads allowed)
			(copperpour not_allowed)
			(footprints allowed)
		)
		(placement
			(enabled no)
			(sheetname "")
		)
		(fill yes
			(thermal_gap 0.5)
			(thermal_bridge_width 0.5)
			(island_removal_mode 0)
		)
		(polygon
			(pts
				(arc
					(start 361.31627 -220.319854)
					(mid 360.66349 -220.319854)
					(end 361.31627 -220.319854)
				)
			)
		)
	)
	(zone
		(layers "B.Cu" "In13.Cu" "In15.Cu")
		(hatch none 0.5)
		(connect_pads
			(clearance 0)
		)
		(min_thickness 0.25)
		(keepout
			(tracks not_allowed)
			(vias allowed)
			(pads allowed)
			(copperpour not_allowed)
			(footprints allowed)
		)
		(placement
			(enabled no)
			(sheetname "")
		)
		(fill yes
			(thermal_gap 0.5)
			(thermal_bridge_width 0.5)
			(island_removal_mode 0)
		)
		(polygon
			(pts
				(arc
					(start 134.154926 -427.289976)
					(mid 133.345174 -427.289976)
					(end 134.154926 -427.289976)
				)
			)
		)
	)
	(zone
		(layers "B.Cu" "In13.Cu" "In15.Cu")
		(hatch none 0.5)
		(connect_pads
			(clearance 0)
		)
		(min_thickness 0.25)
		(keepout
			(tracks not_allowed)
			(vias allowed)
			(pads allowed)
			(copperpour not_allowed)
			(footprints allowed)
		)
		(placement
			(enabled no)
			(sheetname "")
		)
		(fill yes
			(thermal_gap 0.5)
			(thermal_bridge_width 0.5)
			(island_removal_mode 0)
		)
		(polygon
			(pts
				(arc
					(start 348.15907 -233.34218)
					(mid 347.50629 -233.34218)
					(end 348.15907 -233.34218)
				)
			)
		)
	)
	(zone
		(layers "B.Cu" "In13.Cu" "In15.Cu")
		(hatch none 0.5)
		(connect_pads
			(clearance 0)
		)
		(min_thickness 0.25)
		(keepout
			(tracks not_allowed)
			(vias allowed)
			(pads allowed)
			(copperpour not_allowed)
			(footprints allowed)
		)
		(placement
			(enabled no)
			(sheetname "")
		)
		(fill yes
			(thermal_gap 0.5)
			(thermal_bridge_width 0.5)
			(island_removal_mode 0)
		)
		(polygon
			(pts
				(arc
					(start 17.115536 -274.66671)
					(mid 16.462756 -274.66671)
					(end 17.115536 -274.66671)
				)
			)
		)
	)
	(zone
		(layers "B.Cu" "In13.Cu" "In15.Cu")
		(hatch none 0.5)
		(connect_pads
			(clearance 0)
		)
		(min_thickness 0.25)
		(keepout
			(tracks not_allowed)
			(vias allowed)
			(pads allowed)
			(copperpour not_allowed)
			(footprints allowed)
		)
		(placement
			(enabled no)
			(sheetname "")
		)
		(fill yes
			(thermal_gap 0.5)
			(thermal_bridge_width 0.5)
			(island_removal_mode 0)
		)
		(polygon
			(pts
				(arc
					(start 455.337672 -231.316784)
					(mid 454.684892 -231.316784)
					(end 455.337672 -231.316784)
				)
			)
		)
	)
	(zone
		(layers "B.Cu" "In13.Cu" "In15.Cu")
		(hatch none 0.5)
		(connect_pads
			(clearance 0)
		)
		(min_thickness 0.25)
		(keepout
			(tracks not_allowed)
			(vias allowed)
			(pads allowed)
			(copperpour not_allowed)
			(footprints allowed)
		)
		(placement
			(enabled no)
			(sheetname "")
		)
		(fill yes
			(thermal_gap 0.5)
			(thermal_bridge_width 0.5)
			(island_removal_mode 0)
		)
		(polygon
			(pts
				(arc
					(start 348.629224 -245.55069)
					(mid 347.976444 -245.55069)
					(end 348.629224 -245.55069)
				)
			)
		)
	)
	(zone
		(layers "B.Cu" "In13.Cu" "In15.Cu")
		(hatch none 0.5)
		(connect_pads
			(clearance 0)
		)
		(min_thickness 0.25)
		(keepout
			(tracks not_allowed)
			(vias allowed)
			(pads allowed)
			(copperpour not_allowed)
			(footprints allowed)
		)
		(placement
			(enabled no)
			(sheetname "")
		)
		(fill yes
			(thermal_gap 0.5)
			(thermal_bridge_width 0.5)
			(island_removal_mode 0)
		)
		(polygon
			(pts
				(arc
					(start 109.726984 -274.266914)
					(mid 109.074204 -274.266914)
					(end 109.726984 -274.266914)
				)
			)
		)
	)
	(zone
		(layers "B.Cu" "In13.Cu" "In15.Cu")
		(hatch none 0.5)
		(connect_pads
			(clearance 0)
		)
		(min_thickness 0.25)
		(keepout
			(tracks not_allowed)
			(vias allowed)
			(pads allowed)
			(copperpour not_allowed)
			(footprints allowed)
		)
		(placement
			(enabled no)
			(sheetname "")
		)
		(fill yes
			(thermal_gap 0.5)
			(thermal_bridge_width 0.5)
			(island_removal_mode 0)
		)
		(polygon
			(pts
				(arc
					(start 349.09887 -249.620024)
					(mid 348.44609 -249.620024)
					(end 349.09887 -249.620024)
				)
			)
		)
	)
	(zone
		(layers "B.Cu" "In13.Cu" "In15.Cu")
		(hatch none 0.5)
		(connect_pads
			(clearance 0)
		)
		(min_thickness 0.25)
		(keepout
			(tracks not_allowed)
			(vias allowed)
			(pads allowed)
			(copperpour not_allowed)
			(footprints allowed)
		)
		(placement
			(enabled no)
			(sheetname "")
		)
		(fill yes
			(thermal_gap 0.5)
			(thermal_bridge_width 0.5)
			(island_removal_mode 0)
		)
		(polygon
			(pts
				(arc
					(start 398.339564 -6.713474)
					(mid 397.635984 -6.713474)
					(end 398.339564 -6.713474)
				)
			)
		)
	)
	(zone
		(layers "B.Cu" "In13.Cu" "In15.Cu")
		(hatch none 0.5)
		(connect_pads
			(clearance 0)
		)
		(min_thickness 0.25)
		(keepout
			(tracks not_allowed)
			(vias allowed)
			(pads allowed)
			(copperpour not_allowed)
			(footprints allowed)
		)
		(placement
			(enabled no)
			(sheetname "")
		)
		(fill yes
			(thermal_gap 0.5)
			(thermal_bridge_width 0.5)
			(island_removal_mode 0)
		)
		(polygon
			(pts
				(arc
					(start 123.823984 -264.50036)
					(mid 123.171204 -264.50036)
					(end 123.823984 -264.50036)
				)
			)
		)
	)
	(zone
		(layers "B.Cu" "In13.Cu" "In15.Cu")
		(hatch none 0.5)
		(connect_pads
			(clearance 0)
		)
		(min_thickness 0.25)
		(keepout
			(tracks not_allowed)
			(vias allowed)
			(pads allowed)
			(copperpour not_allowed)
			(footprints allowed)
		)
		(placement
			(enabled no)
			(sheetname "")
		)
		(fill yes
			(thermal_gap 0.5)
			(thermal_bridge_width 0.5)
			(island_removal_mode 0)
		)
		(polygon
			(pts
				(arc
					(start 207.397604 -279.766776)
					(mid 206.744824 -279.766776)
					(end 207.397604 -279.766776)
				)
			)
		)
	)
	(zone
		(layers "B.Cu" "In13.Cu" "In15.Cu")
		(hatch none 0.5)
		(connect_pads
			(clearance 0)
		)
		(min_thickness 0.25)
		(keepout
			(tracks not_allowed)
			(vias allowed)
			(pads allowed)
			(copperpour not_allowed)
			(footprints allowed)
		)
		(placement
			(enabled no)
			(sheetname "")
		)
		(fill yes
			(thermal_gap 0.5)
			(thermal_bridge_width 0.5)
			(island_removal_mode 0)
		)
		(polygon
			(pts
				(arc
					(start 348.269052 -272.639282)
					(mid 347.616272 -272.639282)
					(end 348.269052 -272.639282)
				)
			)
		)
	)
	(zone
		(layers "B.Cu" "In13.Cu" "In15.Cu")
		(hatch none 0.5)
		(connect_pads
			(clearance 0)
		)
		(min_thickness 0.25)
		(keepout
			(tracks not_allowed)
			(vias allowed)
			(pads allowed)
			(copperpour not_allowed)
			(footprints allowed)
		)
		(placement
			(enabled no)
			(sheetname "")
		)
		(fill yes
			(thermal_gap 0.5)
			(thermal_bridge_width 0.5)
			(island_removal_mode 0)
		)
		(polygon
			(pts
				(arc
					(start 455.337672 -233.016806)
					(mid 454.684892 -233.016806)
					(end 455.337672 -233.016806)
				)
			)
		)
	)
	(zone
		(layers "B.Cu" "In13.Cu" "In15.Cu")
		(hatch none 0.5)
		(connect_pads
			(clearance 0)
		)
		(min_thickness 0.25)
		(keepout
			(tracks not_allowed)
			(vias allowed)
			(pads allowed)
			(copperpour not_allowed)
			(footprints allowed)
		)
		(placement
			(enabled no)
			(sheetname "")
		)
		(fill yes
			(thermal_gap 0.5)
			(thermal_bridge_width 0.5)
			(island_removal_mode 0)
		)
		(polygon
			(pts
				(arc
					(start 352.028252 -274.266914)
					(mid 351.375472 -274.266914)
					(end 352.028252 -274.266914)
				)
			)
		)
	)
	(zone
		(layers "B.Cu" "In13.Cu" "In15.Cu")
		(hatch none 0.5)
		(connect_pads
			(clearance 0)
		)
		(min_thickness 0.25)
		(keepout
			(tracks not_allowed)
			(vias allowed)
			(pads allowed)
			(copperpour not_allowed)
			(footprints allowed)
		)
		(placement
			(enabled no)
			(sheetname "")
		)
		(fill yes
			(thermal_gap 0.5)
			(thermal_bridge_width 0.5)
			(island_removal_mode 0)
		)
		(polygon
			(pts
				(arc
					(start 374.47347 -244.73662)
					(mid 373.82069 -244.73662)
					(end 374.47347 -244.73662)
				)
			)
		)
	)
	(zone
		(layers "B.Cu" "In13.Cu" "In15.Cu")
		(hatch none 0.5)
		(connect_pads
			(clearance 0)
		)
		(min_thickness 0.25)
		(keepout
			(tracks not_allowed)
			(vias allowed)
			(pads allowed)
			(copperpour not_allowed)
			(footprints allowed)
		)
		(placement
			(enabled no)
			(sheetname "")
		)
		(fill yes
			(thermal_gap 0.5)
			(thermal_bridge_width 0.5)
			(island_removal_mode 0)
		)
		(polygon
			(pts
				(arc
					(start 455.337672 -238.966756)
					(mid 454.684892 -238.966756)
					(end 455.337672 -238.966756)
				)
			)
		)
	)
	(zone
		(layers "B.Cu" "In13.Cu" "In15.Cu")
		(hatch none 0.5)
		(connect_pads
			(clearance 0)
		)
		(min_thickness 0.25)
		(keepout
			(tracks not_allowed)
			(vias allowed)
			(pads allowed)
			(copperpour not_allowed)
			(footprints allowed)
		)
		(placement
			(enabled no)
			(sheetname "")
		)
		(fill yes
			(thermal_gap 0.5)
			(thermal_bridge_width 0.5)
			(island_removal_mode 0)
		)
		(polygon
			(pts
				(arc
					(start 100.799138 -278.336502)
					(mid 100.146358 -278.336502)
					(end 100.799138 -278.336502)
				)
			)
		)
	)
	(zone
		(layers "B.Cu" "In13.Cu" "In15.Cu")
		(hatch none 0.5)
		(connect_pads
			(clearance 0)
		)
		(min_thickness 0.25)
		(keepout
			(tracks not_allowed)
			(vias allowed)
			(pads allowed)
			(copperpour not_allowed)
			(footprints allowed)
		)
		(placement
			(enabled no)
			(sheetname "")
		)
		(fill yes
			(thermal_gap 0.5)
			(thermal_bridge_width 0.5)
			(island_removal_mode 0)
		)
		(polygon
			(pts
				(arc
					(start 21.215604 -221.96679)
					(mid 20.562824 -221.96679)
					(end 21.215604 -221.96679)
				)
			)
		)
	)
	(zone
		(layers "B.Cu" "In13.Cu" "In15.Cu")
		(hatch none 0.5)
		(connect_pads
			(clearance 0)
		)
		(min_thickness 0.25)
		(keepout
			(tracks not_allowed)
			(vias allowed)
			(pads allowed)
			(copperpour not_allowed)
			(footprints allowed)
		)
		(placement
			(enabled no)
			(sheetname "")
		)
		(fill yes
			(thermal_gap 0.5)
			(thermal_bridge_width 0.5)
			(island_removal_mode 0)
		)
		(polygon
			(pts
				(arc
					(start 265.055604 -262.76681)
					(mid 264.402824 -262.76681)
					(end 265.055604 -262.76681)
				)
			)
		)
	)
	(zone
		(layers "B.Cu" "In13.Cu" "In15.Cu")
		(hatch none 0.5)
		(connect_pads
			(clearance 0)
		)
		(min_thickness 0.25)
		(keepout
			(tracks not_allowed)
			(vias allowed)
			(pads allowed)
			(copperpour not_allowed)
			(footprints allowed)
		)
		(placement
			(enabled no)
			(sheetname "")
		)
		(fill yes
			(thermal_gap 0.5)
			(thermal_bridge_width 0.5)
			(island_removal_mode 0)
		)
		(polygon
			(pts
				(arc
					(start 125.233938 -273.453098)
					(mid 124.581158 -273.453098)
					(end 125.233938 -273.453098)
				)
			)
		)
	)
	(zone
		(layers "B.Cu" "In13.Cu" "In15.Cu")
		(hatch none 0.5)
		(connect_pads
			(clearance 0)
		)
		(min_thickness 0.25)
		(keepout
			(tracks not_allowed)
			(vias allowed)
			(pads allowed)
			(copperpour not_allowed)
			(footprints allowed)
		)
		(placement
			(enabled no)
			(sheetname "")
		)
		(fill yes
			(thermal_gap 0.5)
			(thermal_bridge_width 0.5)
			(island_removal_mode 0)
		)
		(polygon
			(pts
				(arc
					(start 17.115536 -219.41663)
					(mid 16.462756 -219.41663)
					(end 17.115536 -219.41663)
				)
			)
		)
	)
	(zone
		(layers "B.Cu" "In13.Cu" "In15.Cu")
		(hatch none 0.5)
		(connect_pads
			(clearance 0)
		)
		(min_thickness 0.25)
		(keepout
			(tracks not_allowed)
			(vias allowed)
			(pads allowed)
			(copperpour not_allowed)
			(footprints allowed)
		)
		(placement
			(enabled no)
			(sheetname "")
		)
		(fill yes
			(thermal_gap 0.5)
			(thermal_bridge_width 0.5)
			(island_removal_mode 0)
		)
		(polygon
			(pts
				(arc
					(start 354.847652 -275.8948)
					(mid 354.194872 -275.8948)
					(end 354.847652 -275.8948)
				)
			)
		)
	)
	(zone
		(layers "B.Cu" "In13.Cu" "In15.Cu")
		(hatch none 0.5)
		(connect_pads
			(clearance 0)
		)
		(min_thickness 0.25)
		(keepout
			(tracks not_allowed)
			(vias allowed)
			(pads allowed)
			(copperpour not_allowed)
			(footprints allowed)
		)
		(placement
			(enabled no)
			(sheetname "")
		)
		(fill yes
			(thermal_gap 0.5)
			(thermal_bridge_width 0.5)
			(island_removal_mode 0)
		)
		(polygon
			(pts
				(arc
					(start 105.027984 -282.405836)
					(mid 104.375204 -282.405836)
					(end 105.027984 -282.405836)
				)
			)
		)
	)
	(zone
		(layers "B.Cu" "In13.Cu" "In15.Cu")
		(hatch none 0.5)
		(connect_pads
			(clearance 0)
		)
		(min_thickness 0.25)
		(keepout
			(tracks not_allowed)
			(vias allowed)
			(pads allowed)
			(copperpour not_allowed)
			(footprints allowed)
		)
		(placement
			(enabled no)
			(sheetname "")
		)
		(fill yes
			(thermal_gap 0.5)
			(thermal_bridge_width 0.5)
			(island_removal_mode 0)
		)
		(polygon
			(pts
				(arc
					(start 373.643652 -269.38351)
					(mid 372.990872 -269.38351)
					(end 373.643652 -269.38351)
				)
			)
		)
	)
	(zone
		(layers "B.Cu" "In13.Cu" "In15.Cu")
		(hatch none 0.5)
		(connect_pads
			(clearance 0)
		)
		(min_thickness 0.25)
		(keepout
			(tracks not_allowed)
			(vias allowed)
			(pads allowed)
			(copperpour not_allowed)
			(footprints allowed)
		)
		(placement
			(enabled no)
			(sheetname "")
		)
		(fill yes
			(thermal_gap 0.5)
			(thermal_bridge_width 0.5)
			(island_removal_mode 0)
		)
		(polygon
			(pts
				(arc
					(start 373.53367 -236.597952)
					(mid 372.88089 -236.597952)
					(end 373.53367 -236.597952)
				)
			)
		)
	)
	(zone
		(layers "B.Cu" "In13.Cu" "In15.Cu")
		(hatch none 0.5)
		(connect_pads
			(clearance 0)
		)
		(min_thickness 0.25)
		(keepout
			(tracks not_allowed)
			(vias allowed)
			(pads allowed)
			(copperpour not_allowed)
			(footprints allowed)
		)
		(placement
			(enabled no)
			(sheetname "")
		)
		(fill yes
			(thermal_gap 0.5)
			(thermal_bridge_width 0.5)
			(island_removal_mode 0)
		)
		(polygon
			(pts
				(arc
					(start 66.711068 -403.883876)
					(mid 66.007488 -403.883876)
					(end 66.711068 -403.883876)
				)
			)
		)
	)
	(zone
		(layers "B.Cu" "In13.Cu" "In15.Cu")
		(hatch none 0.5)
		(connect_pads
			(clearance 0)
		)
		(min_thickness 0.25)
		(keepout
			(tracks not_allowed)
			(vias allowed)
			(pads allowed)
			(copperpour not_allowed)
			(footprints allowed)
		)
		(placement
			(enabled no)
			(sheetname "")
		)
		(fill yes
			(thermal_gap 0.5)
			(thermal_bridge_width 0.5)
			(island_removal_mode 0)
		)
		(polygon
			(pts
				(arc
					(start 207.397604 -301.866554)
					(mid 206.744824 -301.866554)
					(end 207.397604 -301.866554)
				)
			)
		)
	)
	(zone
		(layers "B.Cu" "In13.Cu" "In15.Cu")
		(hatch none 0.5)
		(connect_pads
			(clearance 0)
		)
		(min_thickness 0.25)
		(keepout
			(tracks not_allowed)
			(vias allowed)
			(pads allowed)
			(copperpour not_allowed)
			(footprints allowed)
		)
		(placement
			(enabled no)
			(sheetname "")
		)
		(fill yes
			(thermal_gap 0.5)
			(thermal_bridge_width 0.5)
			(island_removal_mode 0)
		)
		(polygon
			(pts
				(arc
					(start 203.297536 -284.866588)
					(mid 202.644756 -284.866588)
					(end 203.297536 -284.866588)
				)
			)
		)
	)
	(zone
		(layers "B.Cu" "In13.Cu" "In15.Cu")
		(hatch none 0.5)
		(connect_pads
			(clearance 0)
		)
		(min_thickness 0.25)
		(keepout
			(tracks not_allowed)
			(vias allowed)
			(pads allowed)
			(copperpour not_allowed)
			(footprints allowed)
		)
		(placement
			(enabled no)
			(sheetname "")
		)
		(fill yes
			(thermal_gap 0.5)
			(thermal_bridge_width 0.5)
			(island_removal_mode 0)
		)
		(polygon
			(pts
				(arc
					(start 207.397604 -231.316784)
					(mid 206.744824 -231.316784)
					(end 207.397604 -231.316784)
				)
			)
		)
	)
	(zone
		(layers "B.Cu" "In13.Cu" "In15.Cu")
		(hatch none 0.5)
		(connect_pads
			(clearance 0)
		)
		(min_thickness 0.25)
		(keepout
			(tracks not_allowed)
			(vias allowed)
			(pads allowed)
			(copperpour not_allowed)
			(footprints allowed)
		)
		(placement
			(enabled no)
			(sheetname "")
		)
		(fill yes
			(thermal_gap 0.5)
			(thermal_bridge_width 0.5)
			(island_removal_mode 0)
		)
		(polygon
			(pts
				(arc
					(start 154.202384 -403.883876)
					(mid 153.498804 -403.883876)
					(end 154.202384 -403.883876)
				)
			)
		)
	)
	(zone
		(layers "B.Cu" "In13.Cu" "In15.Cu")
		(hatch none 0.5)
		(connect_pads
			(clearance 0)
		)
		(min_thickness 0.25)
		(keepout
			(tracks not_allowed)
			(vias allowed)
			(pads allowed)
			(copperpour not_allowed)
			(footprints allowed)
		)
		(placement
			(enabled no)
			(sheetname "")
		)
		(fill yes
			(thermal_gap 0.5)
			(thermal_bridge_width 0.5)
			(island_removal_mode 0)
		)
		(polygon
			(pts
				(arc
					(start 63.054992 -429.689768)
					(mid 62.24524 -429.689768)
					(end 63.054992 -429.689768)
				)
			)
		)
	)
	(zone
		(layers "B.Cu" "In13.Cu" "In15.Cu")
		(hatch none 0.5)
		(connect_pads
			(clearance 0)
		)
		(min_thickness 0.25)
		(keepout
			(tracks not_allowed)
			(vias allowed)
			(pads allowed)
			(copperpour not_allowed)
			(footprints allowed)
		)
		(placement
			(enabled no)
			(sheetname "")
		)
		(fill yes
			(thermal_gap 0.5)
			(thermal_bridge_width 0.5)
			(island_removal_mode 0)
		)
		(polygon
			(pts
				(arc
					(start 123.823984 -266.128246)
					(mid 123.171204 -266.128246)
					(end 123.823984 -266.128246)
				)
			)
		)
	)
	(zone
		(layers "B.Cu" "In13.Cu" "In15.Cu")
		(hatch none 0.5)
		(connect_pads
			(clearance 0)
		)
		(min_thickness 0.25)
		(keepout
			(tracks not_allowed)
			(vias allowed)
			(pads allowed)
			(copperpour not_allowed)
			(footprints allowed)
		)
		(placement
			(enabled no)
			(sheetname "")
		)
		(fill yes
			(thermal_gap 0.5)
			(thermal_bridge_width 0.5)
			(island_removal_mode 0)
		)
		(polygon
			(pts
				(arc
					(start 348.15907 -244.73662)
					(mid 347.50629 -244.73662)
					(end 348.15907 -244.73662)
				)
			)
		)
	)
	(zone
		(layers "B.Cu" "In13.Cu" "In15.Cu")
		(hatch none 0.5)
		(connect_pads
			(clearance 0)
		)
		(min_thickness 0.25)
		(keepout
			(tracks not_allowed)
			(vias allowed)
			(pads allowed)
			(copperpour not_allowed)
			(footprints allowed)
		)
		(placement
			(enabled no)
			(sheetname "")
		)
		(fill yes
			(thermal_gap 0.5)
			(thermal_bridge_width 0.5)
			(island_removal_mode 0)
		)
		(polygon
			(pts
				(arc
					(start 372.234206 -265.314176)
					(mid 371.581426 -265.314176)
					(end 372.234206 -265.314176)
				)
			)
		)
	)
	(zone
		(layers "B.Cu" "In13.Cu" "In15.Cu")
		(hatch none 0.5)
		(connect_pads
			(clearance 0)
		)
		(min_thickness 0.25)
		(keepout
			(tracks not_allowed)
			(vias allowed)
			(pads allowed)
			(copperpour not_allowed)
			(footprints allowed)
		)
		(placement
			(enabled no)
			(sheetname "")
		)
		(fill yes
			(thermal_gap 0.5)
			(thermal_bridge_width 0.5)
			(island_removal_mode 0)
		)
		(polygon
			(pts
				(arc
					(start 416.454336 -4.95173)
					(mid 415.750756 -4.95173)
					(end 416.454336 -4.95173)
				)
			)
		)
	)
	(zone
		(layers "B.Cu" "In13.Cu" "In15.Cu")
		(hatch none 0.5)
		(connect_pads
			(clearance 0)
		)
		(min_thickness 0.25)
		(keepout
			(tracks not_allowed)
			(vias allowed)
			(pads allowed)
			(copperpour not_allowed)
			(footprints allowed)
		)
		(placement
			(enabled no)
			(sheetname "")
		)
		(fill yes
			(thermal_gap 0.5)
			(thermal_bridge_width 0.5)
			(island_removal_mode 0)
		)
		(polygon
			(pts
				(arc
					(start 397.475964 -6.713474)
					(mid 396.772384 -6.713474)
					(end 397.475964 -6.713474)
				)
			)
		)
	)
	(zone
		(layers "B.Cu" "In13.Cu" "In15.Cu")
		(hatch none 0.5)
		(connect_pads
			(clearance 0)
		)
		(min_thickness 0.25)
		(keepout
			(tracks not_allowed)
			(vias allowed)
			(pads allowed)
			(copperpour not_allowed)
			(footprints allowed)
		)
		(placement
			(enabled no)
			(sheetname "")
		)
		(fill yes
			(thermal_gap 0.5)
			(thermal_bridge_width 0.5)
			(island_removal_mode 0)
		)
		(polygon
			(pts
				(arc
					(start 384.154934 -427.089824)
					(mid 383.345182 -427.089824)
					(end 384.154934 -427.089824)
				)
			)
		)
	)
	(zone
		(layers "B.Cu" "In13.Cu" "In15.Cu")
		(hatch none 0.5)
		(connect_pads
			(clearance 0)
		)
		(min_thickness 0.25)
		(keepout
			(tracks not_allowed)
			(vias allowed)
			(pads allowed)
			(copperpour not_allowed)
			(footprints allowed)
		)
		(placement
			(enabled no)
			(sheetname "")
		)
		(fill yes
			(thermal_gap 0.5)
			(thermal_bridge_width 0.5)
			(island_removal_mode 0)
		)
		(polygon
			(pts
				(arc
					(start 101.158802 -244.73662)
					(mid 100.506022 -244.73662)
					(end 101.158802 -244.73662)
				)
			)
		)
	)
	(zone
		(layers "B.Cu" "In13.Cu" "In15.Cu")
		(hatch none 0.5)
		(connect_pads
			(clearance 0)
		)
		(min_thickness 0.25)
		(keepout
			(tracks not_allowed)
			(vias allowed)
			(pads allowed)
			(copperpour not_allowed)
			(footprints allowed)
		)
		(placement
			(enabled no)
			(sheetname "")
		)
		(fill yes
			(thermal_gap 0.5)
			(thermal_bridge_width 0.5)
			(island_removal_mode 0)
		)
		(polygon
			(pts
				(arc
					(start 123.823984 -271.011396)
					(mid 123.171204 -271.011396)
					(end 123.823984 -271.011396)
				)
			)
		)
	)
	(zone
		(layers "B.Cu" "In13.Cu" "In15.Cu")
		(hatch none 0.5)
		(connect_pads
			(clearance 0)
		)
		(min_thickness 0.25)
		(keepout
			(tracks not_allowed)
			(vias allowed)
			(pads allowed)
			(copperpour not_allowed)
			(footprints allowed)
		)
		(placement
			(enabled no)
			(sheetname "")
		)
		(fill yes
			(thermal_gap 0.5)
			(thermal_bridge_width 0.5)
			(island_removal_mode 0)
		)
		(polygon
			(pts
				(arc
					(start 69.774308 -403.883876)
					(mid 69.070728 -403.883876)
					(end 69.774308 -403.883876)
				)
			)
		)
	)
	(zone
		(layers "B.Cu" "In13.Cu" "In15.Cu")
		(hatch none 0.5)
		(connect_pads
			(clearance 0)
		)
		(min_thickness 0.25)
		(keepout
			(tracks not_allowed)
			(vias allowed)
			(pads allowed)
			(copperpour not_allowed)
			(footprints allowed)
		)
		(placement
			(enabled no)
			(sheetname "")
		)
		(fill yes
			(thermal_gap 0.5)
			(thermal_bridge_width 0.5)
			(island_removal_mode 0)
		)
		(polygon
			(pts
				(arc
					(start 52.258468 -403.883876)
					(mid 51.554888 -403.883876)
					(end 52.258468 -403.883876)
				)
			)
		)
	)
	(zone
		(layers "B.Cu" "In13.Cu" "In15.Cu")
		(hatch none 0.5)
		(connect_pads
			(clearance 0)
		)
		(min_thickness 0.25)
		(keepout
			(tracks not_allowed)
			(vias allowed)
			(pads allowed)
			(copperpour not_allowed)
			(footprints allowed)
		)
		(placement
			(enabled no)
			(sheetname "")
		)
		(fill yes
			(thermal_gap 0.5)
			(thermal_bridge_width 0.5)
			(island_removal_mode 0)
		)
		(polygon
			(pts
				(arc
					(start 384.02768 -403.883876)
					(mid 383.3241 -403.883876)
					(end 384.02768 -403.883876)
				)
			)
		)
	)
	(zone
		(layers "B.Cu" "In13.Cu" "In15.Cu")
		(hatch none 0.5)
		(connect_pads
			(clearance 0)
		)
		(min_thickness 0.25)
		(keepout
			(tracks not_allowed)
			(vias allowed)
			(pads allowed)
			(copperpour not_allowed)
			(footprints allowed)
		)
		(placement
			(enabled no)
			(sheetname "")
		)
		(fill yes
			(thermal_gap 0.5)
			(thermal_bridge_width 0.5)
			(island_removal_mode 0)
		)
		(polygon
			(pts
				(arc
					(start 94.220284 -281.59202)
					(mid 93.567504 -281.59202)
					(end 94.220284 -281.59202)
				)
			)
		)
	)
	(zone
		(layers "B.Cu" "In13.Cu" "In15.Cu")
		(hatch none 0.5)
		(connect_pads
			(clearance 0)
		)
		(min_thickness 0.25)
		(keepout
			(tracks not_allowed)
			(vias allowed)
			(pads allowed)
			(copperpour not_allowed)
			(footprints allowed)
		)
		(placement
			(enabled no)
			(sheetname "")
		)
		(fill yes
			(thermal_gap 0.5)
			(thermal_bridge_width 0.5)
			(island_removal_mode 0)
		)
		(polygon
			(pts
				(arc
					(start 349.208852 -277.522432)
					(mid 348.556072 -277.522432)
					(end 349.208852 -277.522432)
				)
			)
		)
	)
	(zone
		(layers "B.Cu" "In13.Cu" "In15.Cu")
		(hatch none 0.5)
		(connect_pads
			(clearance 0)
		)
		(min_thickness 0.25)
		(keepout
			(tracks not_allowed)
			(vias allowed)
			(pads allowed)
			(copperpour not_allowed)
			(footprints allowed)
		)
		(placement
			(enabled no)
			(sheetname "")
		)
		(fill yes
			(thermal_gap 0.5)
			(thermal_bridge_width 0.5)
			(island_removal_mode 0)
		)
		(polygon
			(pts
				(arc
					(start 451.237604 -216.866724)
					(mid 450.584824 -216.866724)
					(end 451.237604 -216.866724)
				)
			)
		)
	)
	(zone
		(layers "B.Cu" "In13.Cu" "In15.Cu")
		(hatch none 0.5)
		(connect_pads
			(clearance 0)
		)
		(min_thickness 0.25)
		(keepout
			(tracks not_allowed)
			(vias allowed)
			(pads allowed)
			(copperpour not_allowed)
			(footprints allowed)
		)
		(placement
			(enabled no)
			(sheetname "")
		)
		(fill yes
			(thermal_gap 0.5)
			(thermal_bridge_width 0.5)
			(island_removal_mode 0)
		)
		(polygon
			(pts
				(arc
					(start 386.15493 -427.289976)
					(mid 385.345178 -427.289976)
					(end 386.15493 -427.289976)
				)
			)
		)
	)
	(zone
		(layers "B.Cu" "In13.Cu" "In15.Cu")
		(hatch none 0.5)
		(connect_pads
			(clearance 0)
		)
		(min_thickness 0.25)
		(keepout
			(tracks not_allowed)
			(vias allowed)
			(pads allowed)
			(copperpour not_allowed)
			(footprints allowed)
		)
		(placement
			(enabled no)
			(sheetname "")
		)
		(fill yes
			(thermal_gap 0.5)
			(thermal_bridge_width 0.5)
			(island_removal_mode 0)
		)
		(polygon
			(pts
				(arc
					(start 122.774202 -226.831144)
					(mid 122.121422 -226.831144)
					(end 122.774202 -226.831144)
				)
			)
		)
	)
	(zone
		(layers "B.Cu" "In13.Cu" "In15.Cu")
		(hatch none 0.5)
		(connect_pads
			(clearance 0)
		)
		(min_thickness 0.25)
		(keepout
			(tracks not_allowed)
			(vias allowed)
			(pads allowed)
			(copperpour not_allowed)
			(footprints allowed)
		)
		(placement
			(enabled no)
			(sheetname "")
		)
		(fill yes
			(thermal_gap 0.5)
			(thermal_bridge_width 0.5)
			(island_removal_mode 0)
		)
		(polygon
			(pts
				(arc
					(start 84.05495 -429.689768)
					(mid 83.245198 -429.689768)
					(end 84.05495 -429.689768)
				)
			)
		)
	)
	(zone
		(layers "B.Cu" "In13.Cu" "In15.Cu")
		(hatch none 0.5)
		(connect_pads
			(clearance 0)
		)
		(min_thickness 0.25)
		(keepout
			(tracks not_allowed)
			(vias allowed)
			(pads allowed)
			(copperpour not_allowed)
			(footprints allowed)
		)
		(placement
			(enabled no)
			(sheetname "")
		)
		(fill yes
			(thermal_gap 0.5)
			(thermal_bridge_width 0.5)
			(island_removal_mode 0)
		)
		(polygon
			(pts
				(arc
					(start 344.980006 -283.219906)
					(mid 344.327226 -283.219906)
					(end 344.980006 -283.219906)
				)
			)
		)
	)
	(zone
		(layers "B.Cu" "In13.Cu" "In15.Cu")
		(hatch none 0.5)
		(connect_pads
			(clearance 0)
		)
		(min_thickness 0.25)
		(keepout
			(tracks not_allowed)
			(vias allowed)
			(pads allowed)
			(copperpour not_allowed)
			(footprints allowed)
		)
		(placement
			(enabled no)
			(sheetname "")
		)
		(fill yes
			(thermal_gap 0.5)
			(thermal_bridge_width 0.5)
			(island_removal_mode 0)
		)
		(polygon
			(pts
				(arc
					(start 387.09092 -403.883876)
					(mid 386.38734 -403.883876)
					(end 387.09092 -403.883876)
				)
			)
		)
	)
	(zone
		(layers "B.Cu" "In13.Cu" "In15.Cu")
		(hatch none 0.5)
		(connect_pads
			(clearance 0)
		)
		(min_thickness 0.25)
		(keepout
			(tracks not_allowed)
			(vias allowed)
			(pads allowed)
			(copperpour not_allowed)
			(footprints allowed)
		)
		(placement
			(enabled no)
			(sheetname "")
		)
		(fill yes
			(thermal_gap 0.5)
			(thermal_bridge_width 0.5)
			(island_removal_mode 0)
		)
		(polygon
			(pts
				(arc
					(start 104.558338 -281.59202)
					(mid 103.905558 -281.59202)
					(end 104.558338 -281.59202)
				)
			)
		)
	)
	(zone
		(layers "B.Cu" "In13.Cu" "In15.Cu")
		(hatch none 0.5)
		(connect_pads
			(clearance 0)
		)
		(min_thickness 0.25)
		(keepout
			(tracks not_allowed)
			(vias allowed)
			(pads allowed)
			(copperpour not_allowed)
			(footprints allowed)
		)
		(placement
			(enabled no)
			(sheetname "")
		)
		(fill yes
			(thermal_gap 0.5)
			(thermal_bridge_width 0.5)
			(island_removal_mode 0)
		)
		(polygon
			(pts
				(arc
					(start 455.337672 -227.91674)
					(mid 454.684892 -227.91674)
					(end 455.337672 -227.91674)
				)
			)
		)
	)
	(zone
		(layers "B.Cu" "In13.Cu" "In15.Cu")
		(hatch none 0.5)
		(connect_pads
			(clearance 0)
		)
		(min_thickness 0.25)
		(keepout
			(tracks not_allowed)
			(vias allowed)
			(pads allowed)
			(copperpour not_allowed)
			(footprints allowed)
		)
		(placement
			(enabled no)
			(sheetname "")
		)
		(fill yes
			(thermal_gap 0.5)
			(thermal_bridge_width 0.5)
			(island_removal_mode 0)
		)
		(polygon
			(pts
				(arc
					(start 348.15907 -228.45903)
					(mid 347.50629 -228.45903)
					(end 348.15907 -228.45903)
				)
			)
		)
	)
	(zone
		(layers "B.Cu" "In13.Cu" "In15.Cu")
		(hatch none 0.5)
		(connect_pads
			(clearance 0)
		)
		(min_thickness 0.25)
		(keepout
			(tracks not_allowed)
			(vias allowed)
			(pads allowed)
			(copperpour not_allowed)
			(footprints allowed)
		)
		(placement
			(enabled no)
			(sheetname "")
		)
		(fill yes
			(thermal_gap 0.5)
			(thermal_bridge_width 0.5)
			(island_removal_mode 0)
		)
		(polygon
			(pts
				(arc
					(start 100.799138 -276.708616)
					(mid 100.146358 -276.708616)
					(end 100.799138 -276.708616)
				)
			)
		)
	)
	(zone
		(layers "B.Cu" "In13.Cu" "In15.Cu")
		(hatch none 0.5)
		(connect_pads
			(clearance 0)
		)
		(min_thickness 0.25)
		(keepout
			(tracks not_allowed)
			(vias allowed)
			(pads allowed)
			(copperpour not_allowed)
			(footprints allowed)
		)
		(placement
			(enabled no)
			(sheetname "")
		)
		(fill yes
			(thermal_gap 0.5)
			(thermal_bridge_width 0.5)
			(island_removal_mode 0)
		)
		(polygon
			(pts
				(arc
					(start 207.397604 -229.616762)
					(mid 206.744824 -229.616762)
					(end 207.397604 -229.616762)
				)
			)
		)
	)
	(zone
		(layers "B.Cu" "In13.Cu" "In15.Cu")
		(hatch none 0.5)
		(connect_pads
			(clearance 0)
		)
		(min_thickness 0.25)
		(keepout
			(tracks not_allowed)
			(vias allowed)
			(pads allowed)
			(copperpour not_allowed)
			(footprints allowed)
		)
		(placement
			(enabled no)
			(sheetname "")
		)
		(fill yes
			(thermal_gap 0.5)
			(thermal_bridge_width 0.5)
			(island_removal_mode 0)
		)
		(polygon
			(pts
				(arc
					(start 125.593602 -233.34218)
					(mid 124.940822 -233.34218)
					(end 125.593602 -233.34218)
				)
			)
		)
	)
	(zone
		(layers "B.Cu" "In13.Cu" "In15.Cu")
		(hatch none 0.5)
		(connect_pads
			(clearance 0)
		)
		(min_thickness 0.25)
		(keepout
			(tracks not_allowed)
			(vias allowed)
			(pads allowed)
			(copperpour not_allowed)
			(footprints allowed)
		)
		(placement
			(enabled no)
			(sheetname "")
		)
		(fill yes
			(thermal_gap 0.5)
			(thermal_bridge_width 0.5)
			(island_removal_mode 0)
		)
		(polygon
			(pts
				(arc
					(start 100.328984 -275.8948)
					(mid 99.676204 -275.8948)
					(end 100.328984 -275.8948)
				)
			)
		)
	)
	(zone
		(layers "B.Cu" "In13.Cu" "In15.Cu")
		(hatch none 0.5)
		(connect_pads
			(clearance 0)
		)
		(min_thickness 0.25)
		(keepout
			(tracks not_allowed)
			(vias allowed)
			(pads allowed)
			(copperpour not_allowed)
			(footprints allowed)
		)
		(placement
			(enabled no)
			(sheetname "")
		)
		(fill yes
			(thermal_gap 0.5)
			(thermal_bridge_width 0.5)
			(island_removal_mode 0)
		)
		(polygon
			(pts
				(arc
					(start 346.749624 -243.922804)
					(mid 346.096844 -243.922804)
					(end 346.749624 -243.922804)
				)
			)
		)
	)
	(zone
		(layers "B.Cu" "In13.Cu" "In15.Cu")
		(hatch none 0.5)
		(connect_pads
			(clearance 0)
		)
		(min_thickness 0.25)
		(keepout
			(tracks not_allowed)
			(vias allowed)
			(pads allowed)
			(copperpour not_allowed)
			(footprints allowed)
		)
		(placement
			(enabled no)
			(sheetname "")
		)
		(fill yes
			(thermal_gap 0.5)
			(thermal_bridge_width 0.5)
			(island_removal_mode 0)
		)
		(polygon
			(pts
				(arc
					(start 125.233938 -266.941808)
					(mid 124.581158 -266.941808)
					(end 125.233938 -266.941808)
				)
			)
		)
	)
	(zone
		(layers "B.Cu" "In13.Cu" "In15.Cu")
		(hatch none 0.5)
		(connect_pads
			(clearance 0)
		)
		(min_thickness 0.25)
		(keepout
			(tracks not_allowed)
			(vias allowed)
			(pads allowed)
			(copperpour not_allowed)
			(footprints allowed)
		)
		(placement
			(enabled no)
			(sheetname "")
		)
		(fill yes
			(thermal_gap 0.5)
			(thermal_bridge_width 0.5)
			(island_removal_mode 0)
		)
		(polygon
			(pts
				(arc
					(start 451.237604 -284.016704)
					(mid 450.584824 -284.016704)
					(end 451.237604 -284.016704)
				)
			)
		)
	)
	(zone
		(layers "B.Cu" "In13.Cu" "In15.Cu")
		(hatch none 0.5)
		(connect_pads
			(clearance 0)
		)
		(min_thickness 0.25)
		(keepout
			(tracks not_allowed)
			(vias allowed)
			(pads allowed)
			(copperpour not_allowed)
			(footprints allowed)
		)
		(placement
			(enabled no)
			(sheetname "")
		)
		(fill yes
			(thermal_gap 0.5)
			(thermal_bridge_width 0.5)
			(island_removal_mode 0)
		)
		(polygon
			(pts
				(arc
					(start 269.155672 -229.616762)
					(mid 268.502892 -229.616762)
					(end 269.155672 -229.616762)
				)
			)
		)
	)
	(zone
		(layers "B.Cu" "In13.Cu" "In15.Cu")
		(hatch none 0.5)
		(connect_pads
			(clearance 0)
		)
		(min_thickness 0.25)
		(keepout
			(tracks not_allowed)
			(vias allowed)
			(pads allowed)
			(copperpour not_allowed)
			(footprints allowed)
		)
		(placement
			(enabled no)
			(sheetname "")
		)
		(fill yes
			(thermal_gap 0.5)
			(thermal_bridge_width 0.5)
			(island_removal_mode 0)
		)
		(polygon
			(pts
				(arc
					(start 265.055604 -289.966654)
					(mid 264.402824 -289.966654)
					(end 265.055604 -289.966654)
				)
			)
		)
	)
	(zone
		(layers "B.Cu" "In13.Cu" "In15.Cu")
		(hatch none 0.5)
		(connect_pads
			(clearance 0)
		)
		(min_thickness 0.25)
		(keepout
			(tracks not_allowed)
			(vias allowed)
			(pads allowed)
			(copperpour not_allowed)
			(footprints allowed)
		)
		(placement
			(enabled no)
			(sheetname "")
		)
		(fill yes
			(thermal_gap 0.5)
			(thermal_bridge_width 0.5)
			(island_removal_mode 0)
		)
		(polygon
			(pts
				(arc
					(start 57.521348 -403.883876)
					(mid 56.817768 -403.883876)
					(end 57.521348 -403.883876)
				)
			)
		)
	)
	(zone
		(layers "B.Cu" "In13.Cu" "In15.Cu")
		(hatch none 0.5)
		(connect_pads
			(clearance 0)
		)
		(min_thickness 0.25)
		(keepout
			(tracks not_allowed)
			(vias allowed)
			(pads allowed)
			(copperpour not_allowed)
			(footprints allowed)
		)
		(placement
			(enabled no)
			(sheetname "")
		)
		(fill yes
			(thermal_gap 0.5)
			(thermal_bridge_width 0.5)
			(island_removal_mode 0)
		)
		(polygon
			(pts
				(arc
					(start 359.43667 -220.319854)
					(mid 358.78389 -220.319854)
					(end 359.43667 -220.319854)
				)
			)
		)
	)
	(zone
		(layers "B.Cu" "In13.Cu" "In15.Cu")
		(hatch none 0.5)
		(connect_pads
			(clearance 0)
		)
		(min_thickness 0.25)
		(keepout
			(tracks not_allowed)
			(vias allowed)
			(pads allowed)
			(copperpour not_allowed)
			(footprints allowed)
		)
		(placement
			(enabled no)
			(sheetname "")
		)
		(fill yes
			(thermal_gap 0.5)
			(thermal_bridge_width 0.5)
			(island_removal_mode 0)
		)
		(polygon
			(pts
				(arc
					(start 126.173738 -260.430772)
					(mid 125.520958 -260.430772)
					(end 126.173738 -260.430772)
				)
			)
		)
	)
	(zone
		(layers "B.Cu" "In13.Cu" "In15.Cu")
		(hatch none 0.5)
		(connect_pads
			(clearance 0)
		)
		(min_thickness 0.25)
		(keepout
			(tracks not_allowed)
			(vias allowed)
			(pads allowed)
			(copperpour not_allowed)
			(footprints allowed)
		)
		(placement
			(enabled no)
			(sheetname "")
		)
		(fill yes
			(thermal_gap 0.5)
			(thermal_bridge_width 0.5)
			(island_removal_mode 0)
		)
		(polygon
			(pts
				(arc
					(start 373.643652 -259.616956)
					(mid 372.990872 -259.616956)
					(end 373.643652 -259.616956)
				)
			)
		)
	)
	(zone
		(layers "B.Cu" "In13.Cu" "In15.Cu")
		(hatch none 0.5)
		(connect_pads
			(clearance 0)
		)
		(min_thickness 0.25)
		(keepout
			(tracks not_allowed)
			(vias allowed)
			(pads allowed)
			(copperpour not_allowed)
			(footprints allowed)
		)
		(placement
			(enabled no)
			(sheetname "")
		)
		(fill yes
			(thermal_gap 0.5)
			(thermal_bridge_width 0.5)
			(island_removal_mode 0)
		)
		(polygon
			(pts
				(arc
					(start 21.215604 -287.416748)
					(mid 20.562824 -287.416748)
					(end 21.215604 -287.416748)
				)
			)
		)
	)
	(zone
		(layers "B.Cu" "In13.Cu" "In15.Cu")
		(hatch none 0.5)
		(connect_pads
			(clearance 0)
		)
		(min_thickness 0.25)
		(keepout
			(tracks not_allowed)
			(vias allowed)
			(pads allowed)
			(copperpour not_allowed)
			(footprints allowed)
		)
		(placement
			(enabled no)
			(sheetname "")
		)
		(fill yes
			(thermal_gap 0.5)
			(thermal_bridge_width 0.5)
			(island_removal_mode 0)
		)
		(polygon
			(pts
				(arc
					(start 356.257606 -278.336502)
					(mid 355.604826 -278.336502)
					(end 356.257606 -278.336502)
				)
			)
		)
	)
	(zone
		(layers "B.Cu" "In13.Cu" "In15.Cu")
		(hatch none 0.5)
		(connect_pads
			(clearance 0)
		)
		(min_thickness 0.25)
		(keepout
			(tracks not_allowed)
			(vias allowed)
			(pads allowed)
			(copperpour not_allowed)
			(footprints allowed)
		)
		(placement
			(enabled no)
			(sheetname "")
		)
		(fill yes
			(thermal_gap 0.5)
			(thermal_bridge_width 0.5)
			(island_removal_mode 0)
		)
		(polygon
			(pts
				(arc
					(start 265.055604 -288.266632)
					(mid 264.402824 -288.266632)
					(end 265.055604 -288.266632)
				)
			)
		)
	)
	(zone
		(layers "B.Cu" "In13.Cu" "In15.Cu")
		(hatch none 0.5)
		(connect_pads
			(clearance 0)
		)
		(min_thickness 0.25)
		(keepout
			(tracks not_allowed)
			(vias allowed)
			(pads allowed)
			(copperpour not_allowed)
			(footprints allowed)
		)
		(placement
			(enabled no)
			(sheetname "")
		)
		(fill yes
			(thermal_gap 0.5)
			(thermal_bridge_width 0.5)
			(island_removal_mode 0)
		)
		(polygon
			(pts
				(arc
					(start 125.703584 -254.733552)
					(mid 125.050804 -254.733552)
					(end 125.703584 -254.733552)
				)
			)
		)
	)
	(zone
		(layers "B.Cu" "In13.Cu" "In15.Cu")
		(hatch none 0.5)
		(connect_pads
			(clearance 0)
		)
		(min_thickness 0.25)
		(keepout
			(tracks not_allowed)
			(vias allowed)
			(pads allowed)
			(copperpour not_allowed)
			(footprints allowed)
		)
		(placement
			(enabled no)
			(sheetname "")
		)
		(fill yes
			(thermal_gap 0.5)
			(thermal_bridge_width 0.5)
			(island_removal_mode 0)
		)
		(polygon
			(pts
				(arc
					(start 124.294138 -271.825212)
					(mid 123.641358 -271.825212)
					(end 124.294138 -271.825212)
				)
			)
		)
	)
	(zone
		(layers "B.Cu" "In13.Cu" "In15.Cu")
		(hatch none 0.5)
		(connect_pads
			(clearance 0)
		)
		(min_thickness 0.25)
		(keepout
			(tracks not_allowed)
			(vias allowed)
			(pads allowed)
			(copperpour not_allowed)
			(footprints allowed)
		)
		(placement
			(enabled no)
			(sheetname "")
		)
		(fill yes
			(thermal_gap 0.5)
			(thermal_bridge_width 0.5)
			(island_removal_mode 0)
		)
		(polygon
			(pts
				(arc
					(start 105.857802 -220.319854)
					(mid 105.205022 -220.319854)
					(end 105.857802 -220.319854)
				)
			)
		)
	)
	(zone
		(layers "B.Cu" "In13.Cu" "In15.Cu")
		(hatch none 0.5)
		(connect_pads
			(clearance 0)
		)
		(min_thickness 0.25)
		(keepout
			(tracks not_allowed)
			(vias allowed)
			(pads allowed)
			(copperpour not_allowed)
			(footprints allowed)
		)
		(placement
			(enabled no)
			(sheetname "")
		)
		(fill yes
			(thermal_gap 0.5)
			(thermal_bridge_width 0.5)
			(island_removal_mode 0)
		)
		(polygon
			(pts
				(arc
					(start 99.279202 -234.970066)
					(mid 98.626422 -234.970066)
					(end 99.279202 -234.970066)
				)
			)
		)
	)
	(zone
		(layers "B.Cu" "In13.Cu" "In15.Cu")
		(hatch none 0.5)
		(connect_pads
			(clearance 0)
		)
		(min_thickness 0.25)
		(keepout
			(tracks not_allowed)
			(vias allowed)
			(pads allowed)
			(copperpour not_allowed)
			(footprints allowed)
		)
		(placement
			(enabled no)
			(sheetname "")
		)
		(fill yes
			(thermal_gap 0.5)
			(thermal_bridge_width 0.5)
			(island_removal_mode 0)
		)
		(polygon
			(pts
				(arc
					(start 207.397604 -287.416748)
					(mid 206.744824 -287.416748)
					(end 207.397604 -287.416748)
				)
			)
		)
	)
	(zone
		(layers "B.Cu" "In13.Cu" "In15.Cu")
		(hatch none 0.5)
		(connect_pads
			(clearance 0)
		)
		(min_thickness 0.25)
		(keepout
			(tracks not_allowed)
			(vias allowed)
			(pads allowed)
			(copperpour not_allowed)
			(footprints allowed)
		)
		(placement
			(enabled no)
			(sheetname "")
		)
		(fill yes
			(thermal_gap 0.5)
			(thermal_bridge_width 0.5)
			(island_removal_mode 0)
		)
		(polygon
			(pts
				(arc
					(start 126.173738 -255.547622)
					(mid 125.520958 -255.547622)
					(end 126.173738 -255.547622)
				)
			)
		)
	)
	(zone
		(layers "B.Cu" "In13.Cu" "In15.Cu")
		(hatch none 0.5)
		(connect_pads
			(clearance 0)
		)
		(min_thickness 0.25)
		(keepout
			(tracks not_allowed)
			(vias allowed)
			(pads allowed)
			(copperpour not_allowed)
			(footprints allowed)
		)
		(placement
			(enabled no)
			(sheetname "")
		)
		(fill yes
			(thermal_gap 0.5)
			(thermal_bridge_width 0.5)
			(island_removal_mode 0)
		)
		(polygon
			(pts
				(arc
					(start 403.744176 -4.95173)
					(mid 403.040596 -4.95173)
					(end 403.744176 -4.95173)
				)
			)
		)
	)
	(zone
		(layers "B.Cu" "In13.Cu" "In15.Cu")
		(hatch none 0.5)
		(connect_pads
			(clearance 0)
		)
		(min_thickness 0.25)
		(keepout
			(tracks not_allowed)
			(vias allowed)
			(pads allowed)
			(copperpour not_allowed)
			(footprints allowed)
		)
		(placement
			(enabled no)
			(sheetname "")
		)
		(fill yes
			(thermal_gap 0.5)
			(thermal_bridge_width 0.5)
			(island_removal_mode 0)
		)
		(polygon
			(pts
				(arc
					(start 455.337672 -295.06672)
					(mid 454.684892 -295.06672)
					(end 455.337672 -295.06672)
				)
			)
		)
	)
	(zone
		(layers "B.Cu" "In13.Cu" "In15.Cu")
		(hatch none 0.5)
		(connect_pads
			(clearance 0)
		)
		(min_thickness 0.25)
		(keepout
			(tracks not_allowed)
			(vias allowed)
			(pads allowed)
			(copperpour not_allowed)
			(footprints allowed)
		)
		(placement
			(enabled no)
			(sheetname "")
		)
		(fill yes
			(thermal_gap 0.5)
			(thermal_bridge_width 0.5)
			(island_removal_mode 0)
		)
		(polygon
			(pts
				(arc
					(start 207.397604 -220.266768)
					(mid 206.744824 -220.266768)
					(end 207.397604 -220.266768)
				)
			)
		)
	)
	(zone
		(layers "B.Cu" "In13.Cu" "In15.Cu")
		(hatch none 0.5)
		(connect_pads
			(clearance 0)
		)
		(min_thickness 0.25)
		(keepout
			(tracks not_allowed)
			(vias allowed)
			(pads allowed)
			(copperpour not_allowed)
			(footprints allowed)
		)
		(placement
			(enabled no)
			(sheetname "")
		)
		(fill yes
			(thermal_gap 0.5)
			(thermal_bridge_width 0.5)
			(island_removal_mode 0)
		)
		(polygon
			(pts
				(arc
					(start 203.297536 -202.416664)
					(mid 202.644756 -202.416664)
					(end 203.297536 -202.416664)
				)
			)
		)
	)
	(zone
		(layers "B.Cu" "In13.Cu" "In15.Cu")
		(hatch none 0.5)
		(connect_pads
			(clearance 0)
		)
		(min_thickness 0.25)
		(keepout
			(tracks not_allowed)
			(vias allowed)
			(pads allowed)
			(copperpour not_allowed)
			(footprints allowed)
		)
		(placement
			(enabled no)
			(sheetname "")
		)
		(fill yes
			(thermal_gap 0.5)
			(thermal_bridge_width 0.5)
			(island_removal_mode 0)
		)
		(polygon
			(pts
				(arc
					(start 407.154888 -427.289976)
					(mid 406.345136 -427.289976)
					(end 407.154888 -427.289976)
				)
			)
		)
	)
	(zone
		(layers "B.Cu" "In13.Cu" "In15.Cu")
		(hatch none 0.5)
		(connect_pads
			(clearance 0)
		)
		(min_thickness 0.25)
		(keepout
			(tracks not_allowed)
			(vias allowed)
			(pads allowed)
			(copperpour not_allowed)
			(footprints allowed)
		)
		(placement
			(enabled no)
			(sheetname "")
		)
		(fill yes
			(thermal_gap 0.5)
			(thermal_bridge_width 0.5)
			(island_removal_mode 0)
		)
		(polygon
			(pts
				(arc
					(start 451.237604 -282.316682)
					(mid 450.584824 -282.316682)
					(end 451.237604 -282.316682)
				)
			)
		)
	)
	(zone
		(layers "B.Cu" "In13.Cu" "In15.Cu")
		(hatch none 0.5)
		(connect_pads
			(clearance 0)
		)
		(min_thickness 0.25)
		(keepout
			(tracks not_allowed)
			(vias allowed)
			(pads allowed)
			(copperpour not_allowed)
			(footprints allowed)
		)
		(placement
			(enabled no)
			(sheetname "")
		)
		(fill yes
			(thermal_gap 0.5)
			(thermal_bridge_width 0.5)
			(island_removal_mode 0)
		)
		(polygon
			(pts
				(arc
					(start 451.237604 -199.866758)
					(mid 450.584824 -199.866758)
					(end 451.237604 -199.866758)
				)
			)
		)
	)
	(zone
		(layers "B.Cu" "In13.Cu" "In15.Cu")
		(hatch none 0.5)
		(connect_pads
			(clearance 0)
		)
		(min_thickness 0.25)
		(keepout
			(tracks not_allowed)
			(vias allowed)
			(pads allowed)
			(copperpour not_allowed)
			(footprints allowed)
		)
		(placement
			(enabled no)
			(sheetname "")
		)
		(fill yes
			(thermal_gap 0.5)
			(thermal_bridge_width 0.5)
			(island_removal_mode 0)
		)
		(polygon
			(pts
				(arc
					(start 371.294406 -275.08073)
					(mid 370.641626 -275.08073)
					(end 371.294406 -275.08073)
				)
			)
		)
	)
	(zone
		(layers "B.Cu" "In13.Cu" "In15.Cu")
		(hatch none 0.5)
		(connect_pads
			(clearance 0)
		)
		(min_thickness 0.25)
		(keepout
			(tracks not_allowed)
			(vias allowed)
			(pads allowed)
			(copperpour not_allowed)
			(footprints allowed)
		)
		(placement
			(enabled no)
			(sheetname "")
		)
		(fill yes
			(thermal_gap 0.5)
			(thermal_bridge_width 0.5)
			(island_removal_mode 0)
		)
		(polygon
			(pts
				(arc
					(start 98.919538 -266.941808)
					(mid 98.266758 -266.941808)
					(end 98.919538 -266.941808)
				)
			)
		)
	)
	(zone
		(layers "B.Cu" "In13.Cu" "In15.Cu")
		(hatch none 0.5)
		(connect_pads
			(clearance 0)
		)
		(min_thickness 0.25)
		(keepout
			(tracks not_allowed)
			(vias allowed)
			(pads allowed)
			(copperpour not_allowed)
			(footprints allowed)
		)
		(placement
			(enabled no)
			(sheetname "")
		)
		(fill yes
			(thermal_gap 0.5)
			(thermal_bridge_width 0.5)
			(island_removal_mode 0)
		)
		(polygon
			(pts
				(arc
					(start 269.155672 -259.366766)
					(mid 268.502892 -259.366766)
					(end 269.155672 -259.366766)
				)
			)
		)
	)
	(zone
		(layers "B.Cu" "In13.Cu" "In15.Cu")
		(hatch none 0.5)
		(connect_pads
			(clearance 0)
		)
		(min_thickness 0.25)
		(keepout
			(tracks not_allowed)
			(vias allowed)
			(pads allowed)
			(copperpour not_allowed)
			(footprints allowed)
		)
		(placement
			(enabled no)
			(sheetname "")
		)
		(fill yes
			(thermal_gap 0.5)
			(thermal_bridge_width 0.5)
			(island_removal_mode 0)
		)
		(polygon
			(pts
				(arc
					(start 124.294138 -276.708616)
					(mid 123.641358 -276.708616)
					(end 124.294138 -276.708616)
				)
			)
		)
	)
	(zone
		(layers "B.Cu" "In13.Cu" "In15.Cu")
		(hatch none 0.5)
		(connect_pads
			(clearance 0)
		)
		(min_thickness 0.25)
		(keepout
			(tracks not_allowed)
			(vias allowed)
			(pads allowed)
			(copperpour not_allowed)
			(footprints allowed)
		)
		(placement
			(enabled no)
			(sheetname "")
		)
		(fill yes
			(thermal_gap 0.5)
			(thermal_bridge_width 0.5)
			(island_removal_mode 0)
		)
		(polygon
			(pts
				(arc
					(start 451.237604 -247.466612)
					(mid 450.584824 -247.466612)
					(end 451.237604 -247.466612)
				)
			)
		)
	)
	(zone
		(layers "B.Cu" "In13.Cu" "In15.Cu")
		(hatch none 0.5)
		(connect_pads
			(clearance 0)
		)
		(min_thickness 0.25)
		(keepout
			(tracks not_allowed)
			(vias allowed)
			(pads allowed)
			(copperpour not_allowed)
			(footprints allowed)
		)
		(placement
			(enabled no)
			(sheetname "")
		)
		(fill yes
			(thermal_gap 0.5)
			(thermal_bridge_width 0.5)
			(island_removal_mode 0)
		)
		(polygon
			(pts
				(arc
					(start 99.389184 -267.755878)
					(mid 98.736404 -267.755878)
					(end 99.389184 -267.755878)
				)
			)
		)
	)
	(zone
		(layers "B.Cu" "In13.Cu" "In15.Cu")
		(hatch none 0.5)
		(connect_pads
			(clearance 0)
		)
		(min_thickness 0.25)
		(keepout
			(tracks not_allowed)
			(vias allowed)
			(pads allowed)
			(copperpour not_allowed)
			(footprints allowed)
		)
		(placement
			(enabled no)
			(sheetname "")
		)
		(fill yes
			(thermal_gap 0.5)
			(thermal_bridge_width 0.5)
			(island_removal_mode 0)
		)
		(polygon
			(pts
				(arc
					(start 451.237604 -239.81664)
					(mid 450.584824 -239.81664)
					(end 451.237604 -239.81664)
				)
			)
		)
	)
	(zone
		(layers "B.Cu" "In13.Cu" "In15.Cu")
		(hatch none 0.5)
		(connect_pads
			(clearance 0)
		)
		(min_thickness 0.25)
		(keepout
			(tracks not_allowed)
			(vias allowed)
			(pads allowed)
			(copperpour not_allowed)
			(footprints allowed)
		)
		(placement
			(enabled no)
			(sheetname "")
		)
		(fill yes
			(thermal_gap 0.5)
			(thermal_bridge_width 0.5)
			(island_removal_mode 0)
		)
		(polygon
			(pts
				(arc
					(start 149.154896 -428.28972)
					(mid 148.345144 -428.28972)
					(end 149.154896 -428.28972)
				)
			)
		)
	)
	(zone
		(layers "B.Cu" "In13.Cu" "In15.Cu")
		(hatch none 0.5)
		(connect_pads
			(clearance 0)
		)
		(min_thickness 0.25)
		(keepout
			(tracks not_allowed)
			(vias allowed)
			(pads allowed)
			(copperpour not_allowed)
			(footprints allowed)
		)
		(placement
			(enabled no)
			(sheetname "")
		)
		(fill yes
			(thermal_gap 0.5)
			(thermal_bridge_width 0.5)
			(island_removal_mode 0)
		)
		(polygon
			(pts
				(arc
					(start 338.05495 -431.889916)
					(mid 337.245198 -431.889916)
					(end 338.05495 -431.889916)
				)
			)
		)
	)
	(zone
		(layers "B.Cu" "In13.Cu" "In15.Cu")
		(hatch none 0.5)
		(connect_pads
			(clearance 0)
		)
		(min_thickness 0.25)
		(keepout
			(tracks not_allowed)
			(vias allowed)
			(pads allowed)
			(copperpour not_allowed)
			(footprints allowed)
		)
		(placement
			(enabled no)
			(sheetname "")
		)
		(fill yes
			(thermal_gap 0.5)
			(thermal_bridge_width 0.5)
			(island_removal_mode 0)
		)
		(polygon
			(pts
				(arc
					(start 455.337672 -270.416782)
					(mid 454.684892 -270.416782)
					(end 455.337672 -270.416782)
				)
			)
		)
	)
	(zone
		(layers "B.Cu" "In13.Cu" "In15.Cu")
		(hatch none 0.5)
		(connect_pads
			(clearance 0)
		)
		(min_thickness 0.25)
		(keepout
			(tracks not_allowed)
			(vias allowed)
			(pads allowed)
			(copperpour not_allowed)
			(footprints allowed)
		)
		(placement
			(enabled no)
			(sheetname "")
		)
		(fill yes
			(thermal_gap 0.5)
			(thermal_bridge_width 0.5)
			(island_removal_mode 0)
		)
		(polygon
			(pts
				(arc
					(start 111.966756 -221.133924)
					(mid 111.313976 -221.133924)
					(end 111.966756 -221.133924)
				)
			)
		)
	)
	(zone
		(layers "B.Cu" "In13.Cu" "In15.Cu")
		(hatch none 0.5)
		(connect_pads
			(clearance 0)
		)
		(min_thickness 0.25)
		(keepout
			(tracks not_allowed)
			(vias allowed)
			(pads allowed)
			(copperpour not_allowed)
			(footprints allowed)
		)
		(placement
			(enabled no)
			(sheetname "")
		)
		(fill yes
			(thermal_gap 0.5)
			(thermal_bridge_width 0.5)
			(island_removal_mode 0)
		)
		(polygon
			(pts
				(arc
					(start 107.267756 -221.133924)
					(mid 106.614976 -221.133924)
					(end 107.267756 -221.133924)
				)
			)
		)
	)
	(zone
		(layers "B.Cu" "In13.Cu" "In15.Cu")
		(hatch none 0.5)
		(connect_pads
			(clearance 0)
		)
		(min_thickness 0.25)
		(keepout
			(tracks not_allowed)
			(vias allowed)
			(pads allowed)
			(copperpour not_allowed)
			(footprints allowed)
		)
		(placement
			(enabled no)
			(sheetname "")
		)
		(fill yes
			(thermal_gap 0.5)
			(thermal_bridge_width 0.5)
			(island_removal_mode 0)
		)
		(polygon
			(pts
				(arc
					(start 100.219002 -236.597952)
					(mid 99.566222 -236.597952)
					(end 100.219002 -236.597952)
				)
			)
		)
	)
	(zone
		(layers "B.Cu" "In13.Cu" "In15.Cu")
		(hatch none 0.5)
		(connect_pads
			(clearance 0)
		)
		(min_thickness 0.25)
		(keepout
			(tracks not_allowed)
			(vias allowed)
			(pads allowed)
			(copperpour not_allowed)
			(footprints allowed)
		)
		(placement
			(enabled no)
			(sheetname "")
		)
		(fill yes
			(thermal_gap 0.5)
			(thermal_bridge_width 0.5)
			(island_removal_mode 0)
		)
		(polygon
			(pts
				(arc
					(start 21.215604 -234.716574)
					(mid 20.562824 -234.716574)
					(end 21.215604 -234.716574)
				)
			)
		)
	)
	(zone
		(layers "B.Cu" "In13.Cu" "In15.Cu")
		(hatch none 0.5)
		(connect_pads
			(clearance 0)
		)
		(min_thickness 0.25)
		(keepout
			(tracks not_allowed)
			(vias allowed)
			(pads allowed)
			(copperpour not_allowed)
			(footprints allowed)
		)
		(placement
			(enabled no)
			(sheetname "")
		)
		(fill yes
			(thermal_gap 0.5)
			(thermal_bridge_width 0.5)
			(island_removal_mode 0)
		)
		(polygon
			(pts
				(arc
					(start 124.184156 -247.178322)
					(mid 123.531376 -247.178322)
					(end 124.184156 -247.178322)
				)
			)
		)
	)
	(zone
		(layers "B.Cu" "In13.Cu" "In15.Cu")
		(hatch none 0.5)
		(connect_pads
			(clearance 0)
		)
		(min_thickness 0.25)
		(keepout
			(tracks not_allowed)
			(vias allowed)
			(pads allowed)
			(copperpour not_allowed)
			(footprints allowed)
		)
		(placement
			(enabled no)
			(sheetname "")
		)
		(fill yes
			(thermal_gap 0.5)
			(thermal_bridge_width 0.5)
			(island_removal_mode 0)
		)
		(polygon
			(pts
				(arc
					(start 418.58692 -403.883876)
					(mid 417.88334 -403.883876)
					(end 418.58692 -403.883876)
				)
			)
		)
	)
	(zone
		(layers "B.Cu" "In13.Cu" "In15.Cu")
		(hatch none 0.5)
		(connect_pads
			(clearance 0)
		)
		(min_thickness 0.25)
		(keepout
			(tracks not_allowed)
			(vias allowed)
			(pads allowed)
			(copperpour not_allowed)
			(footprints allowed)
		)
		(placement
			(enabled no)
			(sheetname "")
		)
		(fill yes
			(thermal_gap 0.5)
			(thermal_bridge_width 0.5)
			(island_removal_mode 0)
		)
		(polygon
			(pts
				(arc
					(start 160.328864 -403.883876)
					(mid 159.625284 -403.883876)
					(end 160.328864 -403.883876)
				)
			)
		)
	)
	(zone
		(layers "B.Cu" "In13.Cu" "In15.Cu")
		(hatch none 0.5)
		(connect_pads
			(clearance 0)
		)
		(min_thickness 0.25)
		(keepout
			(tracks not_allowed)
			(vias allowed)
			(pads allowed)
			(copperpour not_allowed)
			(footprints allowed)
		)
		(placement
			(enabled no)
			(sheetname "")
		)
		(fill yes
			(thermal_gap 0.5)
			(thermal_bridge_width 0.5)
			(island_removal_mode 0)
		)
		(polygon
			(pts
				(arc
					(start 269.155672 -295.06672)
					(mid 268.502892 -295.06672)
					(end 269.155672 -295.06672)
				)
			)
		)
	)
	(zone
		(layers "B.Cu" "In13.Cu" "In15.Cu")
		(hatch none 0.5)
		(connect_pads
			(clearance 0)
		)
		(min_thickness 0.25)
		(keepout
			(tracks not_allowed)
			(vias allowed)
			(pads allowed)
			(copperpour not_allowed)
			(footprints allowed)
		)
		(placement
			(enabled no)
			(sheetname "")
		)
		(fill yes
			(thermal_gap 0.5)
			(thermal_bridge_width 0.5)
			(island_removal_mode 0)
		)
		(polygon
			(pts
				(arc
					(start 371.294406 -255.547622)
					(mid 370.641626 -255.547622)
					(end 371.294406 -255.547622)
				)
			)
		)
	)
	(zone
		(layers "B.Cu" "In13.Cu" "In15.Cu")
		(hatch none 0.5)
		(connect_pads
			(clearance 0)
		)
		(min_thickness 0.25)
		(keepout
			(tracks not_allowed)
			(vias allowed)
			(pads allowed)
			(copperpour not_allowed)
			(footprints allowed)
		)
		(placement
			(enabled no)
			(sheetname "")
		)
		(fill yes
			(thermal_gap 0.5)
			(thermal_bridge_width 0.5)
			(island_removal_mode 0)
		)
		(polygon
			(pts
				(arc
					(start 17.115536 -239.81664)
					(mid 16.462756 -239.81664)
					(end 17.115536 -239.81664)
				)
			)
		)
	)
	(zone
		(layers "B.Cu" "In13.Cu" "In15.Cu")
		(hatch none 0.5)
		(connect_pads
			(clearance 0)
		)
		(min_thickness 0.25)
		(keepout
			(tracks not_allowed)
			(vias allowed)
			(pads allowed)
			(copperpour not_allowed)
			(footprints allowed)
		)
		(placement
			(enabled no)
			(sheetname "")
		)
		(fill yes
			(thermal_gap 0.5)
			(thermal_bridge_width 0.5)
			(island_removal_mode 0)
		)
		(polygon
			(pts
				(arc
					(start 141.949424 -403.883876)
					(mid 141.245844 -403.883876)
					(end 141.949424 -403.883876)
				)
			)
		)
	)
	(zone
		(layers "B.Cu" "In13.Cu" "In15.Cu")
		(hatch none 0.5)
		(connect_pads
			(clearance 0)
		)
		(min_thickness 0.25)
		(keepout
			(tracks not_allowed)
			(vias allowed)
			(pads allowed)
			(copperpour not_allowed)
			(footprints allowed)
		)
		(placement
			(enabled no)
			(sheetname "")
		)
		(fill yes
			(thermal_gap 0.5)
			(thermal_bridge_width 0.5)
			(island_removal_mode 0)
		)
		(polygon
			(pts
				(arc
					(start 396.15491 -427.089824)
					(mid 395.345158 -427.089824)
					(end 396.15491 -427.089824)
				)
			)
		)
	)
	(zone
		(layers "B.Cu" "In13.Cu" "In15.Cu")
		(hatch none 0.5)
		(connect_pads
			(clearance 0)
		)
		(min_thickness 0.25)
		(keepout
			(tracks not_allowed)
			(vias allowed)
			(pads allowed)
			(copperpour not_allowed)
			(footprints allowed)
		)
		(placement
			(enabled no)
			(sheetname "")
		)
		(fill yes
			(thermal_gap 0.5)
			(thermal_bridge_width 0.5)
			(island_removal_mode 0)
		)
		(polygon
			(pts
				(arc
					(start 330.183998 -410.030168)
					(mid 329.480418 -410.030168)
					(end 330.183998 -410.030168)
				)
			)
		)
	)
	(zone
		(layers "B.Cu" "In13.Cu" "In15.Cu")
		(hatch none 0.5)
		(connect_pads
			(clearance 0)
		)
		(min_thickness 0.25)
		(keepout
			(tracks not_allowed)
			(vias allowed)
			(pads allowed)
			(copperpour not_allowed)
			(footprints allowed)
		)
		(placement
			(enabled no)
			(sheetname "")
		)
		(fill yes
			(thermal_gap 0.5)
			(thermal_bridge_width 0.5)
			(island_removal_mode 0)
		)
		(polygon
			(pts
				(arc
					(start 123.714002 -231.714548)
					(mid 123.061222 -231.714548)
					(end 123.714002 -231.714548)
				)
			)
		)
	)
	(zone
		(layers "B.Cu" "In13.Cu" "In15.Cu")
		(hatch none 0.5)
		(connect_pads
			(clearance 0)
		)
		(min_thickness 0.25)
		(keepout
			(tracks not_allowed)
			(vias allowed)
			(pads allowed)
			(copperpour not_allowed)
			(footprints allowed)
		)
		(placement
			(enabled no)
			(sheetname "")
		)
		(fill yes
			(thermal_gap 0.5)
			(thermal_bridge_width 0.5)
			(island_removal_mode 0)
		)
		(polygon
			(pts
				(arc
					(start 371.764052 -274.266914)
					(mid 371.111272 -274.266914)
					(end 371.764052 -274.266914)
				)
			)
		)
	)
	(zone
		(layers "B.Cu" "In13.Cu" "In15.Cu")
		(hatch none 0.5)
		(connect_pads
			(clearance 0)
		)
		(min_thickness 0.25)
		(keepout
			(tracks not_allowed)
			(vias allowed)
			(pads allowed)
			(copperpour not_allowed)
			(footprints allowed)
		)
		(placement
			(enabled no)
			(sheetname "")
		)
		(fill yes
			(thermal_gap 0.5)
			(thermal_bridge_width 0.5)
			(island_removal_mode 0)
		)
		(polygon
			(pts
				(arc
					(start 346.749624 -248.806208)
					(mid 346.096844 -248.806208)
					(end 346.749624 -248.806208)
				)
			)
		)
	)
	(zone
		(layers "B.Cu" "In13.Cu" "In15.Cu")
		(hatch none 0.5)
		(connect_pads
			(clearance 0)
		)
		(min_thickness 0.25)
		(keepout
			(tracks not_allowed)
			(vias allowed)
			(pads allowed)
			(copperpour not_allowed)
			(footprints allowed)
		)
		(placement
			(enabled no)
			(sheetname "")
		)
		(fill yes
			(thermal_gap 0.5)
			(thermal_bridge_width 0.5)
			(island_removal_mode 0)
		)
		(polygon
			(pts
				(arc
					(start 265.055604 -267.866622)
					(mid 264.402824 -267.866622)
					(end 265.055604 -267.866622)
				)
			)
		)
	)
	(zone
		(layers "B.Cu" "In13.Cu" "In15.Cu")
		(hatch none 0.5)
		(connect_pads
			(clearance 0)
		)
		(min_thickness 0.25)
		(keepout
			(tracks not_allowed)
			(vias allowed)
			(pads allowed)
			(copperpour not_allowed)
			(footprints allowed)
		)
		(placement
			(enabled no)
			(sheetname "")
		)
		(fill yes
			(thermal_gap 0.5)
			(thermal_bridge_width 0.5)
			(island_removal_mode 0)
		)
		(polygon
			(pts
				(arc
					(start 207.397604 -237.266734)
					(mid 206.744824 -237.266734)
					(end 207.397604 -237.266734)
				)
			)
		)
	)
	(zone
		(layers "B.Cu" "In13.Cu" "In15.Cu")
		(hatch none 0.5)
		(connect_pads
			(clearance 0)
		)
		(min_thickness 0.25)
		(keepout
			(tracks not_allowed)
			(vias allowed)
			(pads allowed)
			(copperpour not_allowed)
			(footprints allowed)
		)
		(placement
			(enabled no)
			(sheetname "")
		)
		(fill yes
			(thermal_gap 0.5)
			(thermal_bridge_width 0.5)
			(island_removal_mode 0)
		)
		(polygon
			(pts
				(arc
					(start 88.153748 -403.883876)
					(mid 87.450168 -403.883876)
					(end 88.153748 -403.883876)
				)
			)
		)
	)
	(zone
		(layers "B.Cu" "In13.Cu" "In15.Cu")
		(hatch none 0.5)
		(connect_pads
			(clearance 0)
		)
		(min_thickness 0.25)
		(keepout
			(tracks not_allowed)
			(vias allowed)
			(pads allowed)
			(copperpour not_allowed)
			(footprints allowed)
		)
		(placement
			(enabled no)
			(sheetname "")
		)
		(fill yes
			(thermal_gap 0.5)
			(thermal_bridge_width 0.5)
			(island_removal_mode 0)
		)
		(polygon
			(pts
				(arc
					(start 451.237604 -303.566576)
					(mid 450.584824 -303.566576)
					(end 451.237604 -303.566576)
				)
			)
		)
	)
	(zone
		(layers "B.Cu" "In13.Cu" "In15.Cu")
		(hatch none 0.5)
		(connect_pads
			(clearance 0)
		)
		(min_thickness 0.25)
		(keepout
			(tracks not_allowed)
			(vias allowed)
			(pads allowed)
			(copperpour not_allowed)
			(footprints allowed)
		)
		(placement
			(enabled no)
			(sheetname "")
		)
		(fill yes
			(thermal_gap 0.5)
			(thermal_bridge_width 0.5)
			(island_removal_mode 0)
		)
		(polygon
			(pts
				(arc
					(start 100.799138 -257.175254)
					(mid 100.146358 -257.175254)
					(end 100.799138 -257.175254)
				)
			)
		)
	)
	(zone
		(layers "B.Cu" "In13.Cu" "In15.Cu")
		(hatch none 0.5)
		(connect_pads
			(clearance 0)
		)
		(min_thickness 0.25)
		(keepout
			(tracks not_allowed)
			(vias allowed)
			(pads allowed)
			(copperpour not_allowed)
			(footprints allowed)
		)
		(placement
			(enabled no)
			(sheetname "")
		)
		(fill yes
			(thermal_gap 0.5)
			(thermal_bridge_width 0.5)
			(island_removal_mode 0)
		)
		(polygon
			(pts
				(arc
					(start 357.197152 -276.708616)
					(mid 356.544372 -276.708616)
					(end 357.197152 -276.708616)
				)
			)
		)
	)
	(zone
		(layers "B.Cu" "In13.Cu" "In15.Cu")
		(hatch none 0.5)
		(connect_pads
			(clearance 0)
		)
		(min_thickness 0.25)
		(keepout
			(tracks not_allowed)
			(vias allowed)
			(pads allowed)
			(copperpour not_allowed)
			(footprints allowed)
		)
		(placement
			(enabled no)
			(sheetname "")
		)
		(fill yes
			(thermal_gap 0.5)
			(thermal_bridge_width 0.5)
			(island_removal_mode 0)
		)
		(polygon
			(pts
				(arc
					(start 451.237604 -218.566746)
					(mid 450.584824 -218.566746)
					(end 451.237604 -218.566746)
				)
			)
		)
	)
	(zone
		(layers "B.Cu" "In13.Cu" "In15.Cu")
		(hatch none 0.5)
		(connect_pads
			(clearance 0)
		)
		(min_thickness 0.25)
		(keepout
			(tracks not_allowed)
			(vias allowed)
			(pads allowed)
			(copperpour not_allowed)
			(footprints allowed)
		)
		(placement
			(enabled no)
			(sheetname "")
		)
		(fill yes
			(thermal_gap 0.5)
			(thermal_bridge_width 0.5)
			(island_removal_mode 0)
		)
		(polygon
			(pts
				(arc
					(start 126.533402 -226.831144)
					(mid 125.880622 -226.831144)
					(end 126.533402 -226.831144)
				)
			)
		)
	)
	(zone
		(layers "B.Cu" "In13.Cu" "In15.Cu")
		(hatch none 0.5)
		(connect_pads
			(clearance 0)
		)
		(min_thickness 0.25)
		(keepout
			(tracks not_allowed)
			(vias allowed)
			(pads allowed)
			(copperpour not_allowed)
			(footprints allowed)
		)
		(placement
			(enabled no)
			(sheetname "")
		)
		(fill yes
			(thermal_gap 0.5)
			(thermal_bridge_width 0.5)
			(island_removal_mode 0)
		)
		(polygon
			(pts
				(arc
					(start 347.329252 -266.128246)
					(mid 346.676472 -266.128246)
					(end 347.329252 -266.128246)
				)
			)
		)
	)
	(zone
		(layers "B.Cu" "In13.Cu" "In15.Cu")
		(hatch none 0.5)
		(connect_pads
			(clearance 0)
		)
		(min_thickness 0.25)
		(keepout
			(tracks not_allowed)
			(vias allowed)
			(pads allowed)
			(copperpour not_allowed)
			(footprints allowed)
		)
		(placement
			(enabled no)
			(sheetname "")
		)
		(fill yes
			(thermal_gap 0.5)
			(thermal_bridge_width 0.5)
			(island_removal_mode 0)
		)
		(polygon
			(pts
				(arc
					(start 123.354338 -270.19758)
					(mid 122.701558 -270.19758)
					(end 123.354338 -270.19758)
				)
			)
		)
	)
	(zone
		(layers "B.Cu" "In13.Cu" "In15.Cu")
		(hatch none 0.5)
		(connect_pads
			(clearance 0)
		)
		(min_thickness 0.25)
		(keepout
			(tracks not_allowed)
			(vias allowed)
			(pads allowed)
			(copperpour not_allowed)
			(footprints allowed)
		)
		(placement
			(enabled no)
			(sheetname "")
		)
		(fill yes
			(thermal_gap 0.5)
			(thermal_bridge_width 0.5)
			(island_removal_mode 0)
		)
		(polygon
			(pts
				(arc
					(start 99.389184 -256.361438)
					(mid 98.736404 -256.361438)
					(end 99.389184 -256.361438)
				)
			)
		)
	)
	(zone
		(layers "B.Cu" "In13.Cu" "In15.Cu")
		(hatch none 0.5)
		(connect_pads
			(clearance 0)
		)
		(min_thickness 0.25)
		(keepout
			(tracks not_allowed)
			(vias allowed)
			(pads allowed)
			(copperpour not_allowed)
			(footprints allowed)
		)
		(placement
			(enabled no)
			(sheetname "")
		)
		(fill yes
			(thermal_gap 0.5)
			(thermal_bridge_width 0.5)
			(island_removal_mode 0)
		)
		(polygon
			(pts
				(arc
					(start 396.15491 -428.28972)
					(mid 395.345158 -428.28972)
					(end 396.15491 -428.28972)
				)
			)
		)
	)
	(zone
		(layers "B.Cu" "In13.Cu" "In15.Cu")
		(hatch none 0.5)
		(connect_pads
			(clearance 0)
		)
		(min_thickness 0.25)
		(keepout
			(tracks not_allowed)
			(vias allowed)
			(pads allowed)
			(copperpour not_allowed)
			(footprints allowed)
		)
		(placement
			(enabled no)
			(sheetname "")
		)
		(fill yes
			(thermal_gap 0.5)
			(thermal_bridge_width 0.5)
			(island_removal_mode 0)
		)
		(polygon
			(pts
				(arc
					(start 352.498406 -275.08073)
					(mid 351.845626 -275.08073)
					(end 352.498406 -275.08073)
				)
			)
		)
	)
	(zone
		(layers "B.Cu" "In13.Cu" "In15.Cu")
		(hatch none 0.5)
		(connect_pads
			(clearance 0)
		)
		(min_thickness 0.25)
		(keepout
			(tracks not_allowed)
			(vias allowed)
			(pads allowed)
			(copperpour not_allowed)
			(footprints allowed)
		)
		(placement
			(enabled no)
			(sheetname "")
		)
		(fill yes
			(thermal_gap 0.5)
			(thermal_bridge_width 0.5)
			(island_removal_mode 0)
		)
		(polygon
			(pts
				(arc
					(start 351.558606 -276.708616)
					(mid 350.905826 -276.708616)
					(end 351.558606 -276.708616)
				)
			)
		)
	)
	(zone
		(layers "B.Cu" "In13.Cu" "In15.Cu")
		(hatch none 0.5)
		(connect_pads
			(clearance 0)
		)
		(min_thickness 0.25)
		(keepout
			(tracks not_allowed)
			(vias allowed)
			(pads allowed)
			(copperpour not_allowed)
			(footprints allowed)
		)
		(placement
			(enabled no)
			(sheetname "")
		)
		(fill yes
			(thermal_gap 0.5)
			(thermal_bridge_width 0.5)
			(island_removal_mode 0)
		)
		(polygon
			(pts
				(arc
					(start 265.055604 -280.61666)
					(mid 264.402824 -280.61666)
					(end 265.055604 -280.61666)
				)
			)
		)
	)
	(zone
		(layers "B.Cu" "In13.Cu" "In15.Cu")
		(hatch none 0.5)
		(connect_pads
			(clearance 0)
		)
		(min_thickness 0.25)
		(keepout
			(tracks not_allowed)
			(vias allowed)
			(pads allowed)
			(copperpour not_allowed)
			(footprints allowed)
		)
		(placement
			(enabled no)
			(sheetname "")
		)
		(fill yes
			(thermal_gap 0.5)
			(thermal_bridge_width 0.5)
			(island_removal_mode 0)
		)
		(polygon
			(pts
				(arc
					(start 269.155672 -233.016806)
					(mid 268.502892 -233.016806)
					(end 269.155672 -233.016806)
				)
			)
		)
	)
	(zone
		(layers "B.Cu" "In13.Cu" "In15.Cu")
		(hatch none 0.5)
		(connect_pads
			(clearance 0)
		)
		(min_thickness 0.25)
		(keepout
			(tracks not_allowed)
			(vias allowed)
			(pads allowed)
			(copperpour not_allowed)
			(footprints allowed)
		)
		(placement
			(enabled no)
			(sheetname "")
		)
		(fill yes
			(thermal_gap 0.5)
			(thermal_bridge_width 0.5)
			(island_removal_mode 0)
		)
		(polygon
			(pts
				(arc
					(start 21.215604 -227.91674)
					(mid 20.562824 -227.91674)
					(end 21.215604 -227.91674)
				)
			)
		)
	)
	(zone
		(layers "B.Cu" "In13.Cu" "In15.Cu")
		(hatch none 0.5)
		(connect_pads
			(clearance 0)
		)
		(min_thickness 0.25)
		(keepout
			(tracks not_allowed)
			(vias allowed)
			(pads allowed)
			(copperpour not_allowed)
			(footprints allowed)
		)
		(placement
			(enabled no)
			(sheetname "")
		)
		(fill yes
			(thermal_gap 0.5)
			(thermal_bridge_width 0.5)
			(island_removal_mode 0)
		)
		(polygon
			(pts
				(arc
					(start 381.82804 -403.883876)
					(mid 381.12446 -403.883876)
					(end 381.82804 -403.883876)
				)
			)
		)
	)
	(zone
		(layers "B.Cu" "In13.Cu" "In15.Cu")
		(hatch none 0.5)
		(connect_pads
			(clearance 0)
		)
		(min_thickness 0.25)
		(keepout
			(tracks not_allowed)
			(vias allowed)
			(pads allowed)
			(copperpour not_allowed)
			(footprints allowed)
		)
		(placement
			(enabled no)
			(sheetname "")
		)
		(fill yes
			(thermal_gap 0.5)
			(thermal_bridge_width 0.5)
			(island_removal_mode 0)
		)
		(polygon
			(pts
				(arc
					(start 123.244356 -232.528364)
					(mid 122.591576 -232.528364)
					(end 123.244356 -232.528364)
				)
			)
		)
	)
	(zone
		(layers "B.Cu" "In13.Cu" "In15.Cu")
		(hatch none 0.5)
		(connect_pads
			(clearance 0)
		)
		(min_thickness 0.25)
		(keepout
			(tracks not_allowed)
			(vias allowed)
			(pads allowed)
			(copperpour not_allowed)
			(footprints allowed)
		)
		(placement
			(enabled no)
			(sheetname "")
		)
		(fill yes
			(thermal_gap 0.5)
			(thermal_bridge_width 0.5)
			(island_removal_mode 0)
		)
		(polygon
			(pts
				(arc
					(start 101.268784 -257.98907)
					(mid 100.616004 -257.98907)
					(end 101.268784 -257.98907)
				)
			)
		)
	)
	(zone
		(layers "B.Cu" "In13.Cu" "In15.Cu")
		(hatch none 0.5)
		(connect_pads
			(clearance 0)
		)
		(min_thickness 0.25)
		(keepout
			(tracks not_allowed)
			(vias allowed)
			(pads allowed)
			(copperpour not_allowed)
			(footprints allowed)
		)
		(placement
			(enabled no)
			(sheetname "")
		)
		(fill yes
			(thermal_gap 0.5)
			(thermal_bridge_width 0.5)
			(island_removal_mode 0)
		)
		(polygon
			(pts
				(arc
					(start 346.27947 -234.970066)
					(mid 345.62669 -234.970066)
					(end 346.27947 -234.970066)
				)
			)
		)
	)
	(zone
		(layers "B.Cu" "In13.Cu" "In15.Cu")
		(hatch none 0.5)
		(connect_pads
			(clearance 0)
		)
		(min_thickness 0.25)
		(keepout
			(tracks not_allowed)
			(vias allowed)
			(pads allowed)
			(copperpour not_allowed)
			(footprints allowed)
		)
		(placement
			(enabled no)
			(sheetname "")
		)
		(fill yes
			(thermal_gap 0.5)
			(thermal_bridge_width 0.5)
			(island_removal_mode 0)
		)
		(polygon
			(pts
				(arc
					(start 21.215604 -195.616576)
					(mid 20.562824 -195.616576)
					(end 21.215604 -195.616576)
				)
			)
		)
	)
	(zone
		(layers "B.Cu" "In13.Cu" "In15.Cu")
		(hatch none 0.5)
		(connect_pads
			(clearance 0)
		)
		(min_thickness 0.25)
		(keepout
			(tracks not_allowed)
			(vias allowed)
			(pads allowed)
			(copperpour not_allowed)
			(footprints allowed)
		)
		(placement
			(enabled no)
			(sheetname "")
		)
		(fill yes
			(thermal_gap 0.5)
			(thermal_bridge_width 0.5)
			(island_removal_mode 0)
		)
		(polygon
			(pts
				(arc
					(start 100.689156 -248.806208)
					(mid 100.036376 -248.806208)
					(end 100.689156 -248.806208)
				)
			)
		)
	)
	(zone
		(layers "B.Cu" "In13.Cu" "In15.Cu")
		(hatch none 0.5)
		(connect_pads
			(clearance 0)
		)
		(min_thickness 0.25)
		(keepout
			(tracks not_allowed)
			(vias allowed)
			(pads allowed)
			(copperpour not_allowed)
			(footprints allowed)
		)
		(placement
			(enabled no)
			(sheetname "")
		)
		(fill yes
			(thermal_gap 0.5)
			(thermal_bridge_width 0.5)
			(island_removal_mode 0)
		)
		(polygon
			(pts
				(arc
					(start 455.337672 -227.066602)
					(mid 454.684892 -227.066602)
					(end 455.337672 -227.066602)
				)
			)
		)
	)
	(zone
		(layers "B.Cu" "In13.Cu" "In15.Cu")
		(hatch none 0.5)
		(connect_pads
			(clearance 0)
		)
		(min_thickness 0.25)
		(keepout
			(tracks not_allowed)
			(vias allowed)
			(pads allowed)
			(copperpour not_allowed)
			(footprints allowed)
		)
		(placement
			(enabled no)
			(sheetname "")
		)
		(fill yes
			(thermal_gap 0.5)
			(thermal_bridge_width 0.5)
			(island_removal_mode 0)
		)
		(polygon
			(pts
				(arc
					(start 203.297536 -252.566678)
					(mid 202.644756 -252.566678)
					(end 203.297536 -252.566678)
				)
			)
		)
	)
	(zone
		(layers "B.Cu" "In13.Cu" "In15.Cu")
		(hatch none 0.5)
		(connect_pads
			(clearance 0)
		)
		(min_thickness 0.25)
		(keepout
			(tracks not_allowed)
			(vias allowed)
			(pads allowed)
			(copperpour not_allowed)
			(footprints allowed)
		)
		(placement
			(enabled no)
			(sheetname "")
		)
		(fill yes
			(thermal_gap 0.5)
			(thermal_bridge_width 0.5)
			(island_removal_mode 0)
		)
		(polygon
			(pts
				(arc
					(start 99.389184 -261.244842)
					(mid 98.736404 -261.244842)
					(end 99.389184 -261.244842)
				)
			)
		)
	)
	(zone
		(layers "B.Cu" "In13.Cu" "In15.Cu")
		(hatch none 0.5)
		(connect_pads
			(clearance 0)
		)
		(min_thickness 0.25)
		(keepout
			(tracks not_allowed)
			(vias allowed)
			(pads allowed)
			(copperpour not_allowed)
			(footprints allowed)
		)
		(placement
			(enabled no)
			(sheetname "")
		)
		(fill yes
			(thermal_gap 0.5)
			(thermal_bridge_width 0.5)
			(island_removal_mode 0)
		)
		(polygon
			(pts
				(arc
					(start 207.397604 -296.766742)
					(mid 206.744824 -296.766742)
					(end 207.397604 -296.766742)
				)
			)
		)
	)
	(zone
		(layers "B.Cu" "In13.Cu" "In15.Cu")
		(hatch none 0.5)
		(connect_pads
			(clearance 0)
		)
		(min_thickness 0.25)
		(keepout
			(tracks not_allowed)
			(vias allowed)
			(pads allowed)
			(copperpour not_allowed)
			(footprints allowed)
		)
		(placement
			(enabled no)
			(sheetname "")
		)
		(fill yes
			(thermal_gap 0.5)
			(thermal_bridge_width 0.5)
			(island_removal_mode 0)
		)
		(polygon
			(pts
				(arc
					(start 203.297536 -294.216582)
					(mid 202.644756 -294.216582)
					(end 203.297536 -294.216582)
				)
			)
		)
	)
	(zone
		(layers "B.Cu" "In13.Cu" "In15.Cu")
		(hatch none 0.5)
		(connect_pads
			(clearance 0)
		)
		(min_thickness 0.25)
		(keepout
			(tracks not_allowed)
			(vias allowed)
			(pads allowed)
			(copperpour not_allowed)
			(footprints allowed)
		)
		(placement
			(enabled no)
			(sheetname "")
		)
		(fill yes
			(thermal_gap 0.5)
			(thermal_bridge_width 0.5)
			(island_removal_mode 0)
		)
		(polygon
			(pts
				(arc
					(start 203.297536 -221.116652)
					(mid 202.644756 -221.116652)
					(end 203.297536 -221.116652)
				)
			)
		)
	)
	(zone
		(layers "B.Cu" "In13.Cu" "In15.Cu")
		(hatch none 0.5)
		(connect_pads
			(clearance 0)
		)
		(min_thickness 0.25)
		(keepout
			(tracks not_allowed)
			(vias allowed)
			(pads allowed)
			(copperpour not_allowed)
			(footprints allowed)
		)
		(placement
			(enabled no)
			(sheetname "")
		)
		(fill yes
			(thermal_gap 0.5)
			(thermal_bridge_width 0.5)
			(island_removal_mode 0)
		)
		(polygon
			(pts
				(arc
					(start 347.329252 -271.011396)
					(mid 346.676472 -271.011396)
					(end 347.329252 -271.011396)
				)
			)
		)
	)
	(zone
		(layers "B.Cu" "In13.Cu" "In15.Cu")
		(hatch none 0.5)
		(connect_pads
			(clearance 0)
		)
		(min_thickness 0.25)
		(keepout
			(tracks not_allowed)
			(vias allowed)
			(pads allowed)
			(copperpour not_allowed)
			(footprints allowed)
		)
		(placement
			(enabled no)
			(sheetname "")
		)
		(fill yes
			(thermal_gap 0.5)
			(thermal_bridge_width 0.5)
			(island_removal_mode 0)
		)
		(polygon
			(pts
				(arc
					(start 17.115536 -294.216582)
					(mid 16.462756 -294.216582)
					(end 17.115536 -294.216582)
				)
			)
		)
	)
	(zone
		(layers "B.Cu" "In13.Cu" "In15.Cu")
		(hatch none 0.5)
		(connect_pads
			(clearance 0)
		)
		(min_thickness 0.25)
		(keepout
			(tracks not_allowed)
			(vias allowed)
			(pads allowed)
			(copperpour not_allowed)
			(footprints allowed)
		)
		(placement
			(enabled no)
			(sheetname "")
		)
		(fill yes
			(thermal_gap 0.5)
			(thermal_bridge_width 0.5)
			(island_removal_mode 0)
		)
		(polygon
			(pts
				(arc
					(start 455.337672 -276.366732)
					(mid 454.684892 -276.366732)
					(end 455.337672 -276.366732)
				)
			)
		)
	)
	(zone
		(layers "B.Cu" "In13.Cu" "In15.Cu")
		(hatch none 0.5)
		(connect_pads
			(clearance 0)
		)
		(min_thickness 0.25)
		(keepout
			(tracks not_allowed)
			(vias allowed)
			(pads allowed)
			(copperpour not_allowed)
			(footprints allowed)
		)
		(placement
			(enabled no)
			(sheetname "")
		)
		(fill yes
			(thermal_gap 0.5)
			(thermal_bridge_width 0.5)
			(island_removal_mode 0)
		)
		(polygon
			(pts
				(arc
					(start 373.174006 -260.430772)
					(mid 372.521226 -260.430772)
					(end 373.174006 -260.430772)
				)
			)
		)
	)
	(zone
		(layers "B.Cu" "In13.Cu" "In15.Cu")
		(hatch none 0.5)
		(connect_pads
			(clearance 0)
		)
		(min_thickness 0.25)
		(keepout
			(tracks not_allowed)
			(vias allowed)
			(pads allowed)
			(copperpour not_allowed)
			(footprints allowed)
		)
		(placement
			(enabled no)
			(sheetname "")
		)
		(fill yes
			(thermal_gap 0.5)
			(thermal_bridge_width 0.5)
			(island_removal_mode 0)
		)
		(polygon
			(pts
				(arc
					(start 203.297536 -275.516594)
					(mid 202.644756 -275.516594)
					(end 203.297536 -275.516594)
				)
			)
		)
	)
	(zone
		(layers "B.Cu" "In13.Cu" "In15.Cu")
		(hatch none 0.5)
		(connect_pads
			(clearance 0)
		)
		(min_thickness 0.25)
		(keepout
			(tracks not_allowed)
			(vias allowed)
			(pads allowed)
			(copperpour not_allowed)
			(footprints allowed)
		)
		(placement
			(enabled no)
			(sheetname "")
		)
		(fill yes
			(thermal_gap 0.5)
			(thermal_bridge_width 0.5)
			(island_removal_mode 0)
		)
		(polygon
			(pts
				(arc
					(start 17.115536 -262.76681)
					(mid 16.462756 -262.76681)
					(end 17.115536 -262.76681)
				)
			)
		)
	)
	(zone
		(layers "B.Cu" "In13.Cu" "In15.Cu")
		(hatch none 0.5)
		(connect_pads
			(clearance 0)
		)
		(min_thickness 0.25)
		(keepout
			(tracks not_allowed)
			(vias allowed)
			(pads allowed)
			(copperpour not_allowed)
			(footprints allowed)
		)
		(placement
			(enabled no)
			(sheetname "")
		)
		(fill yes
			(thermal_gap 0.5)
			(thermal_bridge_width 0.5)
			(island_removal_mode 0)
		)
		(polygon
			(pts
				(arc
					(start 329.054968 -430.689766)
					(mid 328.245216 -430.689766)
					(end 329.054968 -430.689766)
				)
			)
		)
	)
	(zone
		(layers "B.Cu" "In13.Cu" "In15.Cu")
		(hatch none 0.5)
		(connect_pads
			(clearance 0)
		)
		(min_thickness 0.25)
		(keepout
			(tracks not_allowed)
			(vias allowed)
			(pads allowed)
			(copperpour not_allowed)
			(footprints allowed)
		)
		(placement
			(enabled no)
			(sheetname "")
		)
		(fill yes
			(thermal_gap 0.5)
			(thermal_bridge_width 0.5)
			(island_removal_mode 0)
		)
		(polygon
			(pts
				(arc
					(start 390.15416 -403.883876)
					(mid 389.45058 -403.883876)
					(end 390.15416 -403.883876)
				)
			)
		)
	)
	(zone
		(layers "B.Cu" "In13.Cu" "In15.Cu")
		(hatch none 0.5)
		(connect_pads
			(clearance 0)
		)
		(min_thickness 0.25)
		(keepout
			(tracks not_allowed)
			(vias allowed)
			(pads allowed)
			(copperpour not_allowed)
			(footprints allowed)
		)
		(placement
			(enabled no)
			(sheetname "")
		)
		(fill yes
			(thermal_gap 0.5)
			(thermal_bridge_width 0.5)
			(island_removal_mode 0)
		)
		(polygon
			(pts
				(arc
					(start 372.63832 -403.883876)
					(mid 371.93474 -403.883876)
					(end 372.63832 -403.883876)
				)
			)
		)
	)
	(zone
		(layers "B.Cu" "In13.Cu" "In15.Cu")
		(hatch none 0.5)
		(connect_pads
			(clearance 0)
		)
		(min_thickness 0.25)
		(keepout
			(tracks not_allowed)
			(vias allowed)
			(pads allowed)
			(copperpour not_allowed)
			(footprints allowed)
		)
		(placement
			(enabled no)
			(sheetname "")
		)
		(fill yes
			(thermal_gap 0.5)
			(thermal_bridge_width 0.5)
			(island_removal_mode 0)
		)
		(polygon
			(pts
				(arc
					(start 424.996102 -6.713474)
					(mid 424.292522 -6.713474)
					(end 424.996102 -6.713474)
				)
			)
		)
	)
	(zone
		(layers "B.Cu" "In13.Cu" "In15.Cu")
		(hatch none 0.5)
		(connect_pads
			(clearance 0)
		)
		(min_thickness 0.25)
		(keepout
			(tracks not_allowed)
			(vias allowed)
			(pads allowed)
			(copperpour not_allowed)
			(footprints allowed)
		)
		(placement
			(enabled no)
			(sheetname "")
		)
		(fill yes
			(thermal_gap 0.5)
			(thermal_bridge_width 0.5)
			(island_removal_mode 0)
		)
		(polygon
			(pts
				(arc
					(start 451.237604 -237.266734)
					(mid 450.584824 -237.266734)
					(end 451.237604 -237.266734)
				)
			)
		)
	)
	(zone
		(layers "B.Cu" "In13.Cu" "In15.Cu")
		(hatch none 0.5)
		(connect_pads
			(clearance 0)
		)
		(min_thickness 0.25)
		(keepout
			(tracks not_allowed)
			(vias allowed)
			(pads allowed)
			(copperpour not_allowed)
			(footprints allowed)
		)
		(placement
			(enabled no)
			(sheetname "")
		)
		(fill yes
			(thermal_gap 0.5)
			(thermal_bridge_width 0.5)
			(island_removal_mode 0)
		)
		(polygon
			(pts
				(arc
					(start 203.297536 -274.66671)
					(mid 202.644756 -274.66671)
					(end 203.297536 -274.66671)
				)
			)
		)
	)
	(zone
		(layers "B.Cu" "In13.Cu" "In15.Cu")
		(hatch none 0.5)
		(connect_pads
			(clearance 0)
		)
		(min_thickness 0.25)
		(keepout
			(tracks not_allowed)
			(vias allowed)
			(pads allowed)
			(copperpour not_allowed)
			(footprints allowed)
		)
		(placement
			(enabled no)
			(sheetname "")
		)
		(fill yes
			(thermal_gap 0.5)
			(thermal_bridge_width 0.5)
			(island_removal_mode 0)
		)
		(polygon
			(pts
				(arc
					(start 29.23667 -4.962652)
					(mid 28.53309 -4.962652)
					(end 29.23667 -4.962652)
				)
			)
		)
	)
	(zone
		(layers "B.Cu" "In13.Cu" "In15.Cu")
		(hatch none 0.5)
		(connect_pads
			(clearance 0)
		)
		(min_thickness 0.25)
		(keepout
			(tracks not_allowed)
			(vias allowed)
			(pads allowed)
			(copperpour not_allowed)
			(footprints allowed)
		)
		(placement
			(enabled no)
			(sheetname "")
		)
		(fill yes
			(thermal_gap 0.5)
			(thermal_bridge_width 0.5)
			(island_removal_mode 0)
		)
		(polygon
			(pts
				(arc
					(start 347.329252 -277.522432)
					(mid 346.676472 -277.522432)
					(end 347.329252 -277.522432)
				)
			)
		)
	)
	(zone
		(layers "B.Cu" "In13.Cu" "In15.Cu")
		(hatch none 0.5)
		(connect_pads
			(clearance 0)
		)
		(min_thickness 0.25)
		(keepout
			(tracks not_allowed)
			(vias allowed)
			(pads allowed)
			(copperpour not_allowed)
			(footprints allowed)
		)
		(placement
			(enabled no)
			(sheetname "")
		)
		(fill yes
			(thermal_gap 0.5)
			(thermal_bridge_width 0.5)
			(island_removal_mode 0)
		)
		(polygon
			(pts
				(arc
					(start 406.33396 -403.883876)
					(mid 405.63038 -403.883876)
					(end 406.33396 -403.883876)
				)
			)
		)
	)
	(zone
		(layers "B.Cu" "In13.Cu" "In15.Cu")
		(hatch none 0.5)
		(connect_pads
			(clearance 0)
		)
		(min_thickness 0.25)
		(keepout
			(tracks not_allowed)
			(vias allowed)
			(pads allowed)
			(copperpour not_allowed)
			(footprints allowed)
		)
		(placement
			(enabled no)
			(sheetname "")
		)
		(fill yes
			(thermal_gap 0.5)
			(thermal_bridge_width 0.5)
			(island_removal_mode 0)
		)
		(polygon
			(pts
				(arc
					(start 132.15493 -428.28972)
					(mid 131.345178 -428.28972)
					(end 132.15493 -428.28972)
				)
			)
		)
	)
	(zone
		(layers "B.Cu" "In13.Cu" "In15.Cu")
		(hatch none 0.5)
		(connect_pads
			(clearance 0)
		)
		(min_thickness 0.25)
		(keepout
			(tracks not_allowed)
			(vias allowed)
			(pads allowed)
			(copperpour not_allowed)
			(footprints allowed)
		)
		(placement
			(enabled no)
			(sheetname "")
		)
		(fill yes
			(thermal_gap 0.5)
			(thermal_bridge_width 0.5)
			(island_removal_mode 0)
		)
		(polygon
			(pts
				(arc
					(start 257.511804 -267.866622)
					(mid 256.859024 -267.866622)
					(end 257.511804 -267.866622)
				)
			)
		)
	)
	(zone
		(layers "B.Cu" "In13.Cu" "In15.Cu")
		(hatch none 0.5)
		(connect_pads
			(clearance 0)
		)
		(min_thickness 0.25)
		(keepout
			(tracks not_allowed)
			(vias allowed)
			(pads allowed)
			(copperpour not_allowed)
			(footprints allowed)
		)
		(placement
			(enabled no)
			(sheetname "")
		)
		(fill yes
			(thermal_gap 0.5)
			(thermal_bridge_width 0.5)
			(island_removal_mode 0)
		)
		(polygon
			(pts
				(arc
					(start 19.368516 -6.724396)
					(mid 18.664936 -6.724396)
					(end 19.368516 -6.724396)
				)
			)
		)
	)
	(zone
		(layers "B.Cu" "In13.Cu" "In15.Cu")
		(hatch none 0.5)
		(connect_pads
			(clearance 0)
		)
		(min_thickness 0.25)
		(keepout
			(tracks not_allowed)
			(vias allowed)
			(pads allowed)
			(copperpour not_allowed)
			(footprints allowed)
		)
		(placement
			(enabled no)
			(sheetname "")
		)
		(fill yes
			(thermal_gap 0.5)
			(thermal_bridge_width 0.5)
			(island_removal_mode 0)
		)
		(polygon
			(pts
				(arc
					(start 21.215604 -236.416596)
					(mid 20.562824 -236.416596)
					(end 21.215604 -236.416596)
				)
			)
		)
	)
	(zone
		(layers "B.Cu" "In13.Cu" "In15.Cu")
		(hatch none 0.5)
		(connect_pads
			(clearance 0)
		)
		(min_thickness 0.25)
		(keepout
			(tracks not_allowed)
			(vias allowed)
			(pads allowed)
			(copperpour not_allowed)
			(footprints allowed)
		)
		(placement
			(enabled no)
			(sheetname "")
		)
		(fill yes
			(thermal_gap 0.5)
			(thermal_bridge_width 0.5)
			(island_removal_mode 0)
		)
		(polygon
			(pts
				(arc
					(start 348.629224 -229.272846)
					(mid 347.976444 -229.272846)
					(end 348.629224 -229.272846)
				)
			)
		)
	)
	(zone
		(layers "B.Cu" "In13.Cu" "In15.Cu")
		(hatch none 0.5)
		(connect_pads
			(clearance 0)
		)
		(min_thickness 0.25)
		(keepout
			(tracks not_allowed)
			(vias allowed)
			(pads allowed)
			(copperpour not_allowed)
			(footprints allowed)
		)
		(placement
			(enabled no)
			(sheetname "")
		)
		(fill yes
			(thermal_gap 0.5)
			(thermal_bridge_width 0.5)
			(island_removal_mode 0)
		)
		(polygon
			(pts
				(arc
					(start 265.055604 -284.866588)
					(mid 264.402824 -284.866588)
					(end 265.055604 -284.866588)
				)
			)
		)
	)
	(zone
		(layers "B.Cu" "In13.Cu" "In15.Cu")
		(hatch none 0.5)
		(connect_pads
			(clearance 0)
		)
		(min_thickness 0.25)
		(keepout
			(tracks not_allowed)
			(vias allowed)
			(pads allowed)
			(copperpour not_allowed)
			(footprints allowed)
		)
		(placement
			(enabled no)
			(sheetname "")
		)
		(fill yes
			(thermal_gap 0.5)
			(thermal_bridge_width 0.5)
			(island_removal_mode 0)
		)
		(polygon
			(pts
				(arc
					(start 373.643652 -266.128246)
					(mid 372.990872 -266.128246)
					(end 373.643652 -266.128246)
				)
			)
		)
	)
	(zone
		(layers "B.Cu" "In13.Cu" "In15.Cu")
		(hatch none 0.5)
		(connect_pads
			(clearance 0)
		)
		(min_thickness 0.25)
		(keepout
			(tracks not_allowed)
			(vias allowed)
			(pads allowed)
			(copperpour not_allowed)
			(footprints allowed)
		)
		(placement
			(enabled no)
			(sheetname "")
		)
		(fill yes
			(thermal_gap 0.5)
			(thermal_bridge_width 0.5)
			(island_removal_mode 0)
		)
		(polygon
			(pts
				(arc
					(start 399.280634 -4.95173)
					(mid 398.577054 -4.95173)
					(end 399.280634 -4.95173)
				)
			)
		)
	)
	(zone
		(layers "B.Cu" "In13.Cu" "In15.Cu")
		(hatch none 0.5)
		(connect_pads
			(clearance 0)
		)
		(min_thickness 0.25)
		(keepout
			(tracks not_allowed)
			(vias allowed)
			(pads allowed)
			(copperpour not_allowed)
			(footprints allowed)
		)
		(placement
			(enabled no)
			(sheetname "")
		)
		(fill yes
			(thermal_gap 0.5)
			(thermal_bridge_width 0.5)
			(island_removal_mode 0)
		)
		(polygon
			(pts
				(arc
					(start 100.799138 -271.825212)
					(mid 100.146358 -271.825212)
					(end 100.799138 -271.825212)
				)
			)
		)
	)
	(zone
		(layers "B.Cu" "In13.Cu" "In15.Cu")
		(hatch none 0.5)
		(connect_pads
			(clearance 0)
		)
		(min_thickness 0.25)
		(keepout
			(tracks not_allowed)
			(vias allowed)
			(pads allowed)
			(copperpour not_allowed)
			(footprints allowed)
		)
		(placement
			(enabled no)
			(sheetname "")
		)
		(fill yes
			(thermal_gap 0.5)
			(thermal_bridge_width 0.5)
			(island_removal_mode 0)
		)
		(polygon
			(pts
				(arc
					(start 455.337672 -195.616576)
					(mid 454.684892 -195.616576)
					(end 455.337672 -195.616576)
				)
			)
		)
	)
	(zone
		(layers "B.Cu" "In13.Cu" "In15.Cu")
		(hatch none 0.5)
		(connect_pads
			(clearance 0)
		)
		(min_thickness 0.25)
		(keepout
			(tracks not_allowed)
			(vias allowed)
			(pads allowed)
			(copperpour not_allowed)
			(footprints allowed)
		)
		(placement
			(enabled no)
			(sheetname "")
		)
		(fill yes
			(thermal_gap 0.5)
			(thermal_bridge_width 0.5)
			(island_removal_mode 0)
		)
		(polygon
			(pts
				(arc
					(start 373.174006 -263.686544)
					(mid 372.521226 -263.686544)
					(end 373.174006 -263.686544)
				)
			)
		)
	)
	(zone
		(layers "B.Cu" "In13.Cu" "In15.Cu")
		(hatch none 0.5)
		(connect_pads
			(clearance 0)
		)
		(min_thickness 0.25)
		(keepout
			(tracks not_allowed)
			(vias allowed)
			(pads allowed)
			(copperpour not_allowed)
			(footprints allowed)
		)
		(placement
			(enabled no)
			(sheetname "")
		)
		(fill yes
			(thermal_gap 0.5)
			(thermal_bridge_width 0.5)
			(island_removal_mode 0)
		)
		(polygon
			(pts
				(arc
					(start 105.498138 -279.964134)
					(mid 104.845358 -279.964134)
					(end 105.498138 -279.964134)
				)
			)
		)
	)
	(zone
		(layers "B.Cu" "In13.Cu" "In15.Cu")
		(hatch none 0.5)
		(connect_pads
			(clearance 0)
		)
		(min_thickness 0.25)
		(keepout
			(tracks not_allowed)
			(vias allowed)
			(pads allowed)
			(copperpour not_allowed)
			(footprints allowed)
		)
		(placement
			(enabled no)
			(sheetname "")
		)
		(fill yes
			(thermal_gap 0.5)
			(thermal_bridge_width 0.5)
			(island_removal_mode 0)
		)
		(polygon
			(pts
				(arc
					(start 356.727506 -275.8948)
					(mid 356.074726 -275.8948)
					(end 356.727506 -275.8948)
				)
			)
		)
	)
	(zone
		(layers "B.Cu" "In13.Cu" "In15.Cu")
		(hatch none 0.5)
		(connect_pads
			(clearance 0)
		)
		(min_thickness 0.25)
		(keepout
			(tracks not_allowed)
			(vias allowed)
			(pads allowed)
			(copperpour not_allowed)
			(footprints allowed)
		)
		(placement
			(enabled no)
			(sheetname "")
		)
		(fill yes
			(thermal_gap 0.5)
			(thermal_bridge_width 0.5)
			(island_removal_mode 0)
		)
		(polygon
			(pts
				(arc
					(start 133.623304 -403.883876)
					(mid 132.919724 -403.883876)
					(end 133.623304 -403.883876)
				)
			)
		)
	)
	(zone
		(layers "B.Cu" "In13.Cu" "In15.Cu")
		(hatch none 0.5)
		(connect_pads
			(clearance 0)
		)
		(min_thickness 0.25)
		(keepout
			(tracks not_allowed)
			(vias allowed)
			(pads allowed)
			(copperpour not_allowed)
			(footprints allowed)
		)
		(placement
			(enabled no)
			(sheetname "")
		)
		(fill yes
			(thermal_gap 0.5)
			(thermal_bridge_width 0.5)
			(island_removal_mode 0)
		)
		(polygon
			(pts
				(arc
					(start 110.557056 -221.94774)
					(mid 109.904276 -221.94774)
					(end 110.557056 -221.94774)
				)
			)
		)
	)
	(zone
		(layers "B.Cu" "In13.Cu" "In15.Cu")
		(hatch none 0.5)
		(connect_pads
			(clearance 0)
		)
		(min_thickness 0.25)
		(keepout
			(tracks not_allowed)
			(vias allowed)
			(pads allowed)
			(copperpour not_allowed)
			(footprints allowed)
		)
		(placement
			(enabled no)
			(sheetname "")
		)
		(fill yes
			(thermal_gap 0.5)
			(thermal_bridge_width 0.5)
			(island_removal_mode 0)
		)
		(polygon
			(pts
				(arc
					(start 344.510106 -280.778204)
					(mid 343.857326 -280.778204)
					(end 344.510106 -280.778204)
				)
			)
		)
	)
	(zone
		(layers "B.Cu" "In13.Cu" "In15.Cu")
		(hatch none 0.5)
		(connect_pads
			(clearance 0)
		)
		(min_thickness 0.25)
		(keepout
			(tracks not_allowed)
			(vias allowed)
			(pads allowed)
			(copperpour not_allowed)
			(footprints allowed)
		)
		(placement
			(enabled no)
			(sheetname "")
		)
		(fill yes
			(thermal_gap 0.5)
			(thermal_bridge_width 0.5)
			(island_removal_mode 0)
		)
		(polygon
			(pts
				(arc
					(start 125.233938 -270.19758)
					(mid 124.581158 -270.19758)
					(end 125.233938 -270.19758)
				)
			)
		)
	)
	(zone
		(layers "B.Cu" "In13.Cu" "In15.Cu")
		(hatch none 0.5)
		(connect_pads
			(clearance 0)
		)
		(min_thickness 0.25)
		(keepout
			(tracks not_allowed)
			(vias allowed)
			(pads allowed)
			(copperpour not_allowed)
			(footprints allowed)
		)
		(placement
			(enabled no)
			(sheetname "")
		)
		(fill yes
			(thermal_gap 0.5)
			(thermal_bridge_width 0.5)
			(island_removal_mode 0)
		)
		(polygon
			(pts
				(arc
					(start 269.155672 -227.91674)
					(mid 268.502892 -227.91674)
					(end 269.155672 -227.91674)
				)
			)
		)
	)
	(zone
		(layers "B.Cu" "In13.Cu" "In15.Cu")
		(hatch none 0.5)
		(connect_pads
			(clearance 0)
		)
		(min_thickness 0.25)
		(keepout
			(tracks not_allowed)
			(vias allowed)
			(pads allowed)
			(copperpour not_allowed)
			(footprints allowed)
		)
		(placement
			(enabled no)
			(sheetname "")
		)
		(fill yes
			(thermal_gap 0.5)
			(thermal_bridge_width 0.5)
			(island_removal_mode 0)
		)
		(polygon
			(pts
				(arc
					(start 455.337672 -223.666558)
					(mid 454.684892 -223.666558)
					(end 455.337672 -223.666558)
				)
			)
		)
	)
	(zone
		(layers "B.Cu" "In13.Cu" "In15.Cu")
		(hatch none 0.5)
		(connect_pads
			(clearance 0)
		)
		(min_thickness 0.25)
		(keepout
			(tracks not_allowed)
			(vias allowed)
			(pads allowed)
			(copperpour not_allowed)
			(footprints allowed)
		)
		(placement
			(enabled no)
			(sheetname "")
		)
		(fill yes
			(thermal_gap 0.5)
			(thermal_bridge_width 0.5)
			(island_removal_mode 0)
		)
		(polygon
			(pts
				(arc
					(start 451.237604 -275.516594)
					(mid 450.584824 -275.516594)
					(end 451.237604 -275.516594)
				)
			)
		)
	)
	(zone
		(layers "B.Cu" "In13.Cu" "In15.Cu")
		(hatch none 0.5)
		(connect_pads
			(clearance 0)
		)
		(min_thickness 0.25)
		(keepout
			(tracks not_allowed)
			(vias allowed)
			(pads allowed)
			(copperpour not_allowed)
			(footprints allowed)
		)
		(placement
			(enabled no)
			(sheetname "")
		)
		(fill yes
			(thermal_gap 0.5)
			(thermal_bridge_width 0.5)
			(island_removal_mode 0)
		)
		(polygon
			(pts
				(arc
					(start 269.155672 -260.21665)
					(mid 268.502892 -260.21665)
					(end 269.155672 -260.21665)
				)
			)
		)
	)
	(zone
		(layers "B.Cu" "In13.Cu" "In15.Cu")
		(hatch none 0.5)
		(connect_pads
			(clearance 0)
		)
		(min_thickness 0.25)
		(keepout
			(tracks not_allowed)
			(vias allowed)
			(pads allowed)
			(copperpour not_allowed)
			(footprints allowed)
		)
		(placement
			(enabled no)
			(sheetname "")
		)
		(fill yes
			(thermal_gap 0.5)
			(thermal_bridge_width 0.5)
			(island_removal_mode 0)
		)
		(polygon
			(pts
				(arc
					(start 347.21927 -234.970066)
					(mid 346.56649 -234.970066)
					(end 347.21927 -234.970066)
				)
			)
		)
	)
	(zone
		(layers "B.Cu" "In13.Cu" "In15.Cu")
		(hatch none 0.5)
		(connect_pads
			(clearance 0)
		)
		(min_thickness 0.25)
		(keepout
			(tracks not_allowed)
			(vias allowed)
			(pads allowed)
			(copperpour not_allowed)
			(footprints allowed)
		)
		(placement
			(enabled no)
			(sheetname "")
		)
		(fill yes
			(thermal_gap 0.5)
			(thermal_bridge_width 0.5)
			(island_removal_mode 0)
		)
		(polygon
			(pts
				(arc
					(start 17.115536 -233.86669)
					(mid 16.462756 -233.86669)
					(end 17.115536 -233.86669)
				)
			)
		)
	)
	(zone
		(layers "B.Cu" "In13.Cu" "In15.Cu")
		(hatch none 0.5)
		(connect_pads
			(clearance 0)
		)
		(min_thickness 0.25)
		(keepout
			(tracks not_allowed)
			(vias allowed)
			(pads allowed)
			(copperpour not_allowed)
			(footprints allowed)
		)
		(placement
			(enabled no)
			(sheetname "")
		)
		(fill yes
			(thermal_gap 0.5)
			(thermal_bridge_width 0.5)
			(island_removal_mode 0)
		)
		(polygon
			(pts
				(arc
					(start 126.063756 -232.528364)
					(mid 125.410976 -232.528364)
					(end 126.063756 -232.528364)
				)
			)
		)
	)
	(zone
		(layers "B.Cu" "In13.Cu" "In15.Cu")
		(hatch none 0.5)
		(connect_pads
			(clearance 0)
		)
		(min_thickness 0.25)
		(keepout
			(tracks not_allowed)
			(vias allowed)
			(pads allowed)
			(copperpour not_allowed)
			(footprints allowed)
		)
		(placement
			(enabled no)
			(sheetname "")
		)
		(fill yes
			(thermal_gap 0.5)
			(thermal_bridge_width 0.5)
			(island_removal_mode 0)
		)
		(polygon
			(pts
				(arc
					(start 98.919538 -262.058658)
					(mid 98.266758 -262.058658)
					(end 98.919538 -262.058658)
				)
			)
		)
	)
	(zone
		(layers "B.Cu" "In13.Cu" "In15.Cu")
		(hatch none 0.5)
		(connect_pads
			(clearance 0)
		)
		(min_thickness 0.25)
		(keepout
			(tracks not_allowed)
			(vias allowed)
			(pads allowed)
			(copperpour not_allowed)
			(footprints allowed)
		)
		(placement
			(enabled no)
			(sheetname "")
		)
		(fill yes
			(thermal_gap 0.5)
			(thermal_bridge_width 0.5)
			(island_removal_mode 0)
		)
		(polygon
			(pts
				(arc
					(start 203.297536 -306.96662)
					(mid 202.644756 -306.96662)
					(end 203.297536 -306.96662)
				)
			)
		)
	)
	(zone
		(layers "B.Cu" "In13.Cu" "In15.Cu")
		(hatch none 0.5)
		(connect_pads
			(clearance 0)
		)
		(min_thickness 0.25)
		(keepout
			(tracks not_allowed)
			(vias allowed)
			(pads allowed)
			(copperpour not_allowed)
			(footprints allowed)
		)
		(placement
			(enabled no)
			(sheetname "")
		)
		(fill yes
			(thermal_gap 0.5)
			(thermal_bridge_width 0.5)
			(island_removal_mode 0)
		)
		(polygon
			(pts
				(arc
					(start 99.279202 -246.364506)
					(mid 98.626422 -246.364506)
					(end 99.279202 -246.364506)
				)
			)
		)
	)
	(zone
		(layers "B.Cu" "In13.Cu" "In15.Cu")
		(hatch none 0.5)
		(connect_pads
			(clearance 0)
		)
		(min_thickness 0.25)
		(keepout
			(tracks not_allowed)
			(vias allowed)
			(pads allowed)
			(copperpour not_allowed)
			(footprints allowed)
		)
		(placement
			(enabled no)
			(sheetname "")
		)
		(fill yes
			(thermal_gap 0.5)
			(thermal_bridge_width 0.5)
			(island_removal_mode 0)
		)
		(polygon
			(pts
				(arc
					(start 100.689156 -235.783882)
					(mid 100.036376 -235.783882)
					(end 100.689156 -235.783882)
				)
			)
		)
	)
	(zone
		(layers "B.Cu" "In13.Cu" "In15.Cu")
		(hatch none 0.5)
		(connect_pads
			(clearance 0)
		)
		(min_thickness 0.25)
		(keepout
			(tracks not_allowed)
			(vias allowed)
			(pads allowed)
			(copperpour not_allowed)
			(footprints allowed)
		)
		(placement
			(enabled no)
			(sheetname "")
		)
		(fill yes
			(thermal_gap 0.5)
			(thermal_bridge_width 0.5)
			(island_removal_mode 0)
		)
		(polygon
			(pts
				(arc
					(start 17.115536 -305.266598)
					(mid 16.462756 -305.266598)
					(end 17.115536 -305.266598)
				)
			)
		)
	)
	(zone
		(layers "B.Cu" "In13.Cu" "In15.Cu")
		(hatch none 0.5)
		(connect_pads
			(clearance 0)
		)
		(min_thickness 0.25)
		(keepout
			(tracks not_allowed)
			(vias allowed)
			(pads allowed)
			(copperpour not_allowed)
			(footprints allowed)
		)
		(placement
			(enabled no)
			(sheetname "")
		)
		(fill yes
			(thermal_gap 0.5)
			(thermal_bridge_width 0.5)
			(island_removal_mode 0)
		)
		(polygon
			(pts
				(arc
					(start 125.703584 -271.011396)
					(mid 125.050804 -271.011396)
					(end 125.703584 -271.011396)
				)
			)
		)
	)
	(zone
		(layers "B.Cu" "In13.Cu" "In15.Cu")
		(hatch none 0.5)
		(connect_pads
			(clearance 0)
		)
		(min_thickness 0.25)
		(keepout
			(tracks not_allowed)
			(vias allowed)
			(pads allowed)
			(copperpour not_allowed)
			(footprints allowed)
		)
		(placement
			(enabled no)
			(sheetname "")
		)
		(fill yes
			(thermal_gap 0.5)
			(thermal_bridge_width 0.5)
			(island_removal_mode 0)
		)
		(polygon
			(pts
				(arc
					(start 92.340684 -281.59202)
					(mid 91.687904 -281.59202)
					(end 92.340684 -281.59202)
				)
			)
		)
	)
	(zone
		(layers "B.Cu" "In13.Cu" "In15.Cu")
		(hatch none 0.5)
		(connect_pads
			(clearance 0)
		)
		(min_thickness 0.25)
		(keepout
			(tracks not_allowed)
			(vias allowed)
			(pads allowed)
			(copperpour not_allowed)
			(footprints allowed)
		)
		(placement
			(enabled no)
			(sheetname "")
		)
		(fill yes
			(thermal_gap 0.5)
			(thermal_bridge_width 0.5)
			(island_removal_mode 0)
		)
		(polygon
			(pts
				(arc
					(start 207.397604 -283.166566)
					(mid 206.744824 -283.166566)
					(end 207.397604 -283.166566)
				)
			)
		)
	)
	(zone
		(layers "B.Cu" "In13.Cu" "In15.Cu")
		(hatch none 0.5)
		(connect_pads
			(clearance 0)
		)
		(min_thickness 0.25)
		(keepout
			(tracks not_allowed)
			(vias allowed)
			(pads allowed)
			(copperpour not_allowed)
			(footprints allowed)
		)
		(placement
			(enabled no)
			(sheetname "")
		)
		(fill yes
			(thermal_gap 0.5)
			(thermal_bridge_width 0.5)
			(island_removal_mode 0)
		)
		(polygon
			(pts
				(arc
					(start 54.088538 -6.724396)
					(mid 53.384958 -6.724396)
					(end 54.088538 -6.724396)
				)
			)
		)
	)
	(zone
		(layers "B.Cu" "In13.Cu" "In15.Cu")
		(hatch none 0.5)
		(connect_pads
			(clearance 0)
		)
		(min_thickness 0.25)
		(keepout
			(tracks not_allowed)
			(vias allowed)
			(pads allowed)
			(copperpour not_allowed)
			(footprints allowed)
		)
		(placement
			(enabled no)
			(sheetname "")
		)
		(fill yes
			(thermal_gap 0.5)
			(thermal_bridge_width 0.5)
			(island_removal_mode 0)
		)
		(polygon
			(pts
				(arc
					(start 21.215604 -302.716692)
					(mid 20.562824 -302.716692)
					(end 21.215604 -302.716692)
				)
			)
		)
	)
	(zone
		(layers "B.Cu" "In13.Cu" "In15.Cu")
		(hatch none 0.5)
		(connect_pads
			(clearance 0)
		)
		(min_thickness 0.25)
		(keepout
			(tracks not_allowed)
			(vias allowed)
			(pads allowed)
			(copperpour not_allowed)
			(footprints allowed)
		)
		(placement
			(enabled no)
			(sheetname "")
		)
		(fill yes
			(thermal_gap 0.5)
			(thermal_bridge_width 0.5)
			(island_removal_mode 0)
		)
		(polygon
			(pts
				(arc
					(start 372.124224 -227.64496)
					(mid 371.471444 -227.64496)
					(end 372.124224 -227.64496)
				)
			)
		)
	)
	(zone
		(layers "B.Cu" "In13.Cu" "In15.Cu")
		(hatch none 0.5)
		(connect_pads
			(clearance 0)
		)
		(min_thickness 0.25)
		(keepout
			(tracks not_allowed)
			(vias allowed)
			(pads allowed)
			(copperpour not_allowed)
			(footprints allowed)
		)
		(placement
			(enabled no)
			(sheetname "")
		)
		(fill yes
			(thermal_gap 0.5)
			(thermal_bridge_width 0.5)
			(island_removal_mode 0)
		)
		(polygon
			(pts
				(arc
					(start 269.155672 -296.766742)
					(mid 268.502892 -296.766742)
					(end 269.155672 -296.766742)
				)
			)
		)
	)
	(zone
		(layers "B.Cu" "In13.Cu" "In15.Cu")
		(hatch none 0.5)
		(connect_pads
			(clearance 0)
		)
		(min_thickness 0.25)
		(keepout
			(tracks not_allowed)
			(vias allowed)
			(pads allowed)
			(copperpour not_allowed)
			(footprints allowed)
		)
		(placement
			(enabled no)
			(sheetname "")
		)
		(fill yes
			(thermal_gap 0.5)
			(thermal_bridge_width 0.5)
			(island_removal_mode 0)
		)
		(polygon
			(pts
				(arc
					(start 348.739206 -266.941808)
					(mid 348.086426 -266.941808)
					(end 348.739206 -266.941808)
				)
			)
		)
	)
	(zone
		(layers "B.Cu" "In13.Cu" "In15.Cu")
		(hatch none 0.5)
		(connect_pads
			(clearance 0)
		)
		(min_thickness 0.25)
		(keepout
			(tracks not_allowed)
			(vias allowed)
			(pads allowed)
			(copperpour not_allowed)
			(footprints allowed)
		)
		(placement
			(enabled no)
			(sheetname "")
		)
		(fill yes
			(thermal_gap 0.5)
			(thermal_bridge_width 0.5)
			(island_removal_mode 0)
		)
		(polygon
			(pts
				(arc
					(start 269.155672 -238.966756)
					(mid 268.502892 -238.966756)
					(end 269.155672 -238.966756)
				)
			)
		)
	)
	(zone
		(layers "B.Cu" "In13.Cu" "In15.Cu")
		(hatch none 0.5)
		(connect_pads
			(clearance 0)
		)
		(min_thickness 0.25)
		(keepout
			(tracks not_allowed)
			(vias allowed)
			(pads allowed)
			(copperpour not_allowed)
			(footprints allowed)
		)
		(placement
			(enabled no)
			(sheetname "")
		)
		(fill yes
			(thermal_gap 0.5)
			(thermal_bridge_width 0.5)
			(island_removal_mode 0)
		)
		(polygon
			(pts
				(arc
					(start 269.155672 -281.466798)
					(mid 268.502892 -281.466798)
					(end 269.155672 -281.466798)
				)
			)
		)
	)
	(zone
		(layers "B.Cu" "In13.Cu" "In15.Cu")
		(hatch none 0.5)
		(connect_pads
			(clearance 0)
		)
		(min_thickness 0.25)
		(keepout
			(tracks not_allowed)
			(vias allowed)
			(pads allowed)
			(copperpour not_allowed)
			(footprints allowed)
		)
		(placement
			(enabled no)
			(sheetname "")
		)
		(fill yes
			(thermal_gap 0.5)
			(thermal_bridge_width 0.5)
			(island_removal_mode 0)
		)
		(polygon
			(pts
				(arc
					(start 203.297536 -222.816674)
					(mid 202.644756 -222.816674)
					(end 203.297536 -222.816674)
				)
			)
		)
	)
	(zone
		(layers "B.Cu" "In13.Cu" "In15.Cu")
		(hatch none 0.5)
		(connect_pads
			(clearance 0)
		)
		(min_thickness 0.25)
		(keepout
			(tracks not_allowed)
			(vias allowed)
			(pads allowed)
			(copperpour not_allowed)
			(footprints allowed)
		)
		(placement
			(enabled no)
			(sheetname "")
		)
		(fill yes
			(thermal_gap 0.5)
			(thermal_bridge_width 0.5)
			(island_removal_mode 0)
		)
		(polygon
			(pts
				(arc
					(start 79.827628 -403.883876)
					(mid 79.124048 -403.883876)
					(end 79.827628 -403.883876)
				)
			)
		)
	)
	(zone
		(layers "B.Cu" "In13.Cu" "In15.Cu")
		(hatch none 0.5)
		(connect_pads
			(clearance 0)
		)
		(min_thickness 0.25)
		(keepout
			(tracks not_allowed)
			(vias allowed)
			(pads allowed)
			(copperpour not_allowed)
			(footprints allowed)
		)
		(placement
			(enabled no)
			(sheetname "")
		)
		(fill yes
			(thermal_gap 0.5)
			(thermal_bridge_width 0.5)
			(island_removal_mode 0)
		)
		(polygon
			(pts
				(arc
					(start 99.389184 -275.8948)
					(mid 98.736404 -275.8948)
					(end 99.389184 -275.8948)
				)
			)
		)
	)
	(zone
		(layers "B.Cu" "In13.Cu" "In15.Cu")
		(hatch none 0.5)
		(connect_pads
			(clearance 0)
		)
		(min_thickness 0.25)
		(keepout
			(tracks not_allowed)
			(vias allowed)
			(pads allowed)
			(copperpour not_allowed)
			(footprints allowed)
		)
		(placement
			(enabled no)
			(sheetname "")
		)
		(fill yes
			(thermal_gap 0.5)
			(thermal_bridge_width 0.5)
			(island_removal_mode 0)
		)
		(polygon
			(pts
				(arc
					(start 21.215604 -231.316784)
					(mid 20.562824 -231.316784)
					(end 21.215604 -231.316784)
				)
			)
		)
	)
	(zone
		(layers "B.Cu" "In13.Cu" "In15.Cu")
		(hatch none 0.5)
		(connect_pads
			(clearance 0)
		)
		(min_thickness 0.25)
		(keepout
			(tracks not_allowed)
			(vias allowed)
			(pads allowed)
			(copperpour not_allowed)
			(footprints allowed)
		)
		(placement
			(enabled no)
			(sheetname "")
		)
		(fill yes
			(thermal_gap 0.5)
			(thermal_bridge_width 0.5)
			(island_removal_mode 0)
		)
		(polygon
			(pts
				(arc
					(start 269.155672 -220.266768)
					(mid 268.502892 -220.266768)
					(end 269.155672 -220.266768)
				)
			)
		)
	)
	(zone
		(layers "B.Cu" "In13.Cu" "In15.Cu")
		(hatch none 0.5)
		(connect_pads
			(clearance 0)
		)
		(min_thickness 0.25)
		(keepout
			(tracks not_allowed)
			(vias allowed)
			(pads allowed)
			(copperpour not_allowed)
			(footprints allowed)
		)
		(placement
			(enabled no)
			(sheetname "")
		)
		(fill yes
			(thermal_gap 0.5)
			(thermal_bridge_width 0.5)
			(island_removal_mode 0)
		)
		(polygon
			(pts
				(arc
					(start 420.054278 -4.95173)
					(mid 419.350698 -4.95173)
					(end 420.054278 -4.95173)
				)
			)
		)
	)
	(zone
		(layers "B.Cu" "In13.Cu" "In15.Cu")
		(hatch none 0.5)
		(connect_pads
			(clearance 0)
		)
		(min_thickness 0.25)
		(keepout
			(tracks not_allowed)
			(vias allowed)
			(pads allowed)
			(copperpour not_allowed)
			(footprints allowed)
		)
		(placement
			(enabled no)
			(sheetname "")
		)
		(fill yes
			(thermal_gap 0.5)
			(thermal_bridge_width 0.5)
			(island_removal_mode 0)
		)
		(polygon
			(pts
				(arc
					(start 371.77472 -403.883876)
					(mid 371.07114 -403.883876)
					(end 371.77472 -403.883876)
				)
			)
		)
	)
	(zone
		(layers "B.Cu" "In13.Cu" "In15.Cu")
		(hatch none 0.5)
		(connect_pads
			(clearance 0)
		)
		(min_thickness 0.25)
		(keepout
			(tracks not_allowed)
			(vias allowed)
			(pads allowed)
			(copperpour not_allowed)
			(footprints allowed)
		)
		(placement
			(enabled no)
			(sheetname "")
		)
		(fill yes
			(thermal_gap 0.5)
			(thermal_bridge_width 0.5)
			(island_removal_mode 0)
		)
		(polygon
			(pts
				(arc
					(start 65.054988 -431.889916)
					(mid 64.245236 -431.889916)
					(end 65.054988 -431.889916)
				)
			)
		)
	)
	(zone
		(layers "B.Cu" "In13.Cu" "In15.Cu")
		(hatch none 0.5)
		(connect_pads
			(clearance 0)
		)
		(min_thickness 0.25)
		(keepout
			(tracks not_allowed)
			(vias allowed)
			(pads allowed)
			(copperpour not_allowed)
			(footprints allowed)
		)
		(placement
			(enabled no)
			(sheetname "")
		)
		(fill yes
			(thermal_gap 0.5)
			(thermal_bridge_width 0.5)
			(island_removal_mode 0)
		)
		(polygon
			(pts
				(arc
					(start 17.115536 -232.166668)
					(mid 16.462756 -232.166668)
					(end 17.115536 -232.166668)
				)
			)
		)
	)
	(zone
		(layers "B.Cu" "In13.Cu" "In15.Cu")
		(hatch none 0.5)
		(connect_pads
			(clearance 0)
		)
		(min_thickness 0.25)
		(keepout
			(tracks not_allowed)
			(vias allowed)
			(pads allowed)
			(copperpour not_allowed)
			(footprints allowed)
		)
		(placement
			(enabled no)
			(sheetname "")
		)
		(fill yes
			(thermal_gap 0.5)
			(thermal_bridge_width 0.5)
			(island_removal_mode 0)
		)
		(polygon
			(pts
				(arc
					(start 265.055604 -259.366766)
					(mid 264.402824 -259.366766)
					(end 265.055604 -259.366766)
				)
			)
		)
	)
	(zone
		(layers "B.Cu" "In13.Cu" "In15.Cu")
		(hatch none 0.5)
		(connect_pads
			(clearance 0)
		)
		(min_thickness 0.25)
		(keepout
			(tracks not_allowed)
			(vias allowed)
			(pads allowed)
			(copperpour not_allowed)
			(footprints allowed)
		)
		(placement
			(enabled no)
			(sheetname "")
		)
		(fill yes
			(thermal_gap 0.5)
			(thermal_bridge_width 0.5)
			(island_removal_mode 0)
		)
		(polygon
			(pts
				(arc
					(start 357.667052 -277.522432)
					(mid 357.014272 -277.522432)
					(end 357.667052 -277.522432)
				)
			)
		)
	)
	(zone
		(layers "B.Cu" "In13.Cu" "In15.Cu")
		(hatch none 0.5)
		(connect_pads
			(clearance 0)
		)
		(min_thickness 0.25)
		(keepout
			(tracks not_allowed)
			(vias allowed)
			(pads allowed)
			(copperpour not_allowed)
			(footprints allowed)
		)
		(placement
			(enabled no)
			(sheetname "")
		)
		(fill yes
			(thermal_gap 0.5)
			(thermal_bridge_width 0.5)
			(island_removal_mode 0)
		)
		(polygon
			(pts
				(arc
					(start 306.541678 -410.030168)
					(mid 305.838098 -410.030168)
					(end 306.541678 -410.030168)
				)
			)
		)
	)
	(zone
		(layers "B.Cu" "In13.Cu" "In15.Cu")
		(hatch none 0.5)
		(connect_pads
			(clearance 0)
		)
		(min_thickness 0.25)
		(keepout
			(tracks not_allowed)
			(vias allowed)
			(pads allowed)
			(copperpour not_allowed)
			(footprints allowed)
		)
		(placement
			(enabled no)
			(sheetname "")
		)
		(fill yes
			(thermal_gap 0.5)
			(thermal_bridge_width 0.5)
			(island_removal_mode 0)
		)
		(polygon
			(pts
				(arc
					(start 265.055604 -274.66671)
					(mid 264.402824 -274.66671)
					(end 265.055604 -274.66671)
				)
			)
		)
	)
	(zone
		(layers "B.Cu" "In13.Cu" "In15.Cu")
		(hatch none 0.5)
		(connect_pads
			(clearance 0)
		)
		(min_thickness 0.25)
		(keepout
			(tracks not_allowed)
			(vias allowed)
			(pads allowed)
			(copperpour not_allowed)
			(footprints allowed)
		)
		(placement
			(enabled no)
			(sheetname "")
		)
		(fill yes
			(thermal_gap 0.5)
			(thermal_bridge_width 0.5)
			(island_removal_mode 0)
		)
		(polygon
			(pts
				(arc
					(start 346.389452 -257.98907)
					(mid 345.736672 -257.98907)
					(end 346.389452 -257.98907)
				)
			)
		)
	)
	(zone
		(layers "B.Cu" "In13.Cu" "In15.Cu")
		(hatch none 0.5)
		(connect_pads
			(clearance 0)
		)
		(min_thickness 0.25)
		(keepout
			(tracks not_allowed)
			(vias allowed)
			(pads allowed)
			(copperpour not_allowed)
			(footprints allowed)
		)
		(placement
			(enabled no)
			(sheetname "")
		)
		(fill yes
			(thermal_gap 0.5)
			(thermal_bridge_width 0.5)
			(island_removal_mode 0)
		)
		(polygon
			(pts
				(arc
					(start 345.919806 -281.59202)
					(mid 345.267026 -281.59202)
					(end 345.919806 -281.59202)
				)
			)
		)
	)
	(zone
		(layers "B.Cu" "In13.Cu" "In15.Cu")
		(hatch none 0.5)
		(connect_pads
			(clearance 0)
		)
		(min_thickness 0.25)
		(keepout
			(tracks not_allowed)
			(vias allowed)
			(pads allowed)
			(copperpour not_allowed)
			(footprints allowed)
		)
		(placement
			(enabled no)
			(sheetname "")
		)
		(fill yes
			(thermal_gap 0.5)
			(thermal_bridge_width 0.5)
			(island_removal_mode 0)
		)
		(polygon
			(pts
				(arc
					(start 343.930224 -248.806208)
					(mid 343.277444 -248.806208)
					(end 343.930224 -248.806208)
				)
			)
		)
	)
	(zone
		(layers "B.Cu" "In13.Cu" "In15.Cu")
		(hatch none 0.5)
		(connect_pads
			(clearance 0)
		)
		(min_thickness 0.25)
		(keepout
			(tracks not_allowed)
			(vias allowed)
			(pads allowed)
			(copperpour not_allowed)
			(footprints allowed)
		)
		(placement
			(enabled no)
			(sheetname "")
		)
		(fill yes
			(thermal_gap 0.5)
			(thermal_bridge_width 0.5)
			(island_removal_mode 0)
		)
		(polygon
			(pts
				(arc
					(start 207.397604 -251.716794)
					(mid 206.744824 -251.716794)
					(end 207.397604 -251.716794)
				)
			)
		)
	)
	(zone
		(layers "B.Cu" "In13.Cu" "In15.Cu")
		(hatch none 0.5)
		(connect_pads
			(clearance 0)
		)
		(min_thickness 0.25)
		(keepout
			(tracks not_allowed)
			(vias allowed)
			(pads allowed)
			(copperpour not_allowed)
			(footprints allowed)
		)
		(placement
			(enabled no)
			(sheetname "")
		)
		(fill yes
			(thermal_gap 0.5)
			(thermal_bridge_width 0.5)
			(island_removal_mode 0)
		)
		(polygon
			(pts
				(arc
					(start 269.155672 -248.31675)
					(mid 268.502892 -248.31675)
					(end 269.155672 -248.31675)
				)
			)
		)
	)
	(zone
		(layers "B.Cu" "In13.Cu" "In15.Cu")
		(hatch none 0.5)
		(connect_pads
			(clearance 0)
		)
		(min_thickness 0.25)
		(keepout
			(tracks not_allowed)
			(vias allowed)
			(pads allowed)
			(copperpour not_allowed)
			(footprints allowed)
		)
		(placement
			(enabled no)
			(sheetname "")
		)
		(fill yes
			(thermal_gap 0.5)
			(thermal_bridge_width 0.5)
			(island_removal_mode 0)
		)
		(polygon
			(pts
				(arc
					(start 451.237604 -227.91674)
					(mid 450.584824 -227.91674)
					(end 451.237604 -227.91674)
				)
			)
		)
	)
	(zone
		(layers "B.Cu" "In13.Cu" "In15.Cu")
		(hatch none 0.5)
		(connect_pads
			(clearance 0)
		)
		(min_thickness 0.25)
		(keepout
			(tracks not_allowed)
			(vias allowed)
			(pads allowed)
			(copperpour not_allowed)
			(footprints allowed)
		)
		(placement
			(enabled no)
			(sheetname "")
		)
		(fill yes
			(thermal_gap 0.5)
			(thermal_bridge_width 0.5)
			(island_removal_mode 0)
		)
		(polygon
			(pts
				(arc
					(start 269.155672 -298.466764)
					(mid 268.502892 -298.466764)
					(end 269.155672 -298.466764)
				)
			)
		)
	)
	(zone
		(layers "B.Cu" "In13.Cu" "In15.Cu")
		(hatch none 0.5)
		(connect_pads
			(clearance 0)
		)
		(min_thickness 0.25)
		(keepout
			(tracks not_allowed)
			(vias allowed)
			(pads allowed)
			(copperpour not_allowed)
			(footprints allowed)
		)
		(placement
			(enabled no)
			(sheetname "")
		)
		(fill yes
			(thermal_gap 0.5)
			(thermal_bridge_width 0.5)
			(island_removal_mode 0)
		)
		(polygon
			(pts
				(arc
					(start 93.280484 -283.219906)
					(mid 92.627704 -283.219906)
					(end 93.280484 -283.219906)
				)
			)
		)
	)
	(zone
		(layers "B.Cu" "In13.Cu" "In15.Cu")
		(hatch none 0.5)
		(connect_pads
			(clearance 0)
		)
		(min_thickness 0.25)
		(keepout
			(tracks not_allowed)
			(vias allowed)
			(pads allowed)
			(copperpour not_allowed)
			(footprints allowed)
		)
		(placement
			(enabled no)
			(sheetname "")
		)
		(fill yes
			(thermal_gap 0.5)
			(thermal_bridge_width 0.5)
			(island_removal_mode 0)
		)
		(polygon
			(pts
				(arc
					(start 13.671804 -259.366766)
					(mid 13.019024 -259.366766)
					(end 13.671804 -259.366766)
				)
			)
		)
	)
	(zone
		(layers "B.Cu" "In13.Cu" "In15.Cu")
		(hatch none 0.5)
		(connect_pads
			(clearance 0)
		)
		(min_thickness 0.25)
		(keepout
			(tracks not_allowed)
			(vias allowed)
			(pads allowed)
			(copperpour not_allowed)
			(footprints allowed)
		)
		(placement
			(enabled no)
			(sheetname "")
		)
		(fill yes
			(thermal_gap 0.5)
			(thermal_bridge_width 0.5)
			(island_removal_mode 0)
		)
		(polygon
			(pts
				(arc
					(start 95.520002 -247.992138)
					(mid 94.867222 -247.992138)
					(end 95.520002 -247.992138)
				)
			)
		)
	)
	(zone
		(layers "B.Cu" "In13.Cu" "In15.Cu")
		(hatch none 0.5)
		(connect_pads
			(clearance 0)
		)
		(min_thickness 0.25)
		(keepout
			(tracks not_allowed)
			(vias allowed)
			(pads allowed)
			(copperpour not_allowed)
			(footprints allowed)
		)
		(placement
			(enabled no)
			(sheetname "")
		)
		(fill yes
			(thermal_gap 0.5)
			(thermal_bridge_width 0.5)
			(island_removal_mode 0)
		)
		(polygon
			(pts
				(arc
					(start 372.234206 -268.569694)
					(mid 371.581426 -268.569694)
					(end 372.234206 -268.569694)
				)
			)
		)
	)
	(zone
		(layers "B.Cu" "In13.Cu" "In15.Cu")
		(hatch none 0.5)
		(connect_pads
			(clearance 0)
		)
		(min_thickness 0.25)
		(keepout
			(tracks not_allowed)
			(vias allowed)
			(pads allowed)
			(copperpour not_allowed)
			(footprints allowed)
		)
		(placement
			(enabled no)
			(sheetname "")
		)
		(fill yes
			(thermal_gap 0.5)
			(thermal_bridge_width 0.5)
			(island_removal_mode 0)
		)
		(polygon
			(pts
				(arc
					(start 55.893208 -4.962652)
					(mid 55.189628 -4.962652)
					(end 55.893208 -4.962652)
				)
			)
		)
	)
	(zone
		(layers "B.Cu" "In13.Cu" "In15.Cu")
		(hatch none 0.5)
		(connect_pads
			(clearance 0)
		)
		(min_thickness 0.25)
		(keepout
			(tracks not_allowed)
			(vias allowed)
			(pads allowed)
			(copperpour not_allowed)
			(footprints allowed)
		)
		(placement
			(enabled no)
			(sheetname "")
		)
		(fill yes
			(thermal_gap 0.5)
			(thermal_bridge_width 0.5)
			(island_removal_mode 0)
		)
		(polygon
			(pts
				(arc
					(start 347.329252 -275.8948)
					(mid 346.676472 -275.8948)
					(end 347.329252 -275.8948)
				)
			)
		)
	)
	(zone
		(layers "B.Cu" "In13.Cu" "In15.Cu")
		(hatch none 0.5)
		(connect_pads
			(clearance 0)
		)
		(min_thickness 0.25)
		(keepout
			(tracks not_allowed)
			(vias allowed)
			(pads allowed)
			(copperpour not_allowed)
			(footprints allowed)
		)
		(placement
			(enabled no)
			(sheetname "")
		)
		(fill yes
			(thermal_gap 0.5)
			(thermal_bridge_width 0.5)
			(island_removal_mode 0)
		)
		(polygon
			(pts
				(arc
					(start 125.123956 -239.0394)
					(mid 124.471176 -239.0394)
					(end 125.123956 -239.0394)
				)
			)
		)
	)
	(zone
		(layers "B.Cu" "In13.Cu" "In15.Cu")
		(hatch none 0.5)
		(connect_pads
			(clearance 0)
		)
		(min_thickness 0.25)
		(keepout
			(tracks not_allowed)
			(vias allowed)
			(pads allowed)
			(copperpour not_allowed)
			(footprints allowed)
		)
		(placement
			(enabled no)
			(sheetname "")
		)
		(fill yes
			(thermal_gap 0.5)
			(thermal_bridge_width 0.5)
			(island_removal_mode 0)
		)
		(polygon
			(pts
				(arc
					(start 59.055 -430.889918)
					(mid 58.245248 -430.889918)
					(end 59.055 -430.889918)
				)
			)
		)
	)
	(zone
		(layers "B.Cu" "In13.Cu" "In15.Cu")
		(hatch none 0.5)
		(connect_pads
			(clearance 0)
		)
		(min_thickness 0.25)
		(keepout
			(tracks not_allowed)
			(vias allowed)
			(pads allowed)
			(copperpour not_allowed)
			(footprints allowed)
		)
		(placement
			(enabled no)
			(sheetname "")
		)
		(fill yes
			(thermal_gap 0.5)
			(thermal_bridge_width 0.5)
			(island_removal_mode 0)
		)
		(polygon
			(pts
				(arc
					(start 21.215604 -289.11677)
					(mid 20.562824 -289.11677)
					(end 21.215604 -289.11677)
				)
			)
		)
	)
	(zone
		(layers "B.Cu" "In13.Cu" "In15.Cu")
		(hatch none 0.5)
		(connect_pads
			(clearance 0)
		)
		(min_thickness 0.25)
		(keepout
			(tracks not_allowed)
			(vias allowed)
			(pads allowed)
			(copperpour not_allowed)
			(footprints allowed)
		)
		(placement
			(enabled no)
			(sheetname "")
		)
		(fill yes
			(thermal_gap 0.5)
			(thermal_bridge_width 0.5)
			(island_removal_mode 0)
		)
		(polygon
			(pts
				(arc
					(start 269.155672 -236.416596)
					(mid 268.502892 -236.416596)
					(end 269.155672 -236.416596)
				)
			)
		)
	)
	(zone
		(layers "B.Cu" "In13.Cu" "In15.Cu")
		(hatch none 0.5)
		(connect_pads
			(clearance 0)
		)
		(min_thickness 0.25)
		(keepout
			(tracks not_allowed)
			(vias allowed)
			(pads allowed)
			(copperpour not_allowed)
			(footprints allowed)
		)
		(placement
			(enabled no)
			(sheetname "")
		)
		(fill yes
			(thermal_gap 0.5)
			(thermal_bridge_width 0.5)
			(island_removal_mode 0)
		)
		(polygon
			(pts
				(arc
					(start 85.090508 -403.883876)
					(mid 84.386928 -403.883876)
					(end 85.090508 -403.883876)
				)
			)
		)
	)
	(zone
		(layers "B.Cu" "In13.Cu" "In15.Cu")
		(hatch none 0.5)
		(connect_pads
			(clearance 0)
		)
		(min_thickness 0.25)
		(keepout
			(tracks not_allowed)
			(vias allowed)
			(pads allowed)
			(copperpour not_allowed)
			(footprints allowed)
		)
		(placement
			(enabled no)
			(sheetname "")
		)
		(fill yes
			(thermal_gap 0.5)
			(thermal_bridge_width 0.5)
			(island_removal_mode 0)
		)
		(polygon
			(pts
				(arc
					(start 207.397604 -265.316716)
					(mid 206.744824 -265.316716)
					(end 207.397604 -265.316716)
				)
			)
		)
	)
	(zone
		(layers "B.Cu" "In13.Cu" "In15.Cu")
		(hatch none 0.5)
		(connect_pads
			(clearance 0)
		)
		(min_thickness 0.25)
		(keepout
			(tracks not_allowed)
			(vias allowed)
			(pads allowed)
			(copperpour not_allowed)
			(footprints allowed)
		)
		(placement
			(enabled no)
			(sheetname "")
		)
		(fill yes
			(thermal_gap 0.5)
			(thermal_bridge_width 0.5)
			(island_removal_mode 0)
		)
		(polygon
			(pts
				(arc
					(start 265.055604 -247.466612)
					(mid 264.402824 -247.466612)
					(end 265.055604 -247.466612)
				)
			)
		)
	)
	(zone
		(layers "B.Cu" "In13.Cu" "In15.Cu")
		(hatch none 0.5)
		(connect_pads
			(clearance 0)
		)
		(min_thickness 0.25)
		(keepout
			(tracks not_allowed)
			(vias allowed)
			(pads allowed)
			(copperpour not_allowed)
			(footprints allowed)
		)
		(placement
			(enabled no)
			(sheetname "")
		)
		(fill yes
			(thermal_gap 0.5)
			(thermal_bridge_width 0.5)
			(island_removal_mode 0)
		)
		(polygon
			(pts
				(arc
					(start 331.047598 -410.030168)
					(mid 330.344018 -410.030168)
					(end 331.047598 -410.030168)
				)
			)
		)
	)
	(zone
		(layers "B.Cu" "In13.Cu" "In15.Cu")
		(hatch none 0.5)
		(connect_pads
			(clearance 0)
		)
		(min_thickness 0.25)
		(keepout
			(tracks not_allowed)
			(vias allowed)
			(pads allowed)
			(copperpour not_allowed)
			(footprints allowed)
		)
		(placement
			(enabled no)
			(sheetname "")
		)
		(fill yes
			(thermal_gap 0.5)
			(thermal_bridge_width 0.5)
			(island_removal_mode 0)
		)
		(polygon
			(pts
				(arc
					(start 123.354338 -265.314176)
					(mid 122.701558 -265.314176)
					(end 123.354338 -265.314176)
				)
			)
		)
	)
	(zone
		(layers "B.Cu" "In13.Cu" "In15.Cu")
		(hatch none 0.5)
		(connect_pads
			(clearance 0)
		)
		(min_thickness 0.25)
		(keepout
			(tracks not_allowed)
			(vias allowed)
			(pads allowed)
			(copperpour not_allowed)
			(footprints allowed)
		)
		(placement
			(enabled no)
			(sheetname "")
		)
		(fill yes
			(thermal_gap 0.5)
			(thermal_bridge_width 0.5)
			(island_removal_mode 0)
		)
		(polygon
			(pts
				(arc
					(start 17.115536 -204.116686)
					(mid 16.462756 -204.116686)
					(end 17.115536 -204.116686)
				)
			)
		)
	)
	(zone
		(layers "B.Cu" "In13.Cu" "In15.Cu")
		(hatch none 0.5)
		(connect_pads
			(clearance 0)
		)
		(min_thickness 0.25)
		(keepout
			(tracks not_allowed)
			(vias allowed)
			(pads allowed)
			(copperpour not_allowed)
			(footprints allowed)
		)
		(placement
			(enabled no)
			(sheetname "")
		)
		(fill yes
			(thermal_gap 0.5)
			(thermal_bridge_width 0.5)
			(island_removal_mode 0)
		)
		(polygon
			(pts
				(arc
					(start 93.280484 -281.59202)
					(mid 92.627704 -281.59202)
					(end 93.280484 -281.59202)
				)
			)
		)
	)
	(zone
		(layers "B.Cu" "In13.Cu" "In15.Cu")
		(hatch none 0.5)
		(connect_pads
			(clearance 0)
		)
		(min_thickness 0.25)
		(keepout
			(tracks not_allowed)
			(vias allowed)
			(pads allowed)
			(copperpour not_allowed)
			(footprints allowed)
		)
		(placement
			(enabled no)
			(sheetname "")
		)
		(fill yes
			(thermal_gap 0.5)
			(thermal_bridge_width 0.5)
			(island_removal_mode 0)
		)
		(polygon
			(pts
				(arc
					(start 69.05498 -431.889916)
					(mid 68.245228 -431.889916)
					(end 69.05498 -431.889916)
				)
			)
		)
	)
	(zone
		(layers "B.Cu" "In13.Cu" "In15.Cu")
		(hatch none 0.5)
		(connect_pads
			(clearance 0)
		)
		(min_thickness 0.25)
		(keepout
			(tracks not_allowed)
			(vias allowed)
			(pads allowed)
			(copperpour not_allowed)
			(footprints allowed)
		)
		(placement
			(enabled no)
			(sheetname "")
		)
		(fill yes
			(thermal_gap 0.5)
			(thermal_bridge_width 0.5)
			(island_removal_mode 0)
		)
		(polygon
			(pts
				(arc
					(start 354.73767 -221.94774)
					(mid 354.08489 -221.94774)
					(end 354.73767 -221.94774)
				)
			)
		)
	)
	(zone
		(layers "B.Cu" "In13.Cu" "In15.Cu")
		(hatch none 0.5)
		(connect_pads
			(clearance 0)
		)
		(min_thickness 0.25)
		(keepout
			(tracks not_allowed)
			(vias allowed)
			(pads allowed)
			(copperpour not_allowed)
			(footprints allowed)
		)
		(placement
			(enabled no)
			(sheetname "")
		)
		(fill yes
			(thermal_gap 0.5)
			(thermal_bridge_width 0.5)
			(island_removal_mode 0)
		)
		(polygon
			(pts
				(arc
					(start 373.53367 -228.45903)
					(mid 372.88089 -228.45903)
					(end 373.53367 -228.45903)
				)
			)
		)
	)
	(zone
		(layers "B.Cu" "In13.Cu" "In15.Cu")
		(hatch none 0.5)
		(connect_pads
			(clearance 0)
		)
		(min_thickness 0.25)
		(keepout
			(tracks not_allowed)
			(vias allowed)
			(pads allowed)
			(copperpour not_allowed)
			(footprints allowed)
		)
		(placement
			(enabled no)
			(sheetname "")
		)
		(fill yes
			(thermal_gap 0.5)
			(thermal_bridge_width 0.5)
			(island_removal_mode 0)
		)
		(polygon
			(pts
				(arc
					(start 130.154934 -426.089826)
					(mid 129.345182 -426.089826)
					(end 130.154934 -426.089826)
				)
			)
		)
	)
	(zone
		(layers "B.Cu" "In13.Cu" "In15.Cu")
		(hatch none 0.5)
		(connect_pads
			(clearance 0)
		)
		(min_thickness 0.25)
		(keepout
			(tracks not_allowed)
			(vias allowed)
			(pads allowed)
			(copperpour not_allowed)
			(footprints allowed)
		)
		(placement
			(enabled no)
			(sheetname "")
		)
		(fill yes
			(thermal_gap 0.5)
			(thermal_bridge_width 0.5)
			(island_removal_mode 0)
		)
		(polygon
			(pts
				(arc
					(start 348.739206 -268.569694)
					(mid 348.086426 -268.569694)
					(end 348.739206 -268.569694)
				)
			)
		)
	)
	(zone
		(layers "B.Cu" "In13.Cu" "In15.Cu")
		(hatch none 0.5)
		(connect_pads
			(clearance 0)
		)
		(min_thickness 0.25)
		(keepout
			(tracks not_allowed)
			(vias allowed)
			(pads allowed)
			(copperpour not_allowed)
			(footprints allowed)
		)
		(placement
			(enabled no)
			(sheetname "")
		)
		(fill yes
			(thermal_gap 0.5)
			(thermal_bridge_width 0.5)
			(island_removal_mode 0)
		)
		(polygon
			(pts
				(arc
					(start 125.233938 -262.058658)
					(mid 124.581158 -262.058658)
					(end 125.233938 -262.058658)
				)
			)
		)
	)
	(zone
		(layers "B.Cu" "In13.Cu" "In15.Cu")
		(hatch none 0.5)
		(connect_pads
			(clearance 0)
		)
		(min_thickness 0.25)
		(keepout
			(tracks not_allowed)
			(vias allowed)
			(pads allowed)
			(copperpour not_allowed)
			(footprints allowed)
		)
		(placement
			(enabled no)
			(sheetname "")
		)
		(fill yes
			(thermal_gap 0.5)
			(thermal_bridge_width 0.5)
			(island_removal_mode 0)
		)
		(polygon
			(pts
				(arc
					(start 43.700954 -398.771872)
					(mid 42.997374 -398.771872)
					(end 43.700954 -398.771872)
				)
			)
		)
	)
	(zone
		(layers "B.Cu" "In13.Cu" "In15.Cu")
		(hatch none 0.5)
		(connect_pads
			(clearance 0)
		)
		(min_thickness 0.25)
		(keepout
			(tracks not_allowed)
			(vias allowed)
			(pads allowed)
			(copperpour not_allowed)
			(footprints allowed)
		)
		(placement
			(enabled no)
			(sheetname "")
		)
		(fill yes
			(thermal_gap 0.5)
			(thermal_bridge_width 0.5)
			(island_removal_mode 0)
		)
		(polygon
			(pts
				(arc
					(start 123.354338 -255.547622)
					(mid 122.701558 -255.547622)
					(end 123.354338 -255.547622)
				)
			)
		)
	)
	(zone
		(layers "B.Cu" "In13.Cu" "In15.Cu")
		(hatch none 0.5)
		(connect_pads
			(clearance 0)
		)
		(min_thickness 0.25)
		(keepout
			(tracks not_allowed)
			(vias allowed)
			(pads allowed)
			(copperpour not_allowed)
			(footprints allowed)
		)
		(placement
			(enabled no)
			(sheetname "")
		)
		(fill yes
			(thermal_gap 0.5)
			(thermal_bridge_width 0.5)
			(island_removal_mode 0)
		)
		(polygon
			(pts
				(arc
					(start 98.449384 -257.98907)
					(mid 97.796604 -257.98907)
					(end 98.449384 -257.98907)
				)
			)
		)
	)
	(zone
		(layers "B.Cu" "In13.Cu" "In15.Cu")
		(hatch none 0.5)
		(connect_pads
			(clearance 0)
		)
		(min_thickness 0.25)
		(keepout
			(tracks not_allowed)
			(vias allowed)
			(pads allowed)
			(copperpour not_allowed)
			(footprints allowed)
		)
		(placement
			(enabled no)
			(sheetname "")
		)
		(fill yes
			(thermal_gap 0.5)
			(thermal_bridge_width 0.5)
			(island_removal_mode 0)
		)
		(polygon
			(pts
				(arc
					(start 17.115536 -302.716692)
					(mid 16.462756 -302.716692)
					(end 17.115536 -302.716692)
				)
			)
		)
	)
	(zone
		(layers "B.Cu" "In13.Cu" "In15.Cu")
		(hatch none 0.5)
		(connect_pads
			(clearance 0)
		)
		(min_thickness 0.25)
		(keepout
			(tracks not_allowed)
			(vias allowed)
			(pads allowed)
			(copperpour not_allowed)
			(footprints allowed)
		)
		(placement
			(enabled no)
			(sheetname "")
		)
		(fill yes
			(thermal_gap 0.5)
			(thermal_bridge_width 0.5)
			(island_removal_mode 0)
		)
		(polygon
			(pts
				(arc
					(start 98.339402 -230.086662)
					(mid 97.686622 -230.086662)
					(end 98.339402 -230.086662)
				)
			)
		)
	)
	(zone
		(layers "B.Cu" "In13.Cu" "In15.Cu")
		(hatch none 0.5)
		(connect_pads
			(clearance 0)
		)
		(min_thickness 0.25)
		(keepout
			(tracks not_allowed)
			(vias allowed)
			(pads allowed)
			(copperpour not_allowed)
			(footprints allowed)
		)
		(placement
			(enabled no)
			(sheetname "")
		)
		(fill yes
			(thermal_gap 0.5)
			(thermal_bridge_width 0.5)
			(island_removal_mode 0)
		)
		(polygon
			(pts
				(arc
					(start 413.154876 -427.089824)
					(mid 412.345124 -427.089824)
					(end 413.154876 -427.089824)
				)
			)
		)
	)
	(zone
		(layers "B.Cu" "In13.Cu" "In15.Cu")
		(hatch none 0.5)
		(connect_pads
			(clearance 0)
		)
		(min_thickness 0.25)
		(keepout
			(tracks not_allowed)
			(vias allowed)
			(pads allowed)
			(copperpour not_allowed)
			(footprints allowed)
		)
		(placement
			(enabled no)
			(sheetname "")
		)
		(fill yes
			(thermal_gap 0.5)
			(thermal_bridge_width 0.5)
			(island_removal_mode 0)
		)
		(polygon
			(pts
				(arc
					(start 376.35307 -246.364506)
					(mid 375.70029 -246.364506)
					(end 376.35307 -246.364506)
				)
			)
		)
	)
	(zone
		(layers "B.Cu" "In13.Cu" "In15.Cu")
		(hatch none 0.5)
		(connect_pads
			(clearance 0)
		)
		(min_thickness 0.25)
		(keepout
			(tracks not_allowed)
			(vias allowed)
			(pads allowed)
			(copperpour not_allowed)
			(footprints allowed)
		)
		(placement
			(enabled no)
			(sheetname "")
		)
		(fill yes
			(thermal_gap 0.5)
			(thermal_bridge_width 0.5)
			(island_removal_mode 0)
		)
		(polygon
			(pts
				(arc
					(start 265.055604 -199.866758)
					(mid 264.402824 -199.866758)
					(end 265.055604 -199.866758)
				)
			)
		)
	)
	(zone
		(layers "B.Cu" "In13.Cu" "In15.Cu")
		(hatch none 0.5)
		(connect_pads
			(clearance 0)
		)
		(min_thickness 0.25)
		(keepout
			(tracks not_allowed)
			(vias allowed)
			(pads allowed)
			(copperpour not_allowed)
			(footprints allowed)
		)
		(placement
			(enabled no)
			(sheetname "")
		)
		(fill yes
			(thermal_gap 0.5)
			(thermal_bridge_width 0.5)
			(island_removal_mode 0)
		)
		(polygon
			(pts
				(arc
					(start 99.859338 -283.219906)
					(mid 99.206558 -283.219906)
					(end 99.859338 -283.219906)
				)
			)
		)
	)
	(zone
		(layers "B.Cu" "In13.Cu" "In15.Cu")
		(hatch none 0.5)
		(connect_pads
			(clearance 0)
		)
		(min_thickness 0.25)
		(keepout
			(tracks not_allowed)
			(vias allowed)
			(pads allowed)
			(copperpour not_allowed)
			(footprints allowed)
		)
		(placement
			(enabled no)
			(sheetname "")
		)
		(fill yes
			(thermal_gap 0.5)
			(thermal_bridge_width 0.5)
			(island_removal_mode 0)
		)
		(polygon
			(pts
				(arc
					(start 100.328984 -279.150318)
					(mid 99.676204 -279.150318)
					(end 100.328984 -279.150318)
				)
			)
		)
	)
	(zone
		(layers "B.Cu" "In13.Cu" "In15.Cu")
		(hatch none 0.5)
		(connect_pads
			(clearance 0)
		)
		(min_thickness 0.25)
		(keepout
			(tracks not_allowed)
			(vias allowed)
			(pads allowed)
			(copperpour not_allowed)
			(footprints allowed)
		)
		(placement
			(enabled no)
			(sheetname "")
		)
		(fill yes
			(thermal_gap 0.5)
			(thermal_bridge_width 0.5)
			(island_removal_mode 0)
		)
		(polygon
			(pts
				(arc
					(start 348.269052 -279.150318)
					(mid 347.616272 -279.150318)
					(end 348.269052 -279.150318)
				)
			)
		)
	)
	(zone
		(layers "B.Cu" "In13.Cu" "In15.Cu")
		(hatch none 0.5)
		(connect_pads
			(clearance 0)
		)
		(min_thickness 0.25)
		(keepout
			(tracks not_allowed)
			(vias allowed)
			(pads allowed)
			(copperpour not_allowed)
			(footprints allowed)
		)
		(placement
			(enabled no)
			(sheetname "")
		)
		(fill yes
			(thermal_gap 0.5)
			(thermal_bridge_width 0.5)
			(island_removal_mode 0)
		)
		(polygon
			(pts
				(arc
					(start 366.95507 -220.319854)
					(mid 366.30229 -220.319854)
					(end 366.95507 -220.319854)
				)
			)
		)
	)
	(zone
		(layers "B.Cu" "In13.Cu" "In15.Cu")
		(hatch none 0.5)
		(connect_pads
			(clearance 0)
		)
		(min_thickness 0.25)
		(keepout
			(tracks not_allowed)
			(vias allowed)
			(pads allowed)
			(copperpour not_allowed)
			(footprints allowed)
		)
		(placement
			(enabled no)
			(sheetname "")
		)
		(fill yes
			(thermal_gap 0.5)
			(thermal_bridge_width 0.5)
			(island_removal_mode 0)
		)
		(polygon
			(pts
				(arc
					(start 101.158802 -230.086662)
					(mid 100.506022 -230.086662)
					(end 101.158802 -230.086662)
				)
			)
		)
	)
	(zone
		(layers "B.Cu" "In13.Cu" "In15.Cu")
		(hatch none 0.5)
		(connect_pads
			(clearance 0)
		)
		(min_thickness 0.25)
		(keepout
			(tracks not_allowed)
			(vias allowed)
			(pads allowed)
			(copperpour not_allowed)
			(footprints allowed)
		)
		(placement
			(enabled no)
			(sheetname "")
		)
		(fill yes
			(thermal_gap 0.5)
			(thermal_bridge_width 0.5)
			(island_removal_mode 0)
		)
		(polygon
			(pts
				(arc
					(start 98.919538 -257.175254)
					(mid 98.266758 -257.175254)
					(end 98.919538 -257.175254)
				)
			)
		)
	)
	(zone
		(layers "B.Cu" "In13.Cu" "In15.Cu")
		(hatch none 0.5)
		(connect_pads
			(clearance 0)
		)
		(min_thickness 0.25)
		(keepout
			(tracks not_allowed)
			(vias allowed)
			(pads allowed)
			(copperpour not_allowed)
			(footprints allowed)
		)
		(placement
			(enabled no)
			(sheetname "")
		)
		(fill yes
			(thermal_gap 0.5)
			(thermal_bridge_width 0.5)
			(island_removal_mode 0)
		)
		(polygon
			(pts
				(arc
					(start 451.237604 -299.316648)
					(mid 450.584824 -299.316648)
					(end 451.237604 -299.316648)
				)
			)
		)
	)
	(zone
		(layers "B.Cu" "In13.Cu" "In15.Cu")
		(hatch none 0.5)
		(connect_pads
			(clearance 0)
		)
		(min_thickness 0.25)
		(keepout
			(tracks not_allowed)
			(vias allowed)
			(pads allowed)
			(copperpour not_allowed)
			(footprints allowed)
		)
		(placement
			(enabled no)
			(sheetname "")
		)
		(fill yes
			(thermal_gap 0.5)
			(thermal_bridge_width 0.5)
			(island_removal_mode 0)
		)
		(polygon
			(pts
				(arc
					(start 348.269052 -274.266914)
					(mid 347.616272 -274.266914)
					(end 348.269052 -274.266914)
				)
			)
		)
	)
	(zone
		(layers "B.Cu" "In13.Cu" "In15.Cu")
		(hatch none 0.5)
		(connect_pads
			(clearance 0)
		)
		(min_thickness 0.25)
		(keepout
			(tracks not_allowed)
			(vias allowed)
			(pads allowed)
			(copperpour not_allowed)
			(footprints allowed)
		)
		(placement
			(enabled no)
			(sheetname "")
		)
		(fill yes
			(thermal_gap 0.5)
			(thermal_bridge_width 0.5)
			(island_removal_mode 0)
		)
		(polygon
			(pts
				(arc
					(start 373.643652 -271.011396)
					(mid 372.990872 -271.011396)
					(end 373.643652 -271.011396)
				)
			)
		)
	)
	(zone
		(layers "B.Cu" "In13.Cu" "In15.Cu")
		(hatch none 0.5)
		(connect_pads
			(clearance 0)
		)
		(min_thickness 0.25)
		(keepout
			(tracks not_allowed)
			(vias allowed)
			(pads allowed)
			(copperpour not_allowed)
			(footprints allowed)
		)
		(placement
			(enabled no)
			(sheetname "")
		)
		(fill yes
			(thermal_gap 0.5)
			(thermal_bridge_width 0.5)
			(island_removal_mode 0)
		)
		(polygon
			(pts
				(arc
					(start 451.237604 -252.566678)
					(mid 450.584824 -252.566678)
					(end 451.237604 -252.566678)
				)
			)
		)
	)
	(zone
		(layers "B.Cu" "In13.Cu" "In15.Cu")
		(hatch none 0.5)
		(connect_pads
			(clearance 0)
		)
		(min_thickness 0.25)
		(keepout
			(tracks not_allowed)
			(vias allowed)
			(pads allowed)
			(copperpour not_allowed)
			(footprints allowed)
		)
		(placement
			(enabled no)
			(sheetname "")
		)
		(fill yes
			(thermal_gap 0.5)
			(thermal_bridge_width 0.5)
			(island_removal_mode 0)
		)
		(polygon
			(pts
				(arc
					(start 342.990424 -247.178322)
					(mid 342.337644 -247.178322)
					(end 342.990424 -247.178322)
				)
			)
		)
	)
	(zone
		(layers "B.Cu" "In13.Cu" "In15.Cu")
		(hatch none 0.5)
		(connect_pads
			(clearance 0)
		)
		(min_thickness 0.25)
		(keepout
			(tracks not_allowed)
			(vias allowed)
			(pads allowed)
			(copperpour not_allowed)
			(footprints allowed)
		)
		(placement
			(enabled no)
			(sheetname "")
		)
		(fill yes
			(thermal_gap 0.5)
			(thermal_bridge_width 0.5)
			(island_removal_mode 0)
		)
		(polygon
			(pts
				(arc
					(start 123.823984 -261.244842)
					(mid 123.171204 -261.244842)
					(end 123.823984 -261.244842)
				)
			)
		)
	)
	(zone
		(layers "B.Cu" "In13.Cu" "In15.Cu")
		(hatch none 0.5)
		(connect_pads
			(clearance 0)
		)
		(min_thickness 0.25)
		(keepout
			(tracks not_allowed)
			(vias allowed)
			(pads allowed)
			(copperpour not_allowed)
			(footprints allowed)
		)
		(placement
			(enabled no)
			(sheetname "")
		)
		(fill yes
			(thermal_gap 0.5)
			(thermal_bridge_width 0.5)
			(island_removal_mode 0)
		)
		(polygon
			(pts
				(arc
					(start 269.155672 -285.716726)
					(mid 268.502892 -285.716726)
					(end 269.155672 -285.716726)
				)
			)
		)
	)
	(zone
		(layers "B.Cu" "In13.Cu" "In15.Cu")
		(hatch none 0.5)
		(connect_pads
			(clearance 0)
		)
		(min_thickness 0.25)
		(keepout
			(tracks not_allowed)
			(vias allowed)
			(pads allowed)
			(copperpour not_allowed)
			(footprints allowed)
		)
		(placement
			(enabled no)
			(sheetname "")
		)
		(fill yes
			(thermal_gap 0.5)
			(thermal_bridge_width 0.5)
			(island_removal_mode 0)
		)
		(polygon
			(pts
				(arc
					(start 397.14424 -403.883876)
					(mid 396.44066 -403.883876)
					(end 397.14424 -403.883876)
				)
			)
		)
	)
	(zone
		(layers "B.Cu" "In13.Cu" "In15.Cu")
		(hatch none 0.5)
		(connect_pads
			(clearance 0)
		)
		(min_thickness 0.25)
		(keepout
			(tracks not_allowed)
			(vias allowed)
			(pads allowed)
			(copperpour not_allowed)
			(footprints allowed)
		)
		(placement
			(enabled no)
			(sheetname "")
		)
		(fill yes
			(thermal_gap 0.5)
			(thermal_bridge_width 0.5)
			(island_removal_mode 0)
		)
		(polygon
			(pts
				(arc
					(start 21.215604 -233.016806)
					(mid 20.562824 -233.016806)
					(end 21.215604 -233.016806)
				)
			)
		)
	)
	(zone
		(layers "B.Cu" "In13.Cu" "In15.Cu")
		(hatch none 0.5)
		(connect_pads
			(clearance 0)
		)
		(min_thickness 0.25)
		(keepout
			(tracks not_allowed)
			(vias allowed)
			(pads allowed)
			(copperpour not_allowed)
			(footprints allowed)
		)
		(placement
			(enabled no)
			(sheetname "")
		)
		(fill yes
			(thermal_gap 0.5)
			(thermal_bridge_width 0.5)
			(island_removal_mode 0)
		)
		(polygon
			(pts
				(arc
					(start 207.397604 -236.416596)
					(mid 206.744824 -236.416596)
					(end 207.397604 -236.416596)
				)
			)
		)
	)
	(zone
		(layers "B.Cu" "In13.Cu" "In15.Cu")
		(hatch none 0.5)
		(connect_pads
			(clearance 0)
		)
		(min_thickness 0.25)
		(keepout
			(tracks not_allowed)
			(vias allowed)
			(pads allowed)
			(copperpour not_allowed)
			(footprints allowed)
		)
		(placement
			(enabled no)
			(sheetname "")
		)
		(fill yes
			(thermal_gap 0.5)
			(thermal_bridge_width 0.5)
			(island_removal_mode 0)
		)
		(polygon
			(pts
				(arc
					(start 347.329252 -274.266914)
					(mid 346.676472 -274.266914)
					(end 347.329252 -274.266914)
				)
			)
		)
	)
	(zone
		(layers "B.Cu" "In13.Cu" "In15.Cu")
		(hatch none 0.5)
		(connect_pads
			(clearance 0)
		)
		(min_thickness 0.25)
		(keepout
			(tracks not_allowed)
			(vias allowed)
			(pads allowed)
			(copperpour not_allowed)
			(footprints allowed)
		)
		(placement
			(enabled no)
			(sheetname "")
		)
		(fill yes
			(thermal_gap 0.5)
			(thermal_bridge_width 0.5)
			(island_removal_mode 0)
		)
		(polygon
			(pts
				(arc
					(start 346.859606 -273.453098)
					(mid 346.206826 -273.453098)
					(end 346.859606 -273.453098)
				)
			)
		)
	)
	(zone
		(layers "B.Cu" "In13.Cu" "In15.Cu")
		(hatch none 0.5)
		(connect_pads
			(clearance 0)
		)
		(min_thickness 0.25)
		(keepout
			(tracks not_allowed)
			(vias allowed)
			(pads allowed)
			(copperpour not_allowed)
			(footprints allowed)
		)
		(placement
			(enabled no)
			(sheetname "")
		)
		(fill yes
			(thermal_gap 0.5)
			(thermal_bridge_width 0.5)
			(island_removal_mode 0)
		)
		(polygon
			(pts
				(arc
					(start 70.637908 -403.883876)
					(mid 69.934328 -403.883876)
					(end 70.637908 -403.883876)
				)
			)
		)
	)
	(zone
		(layers "B.Cu" "In13.Cu" "In15.Cu")
		(hatch none 0.5)
		(connect_pads
			(clearance 0)
		)
		(min_thickness 0.25)
		(keepout
			(tracks not_allowed)
			(vias allowed)
			(pads allowed)
			(copperpour not_allowed)
			(footprints allowed)
		)
		(placement
			(enabled no)
			(sheetname "")
		)
		(fill yes
			(thermal_gap 0.5)
			(thermal_bridge_width 0.5)
			(island_removal_mode 0)
		)
		(polygon
			(pts
				(arc
					(start 100.219002 -239.853216)
					(mid 99.566222 -239.853216)
					(end 100.219002 -239.853216)
				)
			)
		)
	)
	(zone
		(layers "B.Cu" "In13.Cu" "In15.Cu")
		(hatch none 0.5)
		(connect_pads
			(clearance 0)
		)
		(min_thickness 0.25)
		(keepout
			(tracks not_allowed)
			(vias allowed)
			(pads allowed)
			(copperpour not_allowed)
			(footprints allowed)
		)
		(placement
			(enabled no)
			(sheetname "")
		)
		(fill yes
			(thermal_gap 0.5)
			(thermal_bridge_width 0.5)
			(island_removal_mode 0)
		)
		(polygon
			(pts
				(arc
					(start 118.545356 -221.133924)
					(mid 117.892576 -221.133924)
					(end 118.545356 -221.133924)
				)
			)
		)
	)
	(zone
		(layers "B.Cu" "In13.Cu" "In15.Cu")
		(hatch none 0.5)
		(connect_pads
			(clearance 0)
		)
		(min_thickness 0.25)
		(keepout
			(tracks not_allowed)
			(vias allowed)
			(pads allowed)
			(copperpour not_allowed)
			(footprints allowed)
		)
		(placement
			(enabled no)
			(sheetname "")
		)
		(fill yes
			(thermal_gap 0.5)
			(thermal_bridge_width 0.5)
			(island_removal_mode 0)
		)
		(polygon
			(pts
				(arc
					(start 371.184424 -232.528364)
					(mid 370.531644 -232.528364)
					(end 371.184424 -232.528364)
				)
			)
		)
	)
	(zone
		(layers "B.Cu" "In13.Cu" "In15.Cu")
		(hatch none 0.5)
		(connect_pads
			(clearance 0)
		)
		(min_thickness 0.25)
		(keepout
			(tracks not_allowed)
			(vias allowed)
			(pads allowed)
			(copperpour not_allowed)
			(footprints allowed)
		)
		(placement
			(enabled no)
			(sheetname "")
		)
		(fill yes
			(thermal_gap 0.5)
			(thermal_bridge_width 0.5)
			(island_removal_mode 0)
		)
		(polygon
			(pts
				(arc
					(start 455.337672 -203.266802)
					(mid 454.684892 -203.266802)
					(end 455.337672 -203.266802)
				)
			)
		)
	)
	(zone
		(layers "B.Cu" "In13.Cu" "In15.Cu")
		(hatch none 0.5)
		(connect_pads
			(clearance 0)
		)
		(min_thickness 0.25)
		(keepout
			(tracks not_allowed)
			(vias allowed)
			(pads allowed)
			(copperpour not_allowed)
			(footprints allowed)
		)
		(placement
			(enabled no)
			(sheetname "")
		)
		(fill yes
			(thermal_gap 0.5)
			(thermal_bridge_width 0.5)
			(island_removal_mode 0)
		)
		(polygon
			(pts
				(arc
					(start 343.570052 -282.405836)
					(mid 342.917272 -282.405836)
					(end 343.570052 -282.405836)
				)
			)
		)
	)
	(zone
		(layers "B.Cu" "In13.Cu" "In15.Cu")
		(hatch none 0.5)
		(connect_pads
			(clearance 0)
		)
		(min_thickness 0.25)
		(keepout
			(tracks not_allowed)
			(vias allowed)
			(pads allowed)
			(copperpour not_allowed)
			(footprints allowed)
		)
		(placement
			(enabled no)
			(sheetname "")
		)
		(fill yes
			(thermal_gap 0.5)
			(thermal_bridge_width 0.5)
			(island_removal_mode 0)
		)
		(polygon
			(pts
				(arc
					(start 348.629224 -239.0394)
					(mid 347.976444 -239.0394)
					(end 348.629224 -239.0394)
				)
			)
		)
	)
	(zone
		(layers "B.Cu" "In13.Cu" "In15.Cu")
		(hatch none 0.5)
		(connect_pads
			(clearance 0)
		)
		(min_thickness 0.25)
		(keepout
			(tracks not_allowed)
			(vias allowed)
			(pads allowed)
			(copperpour not_allowed)
			(footprints allowed)
		)
		(placement
			(enabled no)
			(sheetname "")
		)
		(fill yes
			(thermal_gap 0.5)
			(thermal_bridge_width 0.5)
			(island_removal_mode 0)
		)
		(polygon
			(pts
				(arc
					(start 100.328984 -256.361438)
					(mid 99.676204 -256.361438)
					(end 100.328984 -256.361438)
				)
			)
		)
	)
	(zone
		(layers "B.Cu" "In13.Cu" "In15.Cu")
		(hatch none 0.5)
		(connect_pads
			(clearance 0)
		)
		(min_thickness 0.25)
		(keepout
			(tracks not_allowed)
			(vias allowed)
			(pads allowed)
			(copperpour not_allowed)
			(footprints allowed)
		)
		(placement
			(enabled no)
			(sheetname "")
		)
		(fill yes
			(thermal_gap 0.5)
			(thermal_bridge_width 0.5)
			(island_removal_mode 0)
		)
		(polygon
			(pts
				(arc
					(start 203.297536 -227.91674)
					(mid 202.644756 -227.91674)
					(end 203.297536 -227.91674)
				)
			)
		)
	)
	(zone
		(layers "B.Cu" "In13.Cu" "In15.Cu")
		(hatch none 0.5)
		(connect_pads
			(clearance 0)
		)
		(min_thickness 0.25)
		(keepout
			(tracks not_allowed)
			(vias allowed)
			(pads allowed)
			(copperpour not_allowed)
			(footprints allowed)
		)
		(placement
			(enabled no)
			(sheetname "")
		)
		(fill yes
			(thermal_gap 0.5)
			(thermal_bridge_width 0.5)
			(island_removal_mode 0)
		)
		(polygon
			(pts
				(arc
					(start 87.641684 -284.847538)
					(mid 86.988904 -284.847538)
					(end 87.641684 -284.847538)
				)
			)
		)
	)
	(zone
		(layers "B.Cu" "In13.Cu" "In15.Cu")
		(hatch none 0.5)
		(connect_pads
			(clearance 0)
		)
		(min_thickness 0.25)
		(keepout
			(tracks not_allowed)
			(vias allowed)
			(pads allowed)
			(copperpour not_allowed)
			(footprints allowed)
		)
		(placement
			(enabled no)
			(sheetname "")
		)
		(fill yes
			(thermal_gap 0.5)
			(thermal_bridge_width 0.5)
			(island_removal_mode 0)
		)
		(polygon
			(pts
				(arc
					(start 372.234206 -262.058658)
					(mid 371.581426 -262.058658)
					(end 372.234206 -262.058658)
				)
			)
		)
	)
	(zone
		(layers "B.Cu" "In13.Cu" "In15.Cu")
		(hatch none 0.5)
		(connect_pads
			(clearance 0)
		)
		(min_thickness 0.25)
		(keepout
			(tracks not_allowed)
			(vias allowed)
			(pads allowed)
			(copperpour not_allowed)
			(footprints allowed)
		)
		(placement
			(enabled no)
			(sheetname "")
		)
		(fill yes
			(thermal_gap 0.5)
			(thermal_bridge_width 0.5)
			(island_removal_mode 0)
		)
		(polygon
			(pts
				(arc
					(start 348.269052 -277.522432)
					(mid 347.616272 -277.522432)
					(end 348.269052 -277.522432)
				)
			)
		)
	)
	(zone
		(layers "B.Cu" "In13.Cu" "In15.Cu")
		(hatch none 0.5)
		(connect_pads
			(clearance 0)
		)
		(min_thickness 0.25)
		(keepout
			(tracks not_allowed)
			(vias allowed)
			(pads allowed)
			(copperpour not_allowed)
			(footprints allowed)
		)
		(placement
			(enabled no)
			(sheetname "")
		)
		(fill yes
			(thermal_gap 0.5)
			(thermal_bridge_width 0.5)
			(island_removal_mode 0)
		)
		(polygon
			(pts
				(arc
					(start 125.123956 -247.178322)
					(mid 124.471176 -247.178322)
					(end 125.123956 -247.178322)
				)
			)
		)
	)
	(zone
		(layers "B.Cu" "In13.Cu" "In15.Cu")
		(hatch none 0.5)
		(connect_pads
			(clearance 0)
		)
		(min_thickness 0.25)
		(keepout
			(tracks not_allowed)
			(vias allowed)
			(pads allowed)
			(copperpour not_allowed)
			(footprints allowed)
		)
		(placement
			(enabled no)
			(sheetname "")
		)
		(fill yes
			(thermal_gap 0.5)
			(thermal_bridge_width 0.5)
			(island_removal_mode 0)
		)
		(polygon
			(pts
				(arc
					(start 355.787452 -275.8948)
					(mid 355.134672 -275.8948)
					(end 355.787452 -275.8948)
				)
			)
		)
	)
	(zone
		(layers "B.Cu" "In13.Cu" "In15.Cu")
		(hatch none 0.5)
		(connect_pads
			(clearance 0)
		)
		(min_thickness 0.25)
		(keepout
			(tracks not_allowed)
			(vias allowed)
			(pads allowed)
			(copperpour not_allowed)
			(footprints allowed)
		)
		(placement
			(enabled no)
			(sheetname "")
		)
		(fill yes
			(thermal_gap 0.5)
			(thermal_bridge_width 0.5)
			(island_removal_mode 0)
		)
		(polygon
			(pts
				(arc
					(start 348.269052 -264.50036)
					(mid 347.616272 -264.50036)
					(end 348.269052 -264.50036)
				)
			)
		)
	)
	(zone
		(layers "B.Cu" "In13.Cu" "In15.Cu")
		(hatch none 0.5)
		(connect_pads
			(clearance 0)
		)
		(min_thickness 0.25)
		(keepout
			(tracks not_allowed)
			(vias allowed)
			(pads allowed)
			(copperpour not_allowed)
			(footprints allowed)
		)
		(placement
			(enabled no)
			(sheetname "")
		)
		(fill yes
			(thermal_gap 0.5)
			(thermal_bridge_width 0.5)
			(island_removal_mode 0)
		)
		(polygon
			(pts
				(arc
					(start 203.297536 -272.966688)
					(mid 202.644756 -272.966688)
					(end 203.297536 -272.966688)
				)
			)
		)
	)
	(zone
		(layers "B.Cu" "In13.Cu" "In15.Cu")
		(hatch none 0.5)
		(connect_pads
			(clearance 0)
		)
		(min_thickness 0.25)
		(keepout
			(tracks not_allowed)
			(vias allowed)
			(pads allowed)
			(copperpour not_allowed)
			(footprints allowed)
		)
		(placement
			(enabled no)
			(sheetname "")
		)
		(fill yes
			(thermal_gap 0.5)
			(thermal_bridge_width 0.5)
			(island_removal_mode 0)
		)
		(polygon
			(pts
				(arc
					(start 366.485424 -221.133924)
					(mid 365.832644 -221.133924)
					(end 366.485424 -221.133924)
				)
			)
		)
	)
	(zone
		(layers "B.Cu" "In13.Cu" "In15.Cu")
		(hatch none 0.5)
		(connect_pads
			(clearance 0)
		)
		(min_thickness 0.25)
		(keepout
			(tracks not_allowed)
			(vias allowed)
			(pads allowed)
			(copperpour not_allowed)
			(footprints allowed)
		)
		(placement
			(enabled no)
			(sheetname "")
		)
		(fill yes
			(thermal_gap 0.5)
			(thermal_bridge_width 0.5)
			(island_removal_mode 0)
		)
		(polygon
			(pts
				(arc
					(start 128.883156 -245.55069)
					(mid 128.230376 -245.55069)
					(end 128.883156 -245.55069)
				)
			)
		)
	)
	(zone
		(layers "B.Cu" "In13.Cu" "In15.Cu")
		(hatch none 0.5)
		(connect_pads
			(clearance 0)
		)
		(min_thickness 0.25)
		(keepout
			(tracks not_allowed)
			(vias allowed)
			(pads allowed)
			(copperpour not_allowed)
			(footprints allowed)
		)
		(placement
			(enabled no)
			(sheetname "")
		)
		(fill yes
			(thermal_gap 0.5)
			(thermal_bridge_width 0.5)
			(island_removal_mode 0)
		)
		(polygon
			(pts
				(arc
					(start 52.293266 -4.962652)
					(mid 51.589686 -4.962652)
					(end 52.293266 -4.962652)
				)
			)
		)
	)
	(zone
		(layers "B.Cu" "In13.Cu" "In15.Cu")
		(hatch none 0.5)
		(connect_pads
			(clearance 0)
		)
		(min_thickness 0.25)
		(keepout
			(tracks not_allowed)
			(vias allowed)
			(pads allowed)
			(copperpour not_allowed)
			(footprints allowed)
		)
		(placement
			(enabled no)
			(sheetname "")
		)
		(fill yes
			(thermal_gap 0.5)
			(thermal_bridge_width 0.5)
			(island_removal_mode 0)
		)
		(polygon
			(pts
				(arc
					(start 374.003824 -232.528364)
					(mid 373.351044 -232.528364)
					(end 374.003824 -232.528364)
				)
			)
		)
	)
	(zone
		(layers "B.Cu" "In13.Cu" "In15.Cu")
		(hatch none 0.5)
		(connect_pads
			(clearance 0)
		)
		(min_thickness 0.25)
		(keepout
			(tracks not_allowed)
			(vias allowed)
			(pads allowed)
			(copperpour not_allowed)
			(footprints allowed)
		)
		(placement
			(enabled no)
			(sheetname "")
		)
		(fill yes
			(thermal_gap 0.5)
			(thermal_bridge_width 0.5)
			(island_removal_mode 0)
		)
		(polygon
			(pts
				(arc
					(start 348.269052 -262.872474)
					(mid 347.616272 -262.872474)
					(end 348.269052 -262.872474)
				)
			)
		)
	)
	(zone
		(layers "B.Cu" "In13.Cu" "In15.Cu")
		(hatch none 0.5)
		(connect_pads
			(clearance 0)
		)
		(min_thickness 0.25)
		(keepout
			(tracks not_allowed)
			(vias allowed)
			(pads allowed)
			(copperpour not_allowed)
			(footprints allowed)
		)
		(placement
			(enabled no)
			(sheetname "")
		)
		(fill yes
			(thermal_gap 0.5)
			(thermal_bridge_width 0.5)
			(island_removal_mode 0)
		)
		(polygon
			(pts
				(arc
					(start 100.799138 -258.80314)
					(mid 100.146358 -258.80314)
					(end 100.799138 -258.80314)
				)
			)
		)
	)
	(zone
		(layers "B.Cu" "In13.Cu" "In15.Cu")
		(hatch none 0.5)
		(connect_pads
			(clearance 0)
		)
		(min_thickness 0.25)
		(keepout
			(tracks not_allowed)
			(vias allowed)
			(pads allowed)
			(copperpour not_allowed)
			(footprints allowed)
		)
		(placement
			(enabled no)
			(sheetname "")
		)
		(fill yes
			(thermal_gap 0.5)
			(thermal_bridge_width 0.5)
			(island_removal_mode 0)
		)
		(polygon
			(pts
				(arc
					(start 21.215604 -217.716608)
					(mid 20.562824 -217.716608)
					(end 21.215604 -217.716608)
				)
			)
		)
	)
	(zone
		(layers "B.Cu" "In13.Cu" "In15.Cu")
		(hatch none 0.5)
		(connect_pads
			(clearance 0)
		)
		(min_thickness 0.25)
		(keepout
			(tracks not_allowed)
			(vias allowed)
			(pads allowed)
			(copperpour not_allowed)
			(footprints allowed)
		)
		(placement
			(enabled no)
			(sheetname "")
		)
		(fill yes
			(thermal_gap 0.5)
			(thermal_bridge_width 0.5)
			(island_removal_mode 0)
		)
		(polygon
			(pts
				(arc
					(start 112.436402 -221.94774)
					(mid 111.783622 -221.94774)
					(end 112.436402 -221.94774)
				)
			)
		)
	)
	(zone
		(layers "B.Cu" "In13.Cu" "In15.Cu")
		(hatch none 0.5)
		(connect_pads
			(clearance 0)
		)
		(min_thickness 0.25)
		(keepout
			(tracks not_allowed)
			(vias allowed)
			(pads allowed)
			(copperpour not_allowed)
			(footprints allowed)
		)
		(placement
			(enabled no)
			(sheetname "")
		)
		(fill yes
			(thermal_gap 0.5)
			(thermal_bridge_width 0.5)
			(island_removal_mode 0)
		)
		(polygon
			(pts
				(arc
					(start 112.906556 -221.133924)
					(mid 112.253776 -221.133924)
					(end 112.906556 -221.133924)
				)
			)
		)
	)
	(zone
		(layers "B.Cu" "In13.Cu" "In15.Cu")
		(hatch none 0.5)
		(connect_pads
			(clearance 0)
		)
		(min_thickness 0.25)
		(keepout
			(tracks not_allowed)
			(vias allowed)
			(pads allowed)
			(copperpour not_allowed)
			(footprints allowed)
		)
		(placement
			(enabled no)
			(sheetname "")
		)
		(fill yes
			(thermal_gap 0.5)
			(thermal_bridge_width 0.5)
			(island_removal_mode 0)
		)
		(polygon
			(pts
				(arc
					(start 92.810838 -280.778204)
					(mid 92.158058 -280.778204)
					(end 92.810838 -280.778204)
				)
			)
		)
	)
	(zone
		(layers "B.Cu" "In13.Cu" "In15.Cu")
		(hatch none 0.5)
		(connect_pads
			(clearance 0)
		)
		(min_thickness 0.25)
		(keepout
			(tracks not_allowed)
			(vias allowed)
			(pads allowed)
			(copperpour not_allowed)
			(footprints allowed)
		)
		(placement
			(enabled no)
			(sheetname "")
		)
		(fill yes
			(thermal_gap 0.5)
			(thermal_bridge_width 0.5)
			(island_removal_mode 0)
		)
		(polygon
			(pts
				(arc
					(start 22.036786 -4.962652)
					(mid 21.333206 -4.962652)
					(end 22.036786 -4.962652)
				)
			)
		)
	)
	(zone
		(layers "B.Cu" "In13.Cu" "In15.Cu")
		(hatch none 0.5)
		(connect_pads
			(clearance 0)
		)
		(min_thickness 0.25)
		(keepout
			(tracks not_allowed)
			(vias allowed)
			(pads allowed)
			(copperpour not_allowed)
			(footprints allowed)
		)
		(placement
			(enabled no)
			(sheetname "")
		)
		(fill yes
			(thermal_gap 0.5)
			(thermal_bridge_width 0.5)
			(island_removal_mode 0)
		)
		(polygon
			(pts
				(arc
					(start 155.154884 -426.089826)
					(mid 154.345132 -426.089826)
					(end 155.154884 -426.089826)
				)
			)
		)
	)
	(zone
		(layers "B.Cu" "In13.Cu" "In15.Cu")
		(hatch none 0.5)
		(connect_pads
			(clearance 0)
		)
		(min_thickness 0.25)
		(keepout
			(tracks not_allowed)
			(vias allowed)
			(pads allowed)
			(copperpour not_allowed)
			(footprints allowed)
		)
		(placement
			(enabled no)
			(sheetname "")
		)
		(fill yes
			(thermal_gap 0.5)
			(thermal_bridge_width 0.5)
			(island_removal_mode 0)
		)
		(polygon
			(pts
				(arc
					(start 390.154922 -427.289976)
					(mid 389.34517 -427.289976)
					(end 390.154922 -427.289976)
				)
			)
		)
	)
	(zone
		(layers "B.Cu" "In13.Cu" "In15.Cu")
		(hatch none 0.5)
		(connect_pads
			(clearance 0)
		)
		(min_thickness 0.25)
		(keepout
			(tracks not_allowed)
			(vias allowed)
			(pads allowed)
			(copperpour not_allowed)
			(footprints allowed)
		)
		(placement
			(enabled no)
			(sheetname "")
		)
		(fill yes
			(thermal_gap 0.5)
			(thermal_bridge_width 0.5)
			(island_removal_mode 0)
		)
		(polygon
			(pts
				(arc
					(start 315.054996 -429.689768)
					(mid 314.245244 -429.689768)
					(end 315.054996 -429.689768)
				)
			)
		)
	)
	(zone
		(layers "B.Cu" "In13.Cu" "In15.Cu")
		(hatch none 0.5)
		(connect_pads
			(clearance 0)
		)
		(min_thickness 0.25)
		(keepout
			(tracks not_allowed)
			(vias allowed)
			(pads allowed)
			(copperpour not_allowed)
			(footprints allowed)
		)
		(placement
			(enabled no)
			(sheetname "")
		)
		(fill yes
			(thermal_gap 0.5)
			(thermal_bridge_width 0.5)
			(island_removal_mode 0)
		)
		(polygon
			(pts
				(arc
					(start 462.881472 -259.366766)
					(mid 462.228692 -259.366766)
					(end 462.881472 -259.366766)
				)
			)
		)
	)
	(zone
		(layers "B.Cu" "In13.Cu" "In15.Cu")
		(hatch none 0.5)
		(connect_pads
			(clearance 0)
		)
		(min_thickness 0.25)
		(keepout
			(tracks not_allowed)
			(vias allowed)
			(pads allowed)
			(copperpour not_allowed)
			(footprints allowed)
		)
		(placement
			(enabled no)
			(sheetname "")
		)
		(fill yes
			(thermal_gap 0.5)
			(thermal_bridge_width 0.5)
			(island_removal_mode 0)
		)
		(polygon
			(pts
				(arc
					(start 265.055604 -301.01667)
					(mid 264.402824 -301.01667)
					(end 265.055604 -301.01667)
				)
			)
		)
	)
	(zone
		(layers "B.Cu" "In13.Cu" "In15.Cu")
		(hatch none 0.5)
		(connect_pads
			(clearance 0)
		)
		(min_thickness 0.25)
		(keepout
			(tracks not_allowed)
			(vias allowed)
			(pads allowed)
			(copperpour not_allowed)
			(footprints allowed)
		)
		(placement
			(enabled no)
			(sheetname "")
		)
		(fill yes
			(thermal_gap 0.5)
			(thermal_bridge_width 0.5)
			(island_removal_mode 0)
		)
		(polygon
			(pts
				(arc
					(start 403.154896 -427.289976)
					(mid 402.345144 -427.289976)
					(end 403.154896 -427.289976)
				)
			)
		)
	)
	(zone
		(layers "B.Cu" "In13.Cu" "In15.Cu")
		(hatch none 0.5)
		(connect_pads
			(clearance 0)
		)
		(min_thickness 0.25)
		(keepout
			(tracks not_allowed)
			(vias allowed)
			(pads allowed)
			(copperpour not_allowed)
			(footprints allowed)
		)
		(placement
			(enabled no)
			(sheetname "")
		)
		(fill yes
			(thermal_gap 0.5)
			(thermal_bridge_width 0.5)
			(island_removal_mode 0)
		)
		(polygon
			(pts
				(arc
					(start 333.247238 -410.030168)
					(mid 332.543658 -410.030168)
					(end 333.247238 -410.030168)
				)
			)
		)
	)
	(zone
		(layers "B.Cu" "In13.Cu" "In15.Cu")
		(hatch none 0.5)
		(connect_pads
			(clearance 0)
		)
		(min_thickness 0.25)
		(keepout
			(tracks not_allowed)
			(vias allowed)
			(pads allowed)
			(copperpour not_allowed)
			(footprints allowed)
		)
		(placement
			(enabled no)
			(sheetname "")
		)
		(fill yes
			(thermal_gap 0.5)
			(thermal_bridge_width 0.5)
			(island_removal_mode 0)
		)
		(polygon
			(pts
				(arc
					(start 207.397604 -199.866758)
					(mid 206.744824 -199.866758)
					(end 207.397604 -199.866758)
				)
			)
		)
	)
	(zone
		(layers "B.Cu" "In13.Cu" "In15.Cu")
		(hatch none 0.5)
		(connect_pads
			(clearance 0)
		)
		(min_thickness 0.25)
		(keepout
			(tracks not_allowed)
			(vias allowed)
			(pads allowed)
			(copperpour not_allowed)
			(footprints allowed)
		)
		(placement
			(enabled no)
			(sheetname "")
		)
		(fill yes
			(thermal_gap 0.5)
			(thermal_bridge_width 0.5)
			(island_removal_mode 0)
		)
		(polygon
			(pts
				(arc
					(start 451.237604 -222.816674)
					(mid 450.584824 -222.816674)
					(end 451.237604 -222.816674)
				)
			)
		)
	)
	(zone
		(layers "B.Cu" "In13.Cu" "In15.Cu")
		(hatch none 0.5)
		(connect_pads
			(clearance 0)
		)
		(min_thickness 0.25)
		(keepout
			(tracks not_allowed)
			(vias allowed)
			(pads allowed)
			(copperpour not_allowed)
			(footprints allowed)
		)
		(placement
			(enabled no)
			(sheetname "")
		)
		(fill yes
			(thermal_gap 0.5)
			(thermal_bridge_width 0.5)
			(island_removal_mode 0)
		)
		(polygon
			(pts
				(arc
					(start 124.294138 -265.314176)
					(mid 123.641358 -265.314176)
					(end 124.294138 -265.314176)
				)
			)
		)
	)
	(zone
		(layers "B.Cu" "In13.Cu" "In15.Cu")
		(hatch none 0.5)
		(connect_pads
			(clearance 0)
		)
		(min_thickness 0.25)
		(keepout
			(tracks not_allowed)
			(vias allowed)
			(pads allowed)
			(copperpour not_allowed)
			(footprints allowed)
		)
		(placement
			(enabled no)
			(sheetname "")
		)
		(fill yes
			(thermal_gap 0.5)
			(thermal_bridge_width 0.5)
			(island_removal_mode 0)
		)
		(polygon
			(pts
				(arc
					(start 100.689156 -234.15625)
					(mid 100.036376 -234.15625)
					(end 100.689156 -234.15625)
				)
			)
		)
	)
	(zone
		(layers "B.Cu" "In13.Cu" "In15.Cu")
		(hatch none 0.5)
		(connect_pads
			(clearance 0)
		)
		(min_thickness 0.25)
		(keepout
			(tracks not_allowed)
			(vias allowed)
			(pads allowed)
			(copperpour not_allowed)
			(footprints allowed)
		)
		(placement
			(enabled no)
			(sheetname "")
		)
		(fill yes
			(thermal_gap 0.5)
			(thermal_bridge_width 0.5)
			(island_removal_mode 0)
		)
		(polygon
			(pts
				(arc
					(start 147.1549 -426.089826)
					(mid 146.345148 -426.089826)
					(end 147.1549 -426.089826)
				)
			)
		)
	)
	(zone
		(layers "B.Cu" "In13.Cu" "In15.Cu")
		(hatch none 0.5)
		(connect_pads
			(clearance 0)
		)
		(min_thickness 0.25)
		(keepout
			(tracks not_allowed)
			(vias allowed)
			(pads allowed)
			(copperpour not_allowed)
			(footprints allowed)
		)
		(placement
			(enabled no)
			(sheetname "")
		)
		(fill yes
			(thermal_gap 0.5)
			(thermal_bridge_width 0.5)
			(island_removal_mode 0)
		)
		(polygon
			(pts
				(arc
					(start 351.626678 -410.030168)
					(mid 350.923098 -410.030168)
					(end 351.626678 -410.030168)
				)
			)
		)
	)
	(zone
		(layers "B.Cu" "In13.Cu" "In15.Cu")
		(hatch none 0.5)
		(connect_pads
			(clearance 0)
		)
		(min_thickness 0.25)
		(keepout
			(tracks not_allowed)
			(vias allowed)
			(pads allowed)
			(copperpour not_allowed)
			(footprints allowed)
		)
		(placement
			(enabled no)
			(sheetname "")
		)
		(fill yes
			(thermal_gap 0.5)
			(thermal_bridge_width 0.5)
			(island_removal_mode 0)
		)
		(polygon
			(pts
				(arc
					(start 348.15907 -231.714548)
					(mid 347.50629 -231.714548)
					(end 348.15907 -231.714548)
				)
			)
		)
	)
	(zone
		(layers "B.Cu" "In13.Cu" "In15.Cu")
		(hatch none 0.5)
		(connect_pads
			(clearance 0)
		)
		(min_thickness 0.25)
		(keepout
			(tracks not_allowed)
			(vias allowed)
			(pads allowed)
			(copperpour not_allowed)
			(footprints allowed)
		)
		(placement
			(enabled no)
			(sheetname "")
		)
		(fill yes
			(thermal_gap 0.5)
			(thermal_bridge_width 0.5)
			(island_removal_mode 0)
		)
		(polygon
			(pts
				(arc
					(start 372.234206 -270.19758)
					(mid 371.581426 -270.19758)
					(end 372.234206 -270.19758)
				)
			)
		)
	)
	(zone
		(layers "B.Cu" "In13.Cu" "In15.Cu")
		(hatch none 0.5)
		(connect_pads
			(clearance 0)
		)
		(min_thickness 0.25)
		(keepout
			(tracks not_allowed)
			(vias allowed)
			(pads allowed)
			(copperpour not_allowed)
			(footprints allowed)
		)
		(placement
			(enabled no)
			(sheetname "")
		)
		(fill yes
			(thermal_gap 0.5)
			(thermal_bridge_width 0.5)
			(island_removal_mode 0)
		)
		(polygon
			(pts
				(arc
					(start 348.629224 -240.667286)
					(mid 347.976444 -240.667286)
					(end 348.629224 -240.667286)
				)
			)
		)
	)
	(zone
		(layers "B.Cu" "In13.Cu" "In15.Cu")
		(hatch none 0.5)
		(connect_pads
			(clearance 0)
		)
		(min_thickness 0.25)
		(keepout
			(tracks not_allowed)
			(vias allowed)
			(pads allowed)
			(copperpour not_allowed)
			(footprints allowed)
		)
		(placement
			(enabled no)
			(sheetname "")
		)
		(fill yes
			(thermal_gap 0.5)
			(thermal_bridge_width 0.5)
			(island_removal_mode 0)
		)
		(polygon
			(pts
				(arc
					(start 98.919538 -278.336502)
					(mid 98.266758 -278.336502)
					(end 98.919538 -278.336502)
				)
			)
		)
	)
	(zone
		(layers "B.Cu" "In13.Cu" "In15.Cu")
		(hatch none 0.5)
		(connect_pads
			(clearance 0)
		)
		(min_thickness 0.25)
		(keepout
			(tracks not_allowed)
			(vias allowed)
			(pads allowed)
			(copperpour not_allowed)
			(footprints allowed)
		)
		(placement
			(enabled no)
			(sheetname "")
		)
		(fill yes
			(thermal_gap 0.5)
			(thermal_bridge_width 0.5)
			(island_removal_mode 0)
		)
		(polygon
			(pts
				(arc
					(start 451.237604 -284.866588)
					(mid 450.584824 -284.866588)
					(end 451.237604 -284.866588)
				)
			)
		)
	)
	(zone
		(layers "B.Cu" "In13.Cu" "In15.Cu")
		(hatch none 0.5)
		(connect_pads
			(clearance 0)
		)
		(min_thickness 0.25)
		(keepout
			(tracks not_allowed)
			(vias allowed)
			(pads allowed)
			(copperpour not_allowed)
			(footprints allowed)
		)
		(placement
			(enabled no)
			(sheetname "")
		)
		(fill yes
			(thermal_gap 0.5)
			(thermal_bridge_width 0.5)
			(island_removal_mode 0)
		)
		(polygon
			(pts
				(arc
					(start 356.147624 -221.133924)
					(mid 355.494844 -221.133924)
					(end 356.147624 -221.133924)
				)
			)
		)
	)
	(zone
		(layers "B.Cu" "In13.Cu" "In15.Cu")
		(hatch none 0.5)
		(connect_pads
			(clearance 0)
		)
		(min_thickness 0.25)
		(keepout
			(tracks not_allowed)
			(vias allowed)
			(pads allowed)
			(copperpour not_allowed)
			(footprints allowed)
		)
		(placement
			(enabled no)
			(sheetname "")
		)
		(fill yes
			(thermal_gap 0.5)
			(thermal_bridge_width 0.5)
			(island_removal_mode 0)
		)
		(polygon
			(pts
				(arc
					(start 98.339402 -239.853216)
					(mid 97.686622 -239.853216)
					(end 98.339402 -239.853216)
				)
			)
		)
	)
	(zone
		(layers "B.Cu" "In13.Cu" "In15.Cu")
		(hatch none 0.5)
		(connect_pads
			(clearance 0)
		)
		(min_thickness 0.25)
		(keepout
			(tracks not_allowed)
			(vias allowed)
			(pads allowed)
			(copperpour not_allowed)
			(footprints allowed)
		)
		(placement
			(enabled no)
			(sheetname "")
		)
		(fill yes
			(thermal_gap 0.5)
			(thermal_bridge_width 0.5)
			(island_removal_mode 0)
		)
		(polygon
			(pts
				(arc
					(start 455.337672 -246.616728)
					(mid 454.684892 -246.616728)
					(end 455.337672 -246.616728)
				)
			)
		)
	)
	(zone
		(layers "B.Cu" "In13.Cu" "In15.Cu")
		(hatch none 0.5)
		(connect_pads
			(clearance 0)
		)
		(min_thickness 0.25)
		(keepout
			(tracks not_allowed)
			(vias allowed)
			(pads allowed)
			(copperpour not_allowed)
			(footprints allowed)
		)
		(placement
			(enabled no)
			(sheetname "")
		)
		(fill yes
			(thermal_gap 0.5)
			(thermal_bridge_width 0.5)
			(island_removal_mode 0)
		)
		(polygon
			(pts
				(arc
					(start 87.171784 -287.28924)
					(mid 86.519004 -287.28924)
					(end 87.171784 -287.28924)
				)
			)
		)
	)
	(zone
		(layers "B.Cu" "In13.Cu" "In15.Cu")
		(hatch none 0.5)
		(connect_pads
			(clearance 0)
		)
		(min_thickness 0.25)
		(keepout
			(tracks not_allowed)
			(vias allowed)
			(pads allowed)
			(copperpour not_allowed)
			(footprints allowed)
		)
		(placement
			(enabled no)
			(sheetname "")
		)
		(fill yes
			(thermal_gap 0.5)
			(thermal_bridge_width 0.5)
			(island_removal_mode 0)
		)
		(polygon
			(pts
				(arc
					(start 358.027224 -221.133924)
					(mid 357.374444 -221.133924)
					(end 358.027224 -221.133924)
				)
			)
		)
	)
	(zone
		(layers "B.Cu" "In13.Cu" "In15.Cu")
		(hatch none 0.5)
		(connect_pads
			(clearance 0)
		)
		(min_thickness 0.25)
		(keepout
			(tracks not_allowed)
			(vias allowed)
			(pads allowed)
			(copperpour not_allowed)
			(footprints allowed)
		)
		(placement
			(enabled no)
			(sheetname "")
		)
		(fill yes
			(thermal_gap 0.5)
			(thermal_bridge_width 0.5)
			(island_removal_mode 0)
		)
		(polygon
			(pts
				(arc
					(start 339.373718 -410.030168)
					(mid 338.670138 -410.030168)
					(end 339.373718 -410.030168)
				)
			)
		)
	)
	(zone
		(layers "B.Cu" "In13.Cu" "In15.Cu")
		(hatch none 0.5)
		(connect_pads
			(clearance 0)
		)
		(min_thickness 0.25)
		(keepout
			(tracks not_allowed)
			(vias allowed)
			(pads allowed)
			(copperpour not_allowed)
			(footprints allowed)
		)
		(placement
			(enabled no)
			(sheetname "")
		)
		(fill yes
			(thermal_gap 0.5)
			(thermal_bridge_width 0.5)
			(island_removal_mode 0)
		)
		(polygon
			(pts
				(arc
					(start 269.155672 -273.816572)
					(mid 268.502892 -273.816572)
					(end 269.155672 -273.816572)
				)
			)
		)
	)
	(zone
		(layers "B.Cu" "In13.Cu" "In15.Cu")
		(hatch none 0.5)
		(connect_pads
			(clearance 0)
		)
		(min_thickness 0.25)
		(keepout
			(tracks not_allowed)
			(vias allowed)
			(pads allowed)
			(copperpour not_allowed)
			(footprints allowed)
		)
		(placement
			(enabled no)
			(sheetname "")
		)
		(fill yes
			(thermal_gap 0.5)
			(thermal_bridge_width 0.5)
			(island_removal_mode 0)
		)
		(polygon
			(pts
				(arc
					(start 126.633224 -403.883876)
					(mid 125.929644 -403.883876)
					(end 126.633224 -403.883876)
				)
			)
		)
	)
	(zone
		(layers "B.Cu" "In13.Cu" "In15.Cu")
		(hatch none 0.5)
		(connect_pads
			(clearance 0)
		)
		(min_thickness 0.25)
		(keepout
			(tracks not_allowed)
			(vias allowed)
			(pads allowed)
			(copperpour not_allowed)
			(footprints allowed)
		)
		(placement
			(enabled no)
			(sheetname "")
		)
		(fill yes
			(thermal_gap 0.5)
			(thermal_bridge_width 0.5)
			(island_removal_mode 0)
		)
		(polygon
			(pts
				(arc
					(start 373.064024 -239.0394)
					(mid 372.411244 -239.0394)
					(end 373.064024 -239.0394)
				)
			)
		)
	)
	(zone
		(layers "B.Cu" "In13.Cu" "In15.Cu")
		(hatch none 0.5)
		(connect_pads
			(clearance 0)
		)
		(min_thickness 0.25)
		(keepout
			(tracks not_allowed)
			(vias allowed)
			(pads allowed)
			(copperpour not_allowed)
			(footprints allowed)
		)
		(placement
			(enabled no)
			(sheetname "")
		)
		(fill yes
			(thermal_gap 0.5)
			(thermal_bridge_width 0.5)
			(island_removal_mode 0)
		)
		(polygon
			(pts
				(arc
					(start 99.279202 -249.620024)
					(mid 98.626422 -249.620024)
					(end 99.279202 -249.620024)
				)
			)
		)
	)
	(zone
		(layers "B.Cu" "In13.Cu" "In15.Cu")
		(hatch none 0.5)
		(connect_pads
			(clearance 0)
		)
		(min_thickness 0.25)
		(keepout
			(tracks not_allowed)
			(vias allowed)
			(pads allowed)
			(copperpour not_allowed)
			(footprints allowed)
		)
		(placement
			(enabled no)
			(sheetname "")
		)
		(fill yes
			(thermal_gap 0.5)
			(thermal_bridge_width 0.5)
			(island_removal_mode 0)
		)
		(polygon
			(pts
				(arc
					(start 265.055604 -297.616626)
					(mid 264.402824 -297.616626)
					(end 265.055604 -297.616626)
				)
			)
		)
	)
	(zone
		(layers "B.Cu" "In13.Cu" "In15.Cu")
		(hatch none 0.5)
		(connect_pads
			(clearance 0)
		)
		(min_thickness 0.25)
		(keepout
			(tracks not_allowed)
			(vias allowed)
			(pads allowed)
			(copperpour not_allowed)
			(footprints allowed)
		)
		(placement
			(enabled no)
			(sheetname "")
		)
		(fill yes
			(thermal_gap 0.5)
			(thermal_bridge_width 0.5)
			(island_removal_mode 0)
		)
		(polygon
			(pts
				(arc
					(start 59.055 -429.689768)
					(mid 58.245248 -429.689768)
					(end 59.055 -429.689768)
				)
			)
		)
	)
	(zone
		(layers "B.Cu" "In13.Cu" "In15.Cu")
		(hatch none 0.5)
		(connect_pads
			(clearance 0)
		)
		(min_thickness 0.25)
		(keepout
			(tracks not_allowed)
			(vias allowed)
			(pads allowed)
			(copperpour not_allowed)
			(footprints allowed)
		)
		(placement
			(enabled no)
			(sheetname "")
		)
		(fill yes
			(thermal_gap 0.5)
			(thermal_bridge_width 0.5)
			(island_removal_mode 0)
		)
		(polygon
			(pts
				(arc
					(start 117.135402 -220.319854)
					(mid 116.482622 -220.319854)
					(end 117.135402 -220.319854)
				)
			)
		)
	)
	(zone
		(layers "B.Cu" "In13.Cu" "In15.Cu")
		(hatch none 0.5)
		(connect_pads
			(clearance 0)
		)
		(min_thickness 0.25)
		(keepout
			(tracks not_allowed)
			(vias allowed)
			(pads allowed)
			(copperpour not_allowed)
			(footprints allowed)
		)
		(placement
			(enabled no)
			(sheetname "")
		)
		(fill yes
			(thermal_gap 0.5)
			(thermal_bridge_width 0.5)
			(island_removal_mode 0)
		)
		(polygon
			(pts
				(arc
					(start 21.215604 -265.316716)
					(mid 20.562824 -265.316716)
					(end 21.215604 -265.316716)
				)
			)
		)
	)
	(zone
		(layers "B.Cu" "In13.Cu" "In15.Cu")
		(hatch none 0.5)
		(connect_pads
			(clearance 0)
		)
		(min_thickness 0.25)
		(keepout
			(tracks not_allowed)
			(vias allowed)
			(pads allowed)
			(copperpour not_allowed)
			(footprints allowed)
		)
		(placement
			(enabled no)
			(sheetname "")
		)
		(fill yes
			(thermal_gap 0.5)
			(thermal_bridge_width 0.5)
			(island_removal_mode 0)
		)
		(polygon
			(pts
				(arc
					(start 97.399602 -247.992138)
					(mid 96.746822 -247.992138)
					(end 97.399602 -247.992138)
				)
			)
		)
	)
	(zone
		(layers "B.Cu" "In13.Cu" "In15.Cu")
		(hatch none 0.5)
		(connect_pads
			(clearance 0)
		)
		(min_thickness 0.25)
		(keepout
			(tracks not_allowed)
			(vias allowed)
			(pads allowed)
			(copperpour not_allowed)
			(footprints allowed)
		)
		(placement
			(enabled no)
			(sheetname "")
		)
		(fill yes
			(thermal_gap 0.5)
			(thermal_bridge_width 0.5)
			(island_removal_mode 0)
		)
		(polygon
			(pts
				(arc
					(start 373.174006 -273.453098)
					(mid 372.521226 -273.453098)
					(end 373.174006 -273.453098)
				)
			)
		)
	)
	(zone
		(layers "B.Cu" "In13.Cu" "In15.Cu")
		(hatch none 0.5)
		(connect_pads
			(clearance 0)
		)
		(min_thickness 0.25)
		(keepout
			(tracks not_allowed)
			(vias allowed)
			(pads allowed)
			(copperpour not_allowed)
			(footprints allowed)
		)
		(placement
			(enabled no)
			(sheetname "")
		)
		(fill yes
			(thermal_gap 0.5)
			(thermal_bridge_width 0.5)
			(island_removal_mode 0)
		)
		(polygon
			(pts
				(arc
					(start 100.219002 -241.481102)
					(mid 99.566222 -241.481102)
					(end 100.219002 -241.481102)
				)
			)
		)
	)
	(zone
		(layers "B.Cu" "In13.Cu" "In15.Cu")
		(hatch none 0.5)
		(connect_pads
			(clearance 0)
		)
		(min_thickness 0.25)
		(keepout
			(tracks not_allowed)
			(vias allowed)
			(pads allowed)
			(copperpour not_allowed)
			(footprints allowed)
		)
		(placement
			(enabled no)
			(sheetname "")
		)
		(fill yes
			(thermal_gap 0.5)
			(thermal_bridge_width 0.5)
			(island_removal_mode 0)
		)
		(polygon
			(pts
				(arc
					(start 337.174078 -410.030168)
					(mid 336.470498 -410.030168)
					(end 337.174078 -410.030168)
				)
			)
		)
	)
	(zone
		(layers "B.Cu" "In13.Cu" "In15.Cu")
		(hatch none 0.5)
		(connect_pads
			(clearance 0)
		)
		(min_thickness 0.25)
		(keepout
			(tracks not_allowed)
			(vias allowed)
			(pads allowed)
			(copperpour not_allowed)
			(footprints allowed)
		)
		(placement
			(enabled no)
			(sheetname "")
		)
		(fill yes
			(thermal_gap 0.5)
			(thermal_bridge_width 0.5)
			(island_removal_mode 0)
		)
		(polygon
			(pts
				(arc
					(start 21.215604 -292.516814)
					(mid 20.562824 -292.516814)
					(end 21.215604 -292.516814)
				)
			)
		)
	)
	(zone
		(layers "B.Cu" "In13.Cu" "In15.Cu")
		(hatch none 0.5)
		(connect_pads
			(clearance 0)
		)
		(min_thickness 0.25)
		(keepout
			(tracks not_allowed)
			(vias allowed)
			(pads allowed)
			(copperpour not_allowed)
			(footprints allowed)
		)
		(placement
			(enabled no)
			(sheetname "")
		)
		(fill yes
			(thermal_gap 0.5)
			(thermal_bridge_width 0.5)
			(island_removal_mode 0)
		)
		(polygon
			(pts
				(arc
					(start 61.448188 -403.883876)
					(mid 60.744608 -403.883876)
					(end 61.448188 -403.883876)
				)
			)
		)
	)
	(zone
		(layers "B.Cu" "In13.Cu" "In15.Cu")
		(hatch none 0.5)
		(connect_pads
			(clearance 0)
		)
		(min_thickness 0.25)
		(keepout
			(tracks not_allowed)
			(vias allowed)
			(pads allowed)
			(copperpour not_allowed)
			(footprints allowed)
		)
		(placement
			(enabled no)
			(sheetname "")
		)
		(fill yes
			(thermal_gap 0.5)
			(thermal_bridge_width 0.5)
			(island_removal_mode 0)
		)
		(polygon
			(pts
				(arc
					(start 157.265624 -403.883876)
					(mid 156.562044 -403.883876)
					(end 157.265624 -403.883876)
				)
			)
		)
	)
	(zone
		(layers "B.Cu" "In13.Cu" "In15.Cu")
		(hatch none 0.5)
		(connect_pads
			(clearance 0)
		)
		(min_thickness 0.25)
		(keepout
			(tracks not_allowed)
			(vias allowed)
			(pads allowed)
			(copperpour not_allowed)
			(footprints allowed)
		)
		(placement
			(enabled no)
			(sheetname "")
		)
		(fill yes
			(thermal_gap 0.5)
			(thermal_bridge_width 0.5)
			(island_removal_mode 0)
		)
		(polygon
			(pts
				(arc
					(start 269.155672 -265.316716)
					(mid 268.502892 -265.316716)
					(end 269.155672 -265.316716)
				)
			)
		)
	)
	(zone
		(layers "B.Cu" "In13.Cu" "In15.Cu")
		(hatch none 0.5)
		(connect_pads
			(clearance 0)
		)
		(min_thickness 0.25)
		(keepout
			(tracks not_allowed)
			(vias allowed)
			(pads allowed)
			(copperpour not_allowed)
			(footprints allowed)
		)
		(placement
			(enabled no)
			(sheetname "")
		)
		(fill yes
			(thermal_gap 0.5)
			(thermal_bridge_width 0.5)
			(island_removal_mode 0)
		)
		(polygon
			(pts
				(arc
					(start 265.055604 -232.166668)
					(mid 264.402824 -232.166668)
					(end 265.055604 -232.166668)
				)
			)
		)
	)
	(zone
		(layers "B.Cu" "In13.Cu" "In15.Cu")
		(hatch none 0.5)
		(connect_pads
			(clearance 0)
		)
		(min_thickness 0.25)
		(keepout
			(tracks not_allowed)
			(vias allowed)
			(pads allowed)
			(copperpour not_allowed)
			(footprints allowed)
		)
		(placement
			(enabled no)
			(sheetname "")
		)
		(fill yes
			(thermal_gap 0.5)
			(thermal_bridge_width 0.5)
			(island_removal_mode 0)
		)
		(polygon
			(pts
				(arc
					(start 157.15488 -427.089824)
					(mid 156.345128 -427.089824)
					(end 157.15488 -427.089824)
				)
			)
		)
	)
	(zone
		(layers "B.Cu" "In13.Cu" "In15.Cu")
		(hatch none 0.5)
		(connect_pads
			(clearance 0)
		)
		(min_thickness 0.25)
		(keepout
			(tracks not_allowed)
			(vias allowed)
			(pads allowed)
			(copperpour not_allowed)
			(footprints allowed)
		)
		(placement
			(enabled no)
			(sheetname "")
		)
		(fill yes
			(thermal_gap 0.5)
			(thermal_bridge_width 0.5)
			(island_removal_mode 0)
		)
		(polygon
			(pts
				(arc
					(start 451.237604 -221.116652)
					(mid 450.584824 -221.116652)
					(end 451.237604 -221.116652)
				)
			)
		)
	)
	(zone
		(layers "B.Cu" "In13.Cu" "In15.Cu")
		(hatch none 0.5)
		(connect_pads
			(clearance 0)
		)
		(min_thickness 0.25)
		(keepout
			(tracks not_allowed)
			(vias allowed)
			(pads allowed)
			(copperpour not_allowed)
			(footprints allowed)
		)
		(placement
			(enabled no)
			(sheetname "")
		)
		(fill yes
			(thermal_gap 0.5)
			(thermal_bridge_width 0.5)
			(island_removal_mode 0)
		)
		(polygon
			(pts
				(arc
					(start 411.15488 -427.289976)
					(mid 410.345128 -427.289976)
					(end 411.15488 -427.289976)
				)
			)
		)
	)
	(zone
		(layers "B.Cu" "In13.Cu" "In15.Cu")
		(hatch none 0.5)
		(connect_pads
			(clearance 0)
		)
		(min_thickness 0.25)
		(keepout
			(tracks not_allowed)
			(vias allowed)
			(pads allowed)
			(copperpour not_allowed)
			(footprints allowed)
		)
		(placement
			(enabled no)
			(sheetname "")
		)
		(fill yes
			(thermal_gap 0.5)
			(thermal_bridge_width 0.5)
			(island_removal_mode 0)
		)
		(polygon
			(pts
				(arc
					(start 129.696464 -403.883876)
					(mid 128.992884 -403.883876)
					(end 129.696464 -403.883876)
				)
			)
		)
	)
	(zone
		(layers "B.Cu" "In13.Cu" "In15.Cu")
		(hatch none 0.5)
		(connect_pads
			(clearance 0)
		)
		(min_thickness 0.25)
		(keepout
			(tracks not_allowed)
			(vias allowed)
			(pads allowed)
			(copperpour not_allowed)
			(footprints allowed)
		)
		(placement
			(enabled no)
			(sheetname "")
		)
		(fill yes
			(thermal_gap 0.5)
			(thermal_bridge_width 0.5)
			(island_removal_mode 0)
		)
		(polygon
			(pts
				(arc
					(start 336.051652 -282.405836)
					(mid 335.398872 -282.405836)
					(end 336.051652 -282.405836)
				)
			)
		)
	)
	(zone
		(layers "B.Cu" "In13.Cu" "In15.Cu")
		(hatch none 0.5)
		(connect_pads
			(clearance 0)
		)
		(min_thickness 0.25)
		(keepout
			(tracks not_allowed)
			(vias allowed)
			(pads allowed)
			(copperpour not_allowed)
			(footprints allowed)
		)
		(placement
			(enabled no)
			(sheetname "")
		)
		(fill yes
			(thermal_gap 0.5)
			(thermal_bridge_width 0.5)
			(island_removal_mode 0)
		)
		(polygon
			(pts
				(arc
					(start 203.297536 -289.966654)
					(mid 202.644756 -289.966654)
					(end 203.297536 -289.966654)
				)
			)
		)
	)
	(zone
		(layers "B.Cu" "In13.Cu" "In15.Cu")
		(hatch none 0.5)
		(connect_pads
			(clearance 0)
		)
		(min_thickness 0.25)
		(keepout
			(tracks not_allowed)
			(vias allowed)
			(pads allowed)
			(copperpour not_allowed)
			(footprints allowed)
		)
		(placement
			(enabled no)
			(sheetname "")
		)
		(fill yes
			(thermal_gap 0.5)
			(thermal_bridge_width 0.5)
			(island_removal_mode 0)
		)
		(polygon
			(pts
				(arc
					(start 373.174006 -271.825212)
					(mid 372.521226 -271.825212)
					(end 373.174006 -271.825212)
				)
			)
		)
	)
	(zone
		(layers "B.Cu" "In13.Cu" "In15.Cu")
		(hatch none 0.5)
		(connect_pads
			(clearance 0)
		)
		(min_thickness 0.25)
		(keepout
			(tracks not_allowed)
			(vias allowed)
			(pads allowed)
			(copperpour not_allowed)
			(footprints allowed)
		)
		(placement
			(enabled no)
			(sheetname "")
		)
		(fill yes
			(thermal_gap 0.5)
			(thermal_bridge_width 0.5)
			(island_removal_mode 0)
		)
		(polygon
			(pts
				(arc
					(start 203.297536 -226.216718)
					(mid 202.644756 -226.216718)
					(end 203.297536 -226.216718)
				)
			)
		)
	)
	(zone
		(layers "B.Cu" "In13.Cu" "In15.Cu")
		(hatch none 0.5)
		(connect_pads
			(clearance 0)
		)
		(min_thickness 0.25)
		(keepout
			(tracks not_allowed)
			(vias allowed)
			(pads allowed)
			(copperpour not_allowed)
			(footprints allowed)
		)
		(placement
			(enabled no)
			(sheetname "")
		)
		(fill yes
			(thermal_gap 0.5)
			(thermal_bridge_width 0.5)
			(island_removal_mode 0)
		)
		(polygon
			(pts
				(arc
					(start 203.297536 -271.266666)
					(mid 202.644756 -271.266666)
					(end 203.297536 -271.266666)
				)
			)
		)
	)
	(zone
		(layers "B.Cu" "In13.Cu" "In15.Cu")
		(hatch none 0.5)
		(connect_pads
			(clearance 0)
		)
		(min_thickness 0.25)
		(keepout
			(tracks not_allowed)
			(vias allowed)
			(pads allowed)
			(copperpour not_allowed)
			(footprints allowed)
		)
		(placement
			(enabled no)
			(sheetname "")
		)
		(fill yes
			(thermal_gap 0.5)
			(thermal_bridge_width 0.5)
			(island_removal_mode 0)
		)
		(polygon
			(pts
				(arc
					(start 100.328984 -269.38351)
					(mid 99.676204 -269.38351)
					(end 100.328984 -269.38351)
				)
			)
		)
	)
	(zone
		(layers "B.Cu" "In13.Cu" "In15.Cu")
		(hatch none 0.5)
		(connect_pads
			(clearance 0)
		)
		(min_thickness 0.25)
		(keepout
			(tracks not_allowed)
			(vias allowed)
			(pads allowed)
			(copperpour not_allowed)
			(footprints allowed)
		)
		(placement
			(enabled no)
			(sheetname "")
		)
		(fill yes
			(thermal_gap 0.5)
			(thermal_bridge_width 0.5)
			(island_removal_mode 0)
		)
		(polygon
			(pts
				(arc
					(start 406.480772 -4.95173)
					(mid 405.777192 -4.95173)
					(end 406.480772 -4.95173)
				)
			)
		)
	)
	(zone
		(layers "B.Cu" "In13.Cu" "In15.Cu")
		(hatch none 0.5)
		(connect_pads
			(clearance 0)
		)
		(min_thickness 0.25)
		(keepout
			(tracks not_allowed)
			(vias allowed)
			(pads allowed)
			(copperpour not_allowed)
			(footprints allowed)
		)
		(placement
			(enabled no)
			(sheetname "")
		)
		(fill yes
			(thermal_gap 0.5)
			(thermal_bridge_width 0.5)
			(island_removal_mode 0)
		)
		(polygon
			(pts
				(arc
					(start 207.321404 -267.016738)
					(mid 206.668624 -267.016738)
					(end 207.321404 -267.016738)
				)
			)
		)
	)
	(zone
		(layers "B.Cu" "In13.Cu" "In15.Cu")
		(hatch none 0.5)
		(connect_pads
			(clearance 0)
		)
		(min_thickness 0.25)
		(keepout
			(tracks not_allowed)
			(vias allowed)
			(pads allowed)
			(copperpour not_allowed)
			(footprints allowed)
		)
		(placement
			(enabled no)
			(sheetname "")
		)
		(fill yes
			(thermal_gap 0.5)
			(thermal_bridge_width 0.5)
			(island_removal_mode 0)
		)
		(polygon
			(pts
				(arc
					(start 17.115536 -259.366766)
					(mid 16.462756 -259.366766)
					(end 17.115536 -259.366766)
				)
			)
		)
	)
	(zone
		(layers "B.Cu" "In13.Cu" "In15.Cu")
		(hatch none 0.5)
		(connect_pads
			(clearance 0)
		)
		(min_thickness 0.25)
		(keepout
			(tracks not_allowed)
			(vias allowed)
			(pads allowed)
			(copperpour not_allowed)
			(footprints allowed)
		)
		(placement
			(enabled no)
			(sheetname "")
		)
		(fill yes
			(thermal_gap 0.5)
			(thermal_bridge_width 0.5)
			(island_removal_mode 0)
		)
		(polygon
			(pts
				(arc
					(start 100.689156 -229.272846)
					(mid 100.036376 -229.272846)
					(end 100.689156 -229.272846)
				)
			)
		)
	)
	(zone
		(layers "B.Cu" "In13.Cu" "In15.Cu")
		(hatch none 0.5)
		(connect_pads
			(clearance 0)
		)
		(min_thickness 0.25)
		(keepout
			(tracks not_allowed)
			(vias allowed)
			(pads allowed)
			(copperpour not_allowed)
			(footprints allowed)
		)
		(placement
			(enabled no)
			(sheetname "")
		)
		(fill yes
			(thermal_gap 0.5)
			(thermal_bridge_width 0.5)
			(island_removal_mode 0)
		)
		(polygon
			(pts
				(arc
					(start 455.337672 -217.716608)
					(mid 454.684892 -217.716608)
					(end 455.337672 -217.716608)
				)
			)
		)
	)
	(zone
		(layers "B.Cu" "In13.Cu" "In15.Cu")
		(hatch none 0.5)
		(connect_pads
			(clearance 0)
		)
		(min_thickness 0.25)
		(keepout
			(tracks not_allowed)
			(vias allowed)
			(pads allowed)
			(copperpour not_allowed)
			(footprints allowed)
		)
		(placement
			(enabled no)
			(sheetname "")
		)
		(fill yes
			(thermal_gap 0.5)
			(thermal_bridge_width 0.5)
			(island_removal_mode 0)
		)
		(polygon
			(pts
				(arc
					(start 30.168596 -6.724396)
					(mid 29.465016 -6.724396)
					(end 30.168596 -6.724396)
				)
			)
		)
	)
	(zone
		(layers "B.Cu" "In13.Cu" "In15.Cu")
		(hatch none 0.5)
		(connect_pads
			(clearance 0)
		)
		(min_thickness 0.25)
		(keepout
			(tracks not_allowed)
			(vias allowed)
			(pads allowed)
			(copperpour not_allowed)
			(footprints allowed)
		)
		(placement
			(enabled no)
			(sheetname "")
		)
		(fill yes
			(thermal_gap 0.5)
			(thermal_bridge_width 0.5)
			(island_removal_mode 0)
		)
		(polygon
			(pts
				(arc
					(start 207.397604 -197.316598)
					(mid 206.744824 -197.316598)
					(end 207.397604 -197.316598)
				)
			)
		)
	)
	(zone
		(layers "B.Cu" "In13.Cu" "In15.Cu")
		(hatch none 0.5)
		(connect_pads
			(clearance 0)
		)
		(min_thickness 0.25)
		(keepout
			(tracks not_allowed)
			(vias allowed)
			(pads allowed)
			(copperpour not_allowed)
			(footprints allowed)
		)
		(placement
			(enabled no)
			(sheetname "")
		)
		(fill yes
			(thermal_gap 0.5)
			(thermal_bridge_width 0.5)
			(island_removal_mode 0)
		)
		(polygon
			(pts
				(arc
					(start 120.506744 -403.883876)
					(mid 119.803164 -403.883876)
					(end 120.506744 -403.883876)
				)
			)
		)
	)
	(zone
		(layers "B.Cu" "In13.Cu" "In15.Cu")
		(hatch none 0.5)
		(connect_pads
			(clearance 0)
		)
		(min_thickness 0.25)
		(keepout
			(tracks not_allowed)
			(vias allowed)
			(pads allowed)
			(copperpour not_allowed)
			(footprints allowed)
		)
		(placement
			(enabled no)
			(sheetname "")
		)
		(fill yes
			(thermal_gap 0.5)
			(thermal_bridge_width 0.5)
			(island_removal_mode 0)
		)
		(polygon
			(pts
				(arc
					(start 124.294138 -253.919736)
					(mid 123.641358 -253.919736)
					(end 124.294138 -253.919736)
				)
			)
		)
	)
	(zone
		(layers "B.Cu" "In13.Cu" "In15.Cu")
		(hatch none 0.5)
		(connect_pads
			(clearance 0)
		)
		(min_thickness 0.25)
		(keepout
			(tracks not_allowed)
			(vias allowed)
			(pads allowed)
			(copperpour not_allowed)
			(footprints allowed)
		)
		(placement
			(enabled no)
			(sheetname "")
		)
		(fill yes
			(thermal_gap 0.5)
			(thermal_bridge_width 0.5)
			(island_removal_mode 0)
		)
		(polygon
			(pts
				(arc
					(start 455.337672 -240.666778)
					(mid 454.684892 -240.666778)
					(end 455.337672 -240.666778)
				)
			)
		)
	)
	(zone
		(layers "B.Cu" "In13.Cu" "In15.Cu")
		(hatch none 0.5)
		(connect_pads
			(clearance 0)
		)
		(min_thickness 0.25)
		(keepout
			(tracks not_allowed)
			(vias allowed)
			(pads allowed)
			(copperpour not_allowed)
			(footprints allowed)
		)
		(placement
			(enabled no)
			(sheetname "")
		)
		(fill yes
			(thermal_gap 0.5)
			(thermal_bridge_width 0.5)
			(island_removal_mode 0)
		)
		(polygon
			(pts
				(arc
					(start 101.268784 -272.639282)
					(mid 100.616004 -272.639282)
					(end 101.268784 -272.639282)
				)
			)
		)
	)
	(zone
		(layers "B.Cu" "In13.Cu" "In15.Cu")
		(hatch none 0.5)
		(connect_pads
			(clearance 0)
		)
		(min_thickness 0.25)
		(keepout
			(tracks not_allowed)
			(vias allowed)
			(pads allowed)
			(copperpour not_allowed)
			(footprints allowed)
		)
		(placement
			(enabled no)
			(sheetname "")
		)
		(fill yes
			(thermal_gap 0.5)
			(thermal_bridge_width 0.5)
			(island_removal_mode 0)
		)
		(polygon
			(pts
				(arc
					(start 372.234206 -275.08073)
					(mid 371.581426 -275.08073)
					(end 372.234206 -275.08073)
				)
			)
		)
	)
	(zone
		(layers "B.Cu" "In13.Cu" "In15.Cu")
		(hatch none 0.5)
		(connect_pads
			(clearance 0)
		)
		(min_thickness 0.25)
		(keepout
			(tracks not_allowed)
			(vias allowed)
			(pads allowed)
			(copperpour not_allowed)
			(footprints allowed)
		)
		(placement
			(enabled no)
			(sheetname "")
		)
		(fill yes
			(thermal_gap 0.5)
			(thermal_bridge_width 0.5)
			(island_removal_mode 0)
		)
		(polygon
			(pts
				(arc
					(start 340.054946 -430.889918)
					(mid 339.245194 -430.889918)
					(end 340.054946 -430.889918)
				)
			)
		)
	)
	(zone
		(layers "B.Cu" "In13.Cu" "In15.Cu")
		(hatch none 0.5)
		(connect_pads
			(clearance 0)
		)
		(min_thickness 0.25)
		(keepout
			(tracks not_allowed)
			(vias allowed)
			(pads allowed)
			(copperpour not_allowed)
			(footprints allowed)
		)
		(placement
			(enabled no)
			(sheetname "")
		)
		(fill yes
			(thermal_gap 0.5)
			(thermal_bridge_width 0.5)
			(island_removal_mode 0)
		)
		(polygon
			(pts
				(arc
					(start 21.215604 -216.016586)
					(mid 20.562824 -216.016586)
					(end 21.215604 -216.016586)
				)
			)
		)
	)
	(zone
		(layers "B.Cu" "In13.Cu" "In15.Cu")
		(hatch none 0.5)
		(connect_pads
			(clearance 0)
		)
		(min_thickness 0.25)
		(keepout
			(tracks not_allowed)
			(vias allowed)
			(pads allowed)
			(copperpour not_allowed)
			(footprints allowed)
		)
		(placement
			(enabled no)
			(sheetname "")
		)
		(fill yes
			(thermal_gap 0.5)
			(thermal_bridge_width 0.5)
			(island_removal_mode 0)
		)
		(polygon
			(pts
				(arc
					(start 269.155672 -283.166566)
					(mid 268.502892 -283.166566)
					(end 269.155672 -283.166566)
				)
			)
		)
	)
	(zone
		(layers "B.Cu" "In13.Cu" "In15.Cu")
		(hatch none 0.5)
		(connect_pads
			(clearance 0)
		)
		(min_thickness 0.25)
		(keepout
			(tracks not_allowed)
			(vias allowed)
			(pads allowed)
			(copperpour not_allowed)
			(footprints allowed)
		)
		(placement
			(enabled no)
			(sheetname "")
		)
		(fill yes
			(thermal_gap 0.5)
			(thermal_bridge_width 0.5)
			(island_removal_mode 0)
		)
		(polygon
			(pts
				(arc
					(start 265.055604 -261.066788)
					(mid 264.402824 -261.066788)
					(end 265.055604 -261.066788)
				)
			)
		)
	)
	(zone
		(layers "B.Cu" "In13.Cu" "In15.Cu")
		(hatch none 0.5)
		(connect_pads
			(clearance 0)
		)
		(min_thickness 0.25)
		(keepout
			(tracks not_allowed)
			(vias allowed)
			(pads allowed)
			(copperpour not_allowed)
			(footprints allowed)
		)
		(placement
			(enabled no)
			(sheetname "")
		)
		(fill yes
			(thermal_gap 0.5)
			(thermal_bridge_width 0.5)
			(island_removal_mode 0)
		)
		(polygon
			(pts
				(arc
					(start 207.397604 -227.91674)
					(mid 206.744824 -227.91674)
					(end 207.397604 -227.91674)
				)
			)
		)
	)
	(zone
		(layers "B.Cu" "In13.Cu" "In15.Cu")
		(hatch none 0.5)
		(connect_pads
			(clearance 0)
		)
		(min_thickness 0.25)
		(keepout
			(tracks not_allowed)
			(vias allowed)
			(pads allowed)
			(copperpour not_allowed)
			(footprints allowed)
		)
		(placement
			(enabled no)
			(sheetname "")
		)
		(fill yes
			(thermal_gap 0.5)
			(thermal_bridge_width 0.5)
			(island_removal_mode 0)
		)
		(polygon
			(pts
				(arc
					(start 101.738938 -281.59202)
					(mid 101.086158 -281.59202)
					(end 101.738938 -281.59202)
				)
			)
		)
	)
	(zone
		(layers "B.Cu" "In13.Cu" "In15.Cu")
		(hatch none 0.5)
		(connect_pads
			(clearance 0)
		)
		(min_thickness 0.25)
		(keepout
			(tracks not_allowed)
			(vias allowed)
			(pads allowed)
			(copperpour not_allowed)
			(footprints allowed)
		)
		(placement
			(enabled no)
			(sheetname "")
		)
		(fill yes
			(thermal_gap 0.5)
			(thermal_bridge_width 0.5)
			(island_removal_mode 0)
		)
		(polygon
			(pts
				(arc
					(start 21.215604 -246.616728)
					(mid 20.562824 -246.616728)
					(end 21.215604 -246.616728)
				)
			)
		)
	)
	(zone
		(layers "B.Cu" "In13.Cu" "In15.Cu")
		(hatch none 0.5)
		(connect_pads
			(clearance 0)
		)
		(min_thickness 0.25)
		(keepout
			(tracks not_allowed)
			(vias allowed)
			(pads allowed)
			(copperpour not_allowed)
			(footprints allowed)
		)
		(placement
			(enabled no)
			(sheetname "")
		)
		(fill yes
			(thermal_gap 0.5)
			(thermal_bridge_width 0.5)
			(island_removal_mode 0)
		)
		(polygon
			(pts
				(arc
					(start 265.055604 -284.016704)
					(mid 264.402824 -284.016704)
					(end 265.055604 -284.016704)
				)
			)
		)
	)
	(zone
		(layers "B.Cu" "In13.Cu" "In15.Cu")
		(hatch none 0.5)
		(connect_pads
			(clearance 0)
		)
		(min_thickness 0.25)
		(keepout
			(tracks not_allowed)
			(vias allowed)
			(pads allowed)
			(copperpour not_allowed)
			(footprints allowed)
		)
		(placement
			(enabled no)
			(sheetname "")
		)
		(fill yes
			(thermal_gap 0.5)
			(thermal_bridge_width 0.5)
			(island_removal_mode 0)
		)
		(polygon
			(pts
				(arc
					(start 455.337672 -221.96679)
					(mid 454.684892 -221.96679)
					(end 455.337672 -221.96679)
				)
			)
		)
	)
	(zone
		(layers "B.Cu" "In13.Cu" "In15.Cu")
		(hatch none 0.5)
		(connect_pads
			(clearance 0)
		)
		(min_thickness 0.25)
		(keepout
			(tracks not_allowed)
			(vias allowed)
			(pads allowed)
			(copperpour not_allowed)
			(footprints allowed)
		)
		(placement
			(enabled no)
			(sheetname "")
		)
		(fill yes
			(thermal_gap 0.5)
			(thermal_bridge_width 0.5)
			(island_removal_mode 0)
		)
		(polygon
			(pts
				(arc
					(start 374.943624 -245.55069)
					(mid 374.290844 -245.55069)
					(end 374.943624 -245.55069)
				)
			)
		)
	)
	(zone
		(layers "B.Cu" "In13.Cu" "In15.Cu")
		(hatch none 0.5)
		(connect_pads
			(clearance 0)
		)
		(min_thickness 0.25)
		(keepout
			(tracks not_allowed)
			(vias allowed)
			(pads allowed)
			(copperpour not_allowed)
			(footprints allowed)
		)
		(placement
			(enabled no)
			(sheetname "")
		)
		(fill yes
			(thermal_gap 0.5)
			(thermal_bridge_width 0.5)
			(island_removal_mode 0)
		)
		(polygon
			(pts
				(arc
					(start 21.215604 -283.166566)
					(mid 20.562824 -283.166566)
					(end 21.215604 -283.166566)
				)
			)
		)
	)
	(zone
		(layers "B.Cu" "In13.Cu" "In15.Cu")
		(hatch none 0.5)
		(connect_pads
			(clearance 0)
		)
		(min_thickness 0.25)
		(keepout
			(tracks not_allowed)
			(vias allowed)
			(pads allowed)
			(copperpour not_allowed)
			(footprints allowed)
		)
		(placement
			(enabled no)
			(sheetname "")
		)
		(fill yes
			(thermal_gap 0.5)
			(thermal_bridge_width 0.5)
			(island_removal_mode 0)
		)
		(polygon
			(pts
				(arc
					(start 373.53367 -241.481102)
					(mid 372.88089 -241.481102)
					(end 373.53367 -241.481102)
				)
			)
		)
	)
	(zone
		(layers "B.Cu" "In13.Cu" "In15.Cu")
		(hatch none 0.5)
		(connect_pads
			(clearance 0)
		)
		(min_thickness 0.25)
		(keepout
			(tracks not_allowed)
			(vias allowed)
			(pads allowed)
			(copperpour not_allowed)
			(footprints allowed)
		)
		(placement
			(enabled no)
			(sheetname "")
		)
		(fill yes
			(thermal_gap 0.5)
			(thermal_bridge_width 0.5)
			(island_removal_mode 0)
		)
		(polygon
			(pts
				(arc
					(start 214.941404 -260.21665)
					(mid 214.288624 -260.21665)
					(end 214.941404 -260.21665)
				)
			)
		)
	)
	(zone
		(layers "B.Cu" "In13.Cu" "In15.Cu")
		(hatch none 0.5)
		(connect_pads
			(clearance 0)
		)
		(min_thickness 0.25)
		(keepout
			(tracks not_allowed)
			(vias allowed)
			(pads allowed)
			(copperpour not_allowed)
			(footprints allowed)
		)
		(placement
			(enabled no)
			(sheetname "")
		)
		(fill yes
			(thermal_gap 0.5)
			(thermal_bridge_width 0.5)
			(island_removal_mode 0)
		)
		(polygon
			(pts
				(arc
					(start 455.337672 -251.716794)
					(mid 454.684892 -251.716794)
					(end 455.337672 -251.716794)
				)
			)
		)
	)
	(zone
		(layers "B.Cu" "In13.Cu" "In15.Cu")
		(hatch none 0.5)
		(connect_pads
			(clearance 0)
		)
		(min_thickness 0.25)
		(keepout
			(tracks not_allowed)
			(vias allowed)
			(pads allowed)
			(copperpour not_allowed)
			(footprints allowed)
		)
		(placement
			(enabled no)
			(sheetname "")
		)
		(fill yes
			(thermal_gap 0.5)
			(thermal_bridge_width 0.5)
			(island_removal_mode 0)
		)
		(polygon
			(pts
				(arc
					(start 100.799138 -262.058658)
					(mid 100.146358 -262.058658)
					(end 100.799138 -262.058658)
				)
			)
		)
	)
	(zone
		(layers "B.Cu" "In13.Cu" "In15.Cu")
		(hatch none 0.5)
		(connect_pads
			(clearance 0)
		)
		(min_thickness 0.25)
		(keepout
			(tracks not_allowed)
			(vias allowed)
			(pads allowed)
			(copperpour not_allowed)
			(footprints allowed)
		)
		(placement
			(enabled no)
			(sheetname "")
		)
		(fill yes
			(thermal_gap 0.5)
			(thermal_bridge_width 0.5)
			(island_removal_mode 0)
		)
		(polygon
			(pts
				(arc
					(start 451.237604 -289.966654)
					(mid 450.584824 -289.966654)
					(end 451.237604 -289.966654)
				)
			)
		)
	)
	(zone
		(layers "B.Cu" "In13.Cu" "In15.Cu")
		(hatch none 0.5)
		(connect_pads
			(clearance 0)
		)
		(min_thickness 0.25)
		(keepout
			(tracks not_allowed)
			(vias allowed)
			(pads allowed)
			(copperpour not_allowed)
			(footprints allowed)
		)
		(placement
			(enabled no)
			(sheetname "")
		)
		(fill yes
			(thermal_gap 0.5)
			(thermal_bridge_width 0.5)
			(island_removal_mode 0)
		)
		(polygon
			(pts
				(arc
					(start 371.764052 -264.50036)
					(mid 371.111272 -264.50036)
					(end 371.764052 -264.50036)
				)
			)
		)
	)
	(zone
		(layers "B.Cu" "In13.Cu" "In15.Cu")
		(hatch none 0.5)
		(connect_pads
			(clearance 0)
		)
		(min_thickness 0.25)
		(keepout
			(tracks not_allowed)
			(vias allowed)
			(pads allowed)
			(copperpour not_allowed)
			(footprints allowed)
		)
		(placement
			(enabled no)
			(sheetname "")
		)
		(fill yes
			(thermal_gap 0.5)
			(thermal_bridge_width 0.5)
			(island_removal_mode 0)
		)
		(polygon
			(pts
				(arc
					(start 17.115536 -291.666676)
					(mid 16.462756 -291.666676)
					(end 17.115536 -291.666676)
				)
			)
		)
	)
	(zone
		(layers "B.Cu" "In13.Cu" "In15.Cu")
		(hatch none 0.5)
		(connect_pads
			(clearance 0)
		)
		(min_thickness 0.25)
		(keepout
			(tracks not_allowed)
			(vias allowed)
			(pads allowed)
			(copperpour not_allowed)
			(footprints allowed)
		)
		(placement
			(enabled no)
			(sheetname "")
		)
		(fill yes
			(thermal_gap 0.5)
			(thermal_bridge_width 0.5)
			(island_removal_mode 0)
		)
		(polygon
			(pts
				(arc
					(start 98.919538 -271.825212)
					(mid 98.266758 -271.825212)
					(end 98.919538 -271.825212)
				)
			)
		)
	)
	(zone
		(layers "B.Cu" "In13.Cu" "In15.Cu")
		(hatch none 0.5)
		(connect_pads
			(clearance 0)
		)
		(min_thickness 0.25)
		(keepout
			(tracks not_allowed)
			(vias allowed)
			(pads allowed)
			(copperpour not_allowed)
			(footprints allowed)
		)
		(placement
			(enabled no)
			(sheetname "")
		)
		(fill yes
			(thermal_gap 0.5)
			(thermal_bridge_width 0.5)
			(island_removal_mode 0)
		)
		(polygon
			(pts
				(arc
					(start 455.337672 -225.36658)
					(mid 454.684892 -225.36658)
					(end 455.337672 -225.36658)
				)
			)
		)
	)
	(zone
		(layers "B.Cu" "In13.Cu" "In15.Cu")
		(hatch none 0.5)
		(connect_pads
			(clearance 0)
		)
		(min_thickness 0.25)
		(keepout
			(tracks not_allowed)
			(vias allowed)
			(pads allowed)
			(copperpour not_allowed)
			(footprints allowed)
		)
		(placement
			(enabled no)
			(sheetname "")
		)
		(fill yes
			(thermal_gap 0.5)
			(thermal_bridge_width 0.5)
			(island_removal_mode 0)
		)
		(polygon
			(pts
				(arc
					(start 378.7648 -403.883876)
					(mid 378.06122 -403.883876)
					(end 378.7648 -403.883876)
				)
			)
		)
	)
	(zone
		(layers "B.Cu" "In13.Cu" "In15.Cu")
		(hatch none 0.5)
		(connect_pads
			(clearance 0)
		)
		(min_thickness 0.25)
		(keepout
			(tracks not_allowed)
			(vias allowed)
			(pads allowed)
			(copperpour not_allowed)
			(footprints allowed)
		)
		(placement
			(enabled no)
			(sheetname "")
		)
		(fill yes
			(thermal_gap 0.5)
			(thermal_bridge_width 0.5)
			(island_removal_mode 0)
		)
		(polygon
			(pts
				(arc
					(start 265.055604 -227.91674)
					(mid 264.402824 -227.91674)
					(end 265.055604 -227.91674)
				)
			)
		)
	)
	(zone
		(layers "B.Cu" "In13.Cu" "In15.Cu")
		(hatch none 0.5)
		(connect_pads
			(clearance 0)
		)
		(min_thickness 0.25)
		(keepout
			(tracks not_allowed)
			(vias allowed)
			(pads allowed)
			(copperpour not_allowed)
			(footprints allowed)
		)
		(placement
			(enabled no)
			(sheetname "")
		)
		(fill yes
			(thermal_gap 0.5)
			(thermal_bridge_width 0.5)
			(island_removal_mode 0)
		)
		(polygon
			(pts
				(arc
					(start 17.115536 -235.566712)
					(mid 16.462756 -235.566712)
					(end 17.115536 -235.566712)
				)
			)
		)
	)
	(zone
		(layers "B.Cu" "In13.Cu" "In15.Cu")
		(hatch none 0.5)
		(connect_pads
			(clearance 0)
		)
		(min_thickness 0.25)
		(keepout
			(tracks not_allowed)
			(vias allowed)
			(pads allowed)
			(copperpour not_allowed)
			(footprints allowed)
		)
		(placement
			(enabled no)
			(sheetname "")
		)
		(fill yes
			(thermal_gap 0.5)
			(thermal_bridge_width 0.5)
			(island_removal_mode 0)
		)
		(polygon
			(pts
				(arc
					(start 21.215604 -238.966756)
					(mid 20.562824 -238.966756)
					(end 21.215604 -238.966756)
				)
			)
		)
	)
	(zone
		(layers "B.Cu" "In13.Cu" "In15.Cu")
		(hatch none 0.5)
		(connect_pads
			(clearance 0)
		)
		(min_thickness 0.25)
		(keepout
			(tracks not_allowed)
			(vias allowed)
			(pads allowed)
			(copperpour not_allowed)
			(footprints allowed)
		)
		(placement
			(enabled no)
			(sheetname "")
		)
		(fill yes
			(thermal_gap 0.5)
			(thermal_bridge_width 0.5)
			(island_removal_mode 0)
		)
		(polygon
			(pts
				(arc
					(start 100.799138 -268.569694)
					(mid 100.146358 -268.569694)
					(end 100.799138 -268.569694)
				)
			)
		)
	)
	(zone
		(layers "B.Cu" "In13.Cu" "In15.Cu")
		(hatch none 0.5)
		(connect_pads
			(clearance 0)
		)
		(min_thickness 0.25)
		(keepout
			(tracks not_allowed)
			(vias allowed)
			(pads allowed)
			(copperpour not_allowed)
			(footprints allowed)
		)
		(placement
			(enabled no)
			(sheetname "")
		)
		(fill yes
			(thermal_gap 0.5)
			(thermal_bridge_width 0.5)
			(island_removal_mode 0)
		)
		(polygon
			(pts
				(arc
					(start 347.329252 -261.244842)
					(mid 346.676472 -261.244842)
					(end 347.329252 -261.244842)
				)
			)
		)
	)
	(zone
		(layers "B.Cu" "In13.Cu" "In15.Cu")
		(hatch none 0.5)
		(connect_pads
			(clearance 0)
		)
		(min_thickness 0.25)
		(keepout
			(tracks not_allowed)
			(vias allowed)
			(pads allowed)
			(copperpour not_allowed)
			(footprints allowed)
		)
		(placement
			(enabled no)
			(sheetname "")
		)
		(fill yes
			(thermal_gap 0.5)
			(thermal_bridge_width 0.5)
			(island_removal_mode 0)
		)
		(polygon
			(pts
				(arc
					(start 455.337672 -302.716692)
					(mid 454.684892 -302.716692)
					(end 455.337672 -302.716692)
				)
			)
		)
	)
	(zone
		(layers "B.Cu" "In13.Cu" "In15.Cu")
		(hatch none 0.5)
		(connect_pads
			(clearance 0)
		)
		(min_thickness 0.25)
		(keepout
			(tracks not_allowed)
			(vias allowed)
			(pads allowed)
			(copperpour not_allowed)
			(footprints allowed)
		)
		(placement
			(enabled no)
			(sheetname "")
		)
		(fill yes
			(thermal_gap 0.5)
			(thermal_bridge_width 0.5)
			(island_removal_mode 0)
		)
		(polygon
			(pts
				(arc
					(start 43.742102 -6.724396)
					(mid 43.038522 -6.724396)
					(end 43.742102 -6.724396)
				)
			)
		)
	)
	(zone
		(layers "B.Cu" "In13.Cu" "In15.Cu")
		(hatch none 0.5)
		(connect_pads
			(clearance 0)
		)
		(min_thickness 0.25)
		(keepout
			(tracks not_allowed)
			(vias allowed)
			(pads allowed)
			(copperpour not_allowed)
			(footprints allowed)
		)
		(placement
			(enabled no)
			(sheetname "")
		)
		(fill yes
			(thermal_gap 0.5)
			(thermal_bridge_width 0.5)
			(island_removal_mode 0)
		)
		(polygon
			(pts
				(arc
					(start 352.490278 -410.030168)
					(mid 351.786698 -410.030168)
					(end 352.490278 -410.030168)
				)
			)
		)
	)
	(zone
		(layers "B.Cu" "In13.Cu" "In15.Cu")
		(hatch none 0.5)
		(connect_pads
			(clearance 0)
		)
		(min_thickness 0.25)
		(keepout
			(tracks not_allowed)
			(vias allowed)
			(pads allowed)
			(copperpour not_allowed)
			(footprints allowed)
		)
		(placement
			(enabled no)
			(sheetname "")
		)
		(fill yes
			(thermal_gap 0.5)
			(thermal_bridge_width 0.5)
			(island_removal_mode 0)
		)
		(polygon
			(pts
				(arc
					(start 98.809556 -229.272846)
					(mid 98.156776 -229.272846)
					(end 98.809556 -229.272846)
				)
			)
		)
	)
	(zone
		(layers "B.Cu" "In13.Cu" "In15.Cu")
		(hatch none 0.5)
		(connect_pads
			(clearance 0)
		)
		(min_thickness 0.25)
		(keepout
			(tracks not_allowed)
			(vias allowed)
			(pads allowed)
			(copperpour not_allowed)
			(footprints allowed)
		)
		(placement
			(enabled no)
			(sheetname "")
		)
		(fill yes
			(thermal_gap 0.5)
			(thermal_bridge_width 0.5)
			(island_removal_mode 0)
		)
		(polygon
			(pts
				(arc
					(start 265.055604 -295.916604)
					(mid 264.402824 -295.916604)
					(end 265.055604 -295.916604)
				)
			)
		)
	)
	(zone
		(layers "B.Cu" "In13.Cu" "In15.Cu")
		(hatch none 0.5)
		(connect_pads
			(clearance 0)
		)
		(min_thickness 0.25)
		(keepout
			(tracks not_allowed)
			(vias allowed)
			(pads allowed)
			(copperpour not_allowed)
			(footprints allowed)
		)
		(placement
			(enabled no)
			(sheetname "")
		)
		(fill yes
			(thermal_gap 0.5)
			(thermal_bridge_width 0.5)
			(island_removal_mode 0)
		)
		(polygon
			(pts
				(arc
					(start 127.003556 -245.55069)
					(mid 126.350776 -245.55069)
					(end 127.003556 -245.55069)
				)
			)
		)
	)
	(zone
		(layers "B.Cu" "In13.Cu" "In15.Cu")
		(hatch none 0.5)
		(connect_pads
			(clearance 0)
		)
		(min_thickness 0.25)
		(keepout
			(tracks not_allowed)
			(vias allowed)
			(pads allowed)
			(copperpour not_allowed)
			(footprints allowed)
		)
		(placement
			(enabled no)
			(sheetname "")
		)
		(fill yes
			(thermal_gap 0.5)
			(thermal_bridge_width 0.5)
			(island_removal_mode 0)
		)
		(polygon
			(pts
				(arc
					(start 373.643652 -275.8948)
					(mid 372.990872 -275.8948)
					(end 373.643652 -275.8948)
				)
			)
		)
	)
	(zone
		(layers "B.Cu" "In13.Cu" "In15.Cu")
		(hatch none 0.5)
		(connect_pads
			(clearance 0)
		)
		(min_thickness 0.25)
		(keepout
			(tracks not_allowed)
			(vias allowed)
			(pads allowed)
			(copperpour not_allowed)
			(footprints allowed)
		)
		(placement
			(enabled no)
			(sheetname "")
		)
		(fill yes
			(thermal_gap 0.5)
			(thermal_bridge_width 0.5)
			(island_removal_mode 0)
		)
		(polygon
			(pts
				(arc
					(start 265.055604 -303.566576)
					(mid 264.402824 -303.566576)
					(end 265.055604 -303.566576)
				)
			)
		)
	)
	(zone
		(layers "B.Cu" "In13.Cu" "In15.Cu")
		(hatch none 0.5)
		(connect_pads
			(clearance 0)
		)
		(min_thickness 0.25)
		(keepout
			(tracks not_allowed)
			(vias allowed)
			(pads allowed)
			(copperpour not_allowed)
			(footprints allowed)
		)
		(placement
			(enabled no)
			(sheetname "")
		)
		(fill yes
			(thermal_gap 0.5)
			(thermal_bridge_width 0.5)
			(island_removal_mode 0)
		)
		(polygon
			(pts
				(arc
					(start 164.255704 -403.883876)
					(mid 163.552124 -403.883876)
					(end 164.255704 -403.883876)
				)
			)
		)
	)
	(zone
		(layers "B.Cu" "In13.Cu" "In15.Cu")
		(hatch none 0.5)
		(connect_pads
			(clearance 0)
		)
		(min_thickness 0.25)
		(keepout
			(tracks not_allowed)
			(vias allowed)
			(pads allowed)
			(copperpour not_allowed)
			(footprints allowed)
		)
		(placement
			(enabled no)
			(sheetname "")
		)
		(fill yes
			(thermal_gap 0.5)
			(thermal_bridge_width 0.5)
			(island_removal_mode 0)
		)
		(polygon
			(pts
				(arc
					(start 451.237604 -204.116686)
					(mid 450.584824 -204.116686)
					(end 451.237604 -204.116686)
				)
			)
		)
	)
	(zone
		(layers "B.Cu" "In13.Cu" "In15.Cu")
		(hatch none 0.5)
		(connect_pads
			(clearance 0)
		)
		(min_thickness 0.25)
		(keepout
			(tracks not_allowed)
			(vias allowed)
			(pads allowed)
			(copperpour not_allowed)
			(footprints allowed)
		)
		(placement
			(enabled no)
			(sheetname "")
		)
		(fill yes
			(thermal_gap 0.5)
			(thermal_bridge_width 0.5)
			(island_removal_mode 0)
		)
		(polygon
			(pts
				(arc
					(start 124.184156 -232.528364)
					(mid 123.531376 -232.528364)
					(end 124.184156 -232.528364)
				)
			)
		)
	)
	(zone
		(layers "B.Cu" "In13.Cu" "In15.Cu")
		(hatch none 0.5)
		(connect_pads
			(clearance 0)
		)
		(min_thickness 0.25)
		(keepout
			(tracks not_allowed)
			(vias allowed)
			(pads allowed)
			(copperpour not_allowed)
			(footprints allowed)
		)
		(placement
			(enabled no)
			(sheetname "")
		)
		(fill yes
			(thermal_gap 0.5)
			(thermal_bridge_width 0.5)
			(island_removal_mode 0)
		)
		(polygon
			(pts
				(arc
					(start 462.881472 -260.21665)
					(mid 462.228692 -260.21665)
					(end 462.881472 -260.21665)
				)
			)
		)
	)
	(zone
		(layers "B.Cu" "In13.Cu" "In15.Cu")
		(hatch none 0.5)
		(connect_pads
			(clearance 0)
		)
		(min_thickness 0.25)
		(keepout
			(tracks not_allowed)
			(vias allowed)
			(pads allowed)
			(copperpour not_allowed)
			(footprints allowed)
		)
		(placement
			(enabled no)
			(sheetname "")
		)
		(fill yes
			(thermal_gap 0.5)
			(thermal_bridge_width 0.5)
			(island_removal_mode 0)
		)
		(polygon
			(pts
				(arc
					(start 123.823984 -269.38351)
					(mid 123.171204 -269.38351)
					(end 123.823984 -269.38351)
				)
			)
		)
	)
	(zone
		(layers "B.Cu" "In13.Cu" "In15.Cu")
		(hatch none 0.5)
		(connect_pads
			(clearance 0)
		)
		(min_thickness 0.25)
		(keepout
			(tracks not_allowed)
			(vias allowed)
			(pads allowed)
			(copperpour not_allowed)
			(footprints allowed)
		)
		(placement
			(enabled no)
			(sheetname "")
		)
		(fill yes
			(thermal_gap 0.5)
			(thermal_bridge_width 0.5)
			(island_removal_mode 0)
		)
		(polygon
			(pts
				(arc
					(start 60.584588 -403.883876)
					(mid 59.881008 -403.883876)
					(end 60.584588 -403.883876)
				)
			)
		)
	)
	(zone
		(layers "B.Cu" "In13.Cu" "In15.Cu")
		(hatch none 0.5)
		(connect_pads
			(clearance 0)
		)
		(min_thickness 0.25)
		(keepout
			(tracks not_allowed)
			(vias allowed)
			(pads allowed)
			(copperpour not_allowed)
			(footprints allowed)
		)
		(placement
			(enabled no)
			(sheetname "")
		)
		(fill yes
			(thermal_gap 0.5)
			(thermal_bridge_width 0.5)
			(island_removal_mode 0)
		)
		(polygon
			(pts
				(arc
					(start 67.054984 -429.689768)
					(mid 66.245232 -429.689768)
					(end 67.054984 -429.689768)
				)
			)
		)
	)
	(zone
		(layers "B.Cu" "In13.Cu" "In15.Cu")
		(hatch none 0.5)
		(connect_pads
			(clearance 0)
		)
		(min_thickness 0.25)
		(keepout
			(tracks not_allowed)
			(vias allowed)
			(pads allowed)
			(copperpour not_allowed)
			(footprints allowed)
		)
		(placement
			(enabled no)
			(sheetname "")
		)
		(fill yes
			(thermal_gap 0.5)
			(thermal_bridge_width 0.5)
			(island_removal_mode 0)
		)
		(polygon
			(pts
				(arc
					(start 87.641684 -286.475424)
					(mid 86.988904 -286.475424)
					(end 87.641684 -286.475424)
				)
			)
		)
	)
	(zone
		(layers "B.Cu" "In13.Cu" "In15.Cu")
		(hatch none 0.5)
		(connect_pads
			(clearance 0)
		)
		(min_thickness 0.25)
		(keepout
			(tracks not_allowed)
			(vias allowed)
			(pads allowed)
			(copperpour not_allowed)
			(footprints allowed)
		)
		(placement
			(enabled no)
			(sheetname "")
		)
		(fill yes
			(thermal_gap 0.5)
			(thermal_bridge_width 0.5)
			(island_removal_mode 0)
		)
		(polygon
			(pts
				(arc
					(start 348.629224 -230.900478)
					(mid 347.976444 -230.900478)
					(end 348.629224 -230.900478)
				)
			)
		)
	)
	(zone
		(layers "B.Cu" "In13.Cu" "In15.Cu")
		(hatch none 0.5)
		(connect_pads
			(clearance 0)
		)
		(min_thickness 0.25)
		(keepout
			(tracks not_allowed)
			(vias allowed)
			(pads allowed)
			(copperpour not_allowed)
			(footprints allowed)
		)
		(placement
			(enabled no)
			(sheetname "")
		)
		(fill yes
			(thermal_gap 0.5)
			(thermal_bridge_width 0.5)
			(island_removal_mode 0)
		)
		(polygon
			(pts
				(arc
					(start 373.53367 -233.34218)
					(mid 372.88089 -233.34218)
					(end 373.53367 -233.34218)
				)
			)
		)
	)
	(zone
		(layers "B.Cu" "In13.Cu" "In15.Cu")
		(hatch none 0.5)
		(connect_pads
			(clearance 0)
		)
		(min_thickness 0.25)
		(keepout
			(tracks not_allowed)
			(vias allowed)
			(pads allowed)
			(copperpour not_allowed)
			(footprints allowed)
		)
		(placement
			(enabled no)
			(sheetname "")
		)
		(fill yes
			(thermal_gap 0.5)
			(thermal_bridge_width 0.5)
			(island_removal_mode 0)
		)
		(polygon
			(pts
				(arc
					(start 315.054996 -430.889918)
					(mid 314.245244 -430.889918)
					(end 315.054996 -430.889918)
				)
			)
		)
	)
	(zone
		(layers "B.Cu" "In13.Cu" "In15.Cu")
		(hatch none 0.5)
		(connect_pads
			(clearance 0)
		)
		(min_thickness 0.25)
		(keepout
			(tracks not_allowed)
			(vias allowed)
			(pads allowed)
			(copperpour not_allowed)
			(footprints allowed)
		)
		(placement
			(enabled no)
			(sheetname "")
		)
		(fill yes
			(thermal_gap 0.5)
			(thermal_bridge_width 0.5)
			(island_removal_mode 0)
		)
		(polygon
			(pts
				(arc
					(start 359.906824 -221.133924)
					(mid 359.254044 -221.133924)
					(end 359.906824 -221.133924)
				)
			)
		)
	)
	(zone
		(layers "B.Cu" "In13.Cu" "In15.Cu")
		(hatch none 0.5)
		(connect_pads
			(clearance 0)
		)
		(min_thickness 0.25)
		(keepout
			(tracks not_allowed)
			(vias allowed)
			(pads allowed)
			(copperpour not_allowed)
			(footprints allowed)
		)
		(placement
			(enabled no)
			(sheetname "")
		)
		(fill yes
			(thermal_gap 0.5)
			(thermal_bridge_width 0.5)
			(island_removal_mode 0)
		)
		(polygon
			(pts
				(arc
					(start 41.08323 -4.962652)
					(mid 40.37965 -4.962652)
					(end 41.08323 -4.962652)
				)
			)
		)
	)
	(zone
		(layers "B.Cu" "In13.Cu" "In15.Cu")
		(hatch none 0.5)
		(connect_pads
			(clearance 0)
		)
		(min_thickness 0.25)
		(keepout
			(tracks not_allowed)
			(vias allowed)
			(pads allowed)
			(copperpour not_allowed)
			(footprints allowed)
		)
		(placement
			(enabled no)
			(sheetname "")
		)
		(fill yes
			(thermal_gap 0.5)
			(thermal_bridge_width 0.5)
			(island_removal_mode 0)
		)
		(polygon
			(pts
				(arc
					(start 451.237604 -198.166736)
					(mid 450.584824 -198.166736)
					(end 451.237604 -198.166736)
				)
			)
		)
	)
	(zone
		(layers "B.Cu" "In13.Cu" "In15.Cu")
		(hatch none 0.5)
		(connect_pads
			(clearance 0)
		)
		(min_thickness 0.25)
		(keepout
			(tracks not_allowed)
			(vias allowed)
			(pads allowed)
			(copperpour not_allowed)
			(footprints allowed)
		)
		(placement
			(enabled no)
			(sheetname "")
		)
		(fill yes
			(thermal_gap 0.5)
			(thermal_bridge_width 0.5)
			(island_removal_mode 0)
		)
		(polygon
			(pts
				(arc
					(start 86.701884 -284.847538)
					(mid 86.049104 -284.847538)
					(end 86.701884 -284.847538)
				)
			)
		)
	)
	(zone
		(layers "B.Cu" "In13.Cu" "In15.Cu")
		(hatch none 0.5)
		(connect_pads
			(clearance 0)
		)
		(min_thickness 0.25)
		(keepout
			(tracks not_allowed)
			(vias allowed)
			(pads allowed)
			(copperpour not_allowed)
			(footprints allowed)
		)
		(placement
			(enabled no)
			(sheetname "")
		)
		(fill yes
			(thermal_gap 0.5)
			(thermal_bridge_width 0.5)
			(island_removal_mode 0)
		)
		(polygon
			(pts
				(arc
					(start 371.65407 -236.597952)
					(mid 371.00129 -236.597952)
					(end 371.65407 -236.597952)
				)
			)
		)
	)
	(zone
		(layers "B.Cu" "In13.Cu" "In15.Cu")
		(hatch none 0.5)
		(connect_pads
			(clearance 0)
		)
		(min_thickness 0.25)
		(keepout
			(tracks not_allowed)
			(vias allowed)
			(pads allowed)
			(copperpour not_allowed)
			(footprints allowed)
		)
		(placement
			(enabled no)
			(sheetname "")
		)
		(fill yes
			(thermal_gap 0.5)
			(thermal_bridge_width 0.5)
			(island_removal_mode 0)
		)
		(polygon
			(pts
				(arc
					(start 401.939506 -6.713474)
					(mid 401.235926 -6.713474)
					(end 401.939506 -6.713474)
				)
			)
		)
	)
	(zone
		(layers "B.Cu" "In13.Cu" "In15.Cu")
		(hatch none 0.5)
		(connect_pads
			(clearance 0)
		)
		(min_thickness 0.25)
		(keepout
			(tracks not_allowed)
			(vias allowed)
			(pads allowed)
			(copperpour not_allowed)
			(footprints allowed)
		)
		(placement
			(enabled no)
			(sheetname "")
		)
		(fill yes
			(thermal_gap 0.5)
			(thermal_bridge_width 0.5)
			(island_removal_mode 0)
		)
		(polygon
			(pts
				(arc
					(start 125.703584 -261.244842)
					(mid 125.050804 -261.244842)
					(end 125.703584 -261.244842)
				)
			)
		)
	)
	(zone
		(layers "B.Cu" "In13.Cu" "In15.Cu")
		(hatch none 0.5)
		(connect_pads
			(clearance 0)
		)
		(min_thickness 0.25)
		(keepout
			(tracks not_allowed)
			(vias allowed)
			(pads allowed)
			(copperpour not_allowed)
			(footprints allowed)
		)
		(placement
			(enabled no)
			(sheetname "")
		)
		(fill yes
			(thermal_gap 0.5)
			(thermal_bridge_width 0.5)
			(island_removal_mode 0)
		)
		(polygon
			(pts
				(arc
					(start 17.115536 -247.466612)
					(mid 16.462756 -247.466612)
					(end 17.115536 -247.466612)
				)
			)
		)
	)
	(zone
		(layers "B.Cu" "In13.Cu" "In15.Cu")
		(hatch none 0.5)
		(connect_pads
			(clearance 0)
		)
		(min_thickness 0.25)
		(keepout
			(tracks not_allowed)
			(vias allowed)
			(pads allowed)
			(copperpour not_allowed)
			(footprints allowed)
		)
		(placement
			(enabled no)
			(sheetname "")
		)
		(fill yes
			(thermal_gap 0.5)
			(thermal_bridge_width 0.5)
			(island_removal_mode 0)
		)
		(polygon
			(pts
				(arc
					(start 203.297536 -232.166668)
					(mid 202.644756 -232.166668)
					(end 203.297536 -232.166668)
				)
			)
		)
	)
	(zone
		(layers "B.Cu" "In13.Cu" "In15.Cu")
		(hatch none 0.5)
		(connect_pads
			(clearance 0)
		)
		(min_thickness 0.25)
		(keepout
			(tracks not_allowed)
			(vias allowed)
			(pads allowed)
			(copperpour not_allowed)
			(footprints allowed)
		)
		(placement
			(enabled no)
			(sheetname "")
		)
		(fill yes
			(thermal_gap 0.5)
			(thermal_bridge_width 0.5)
			(island_removal_mode 0)
		)
		(polygon
			(pts
				(arc
					(start 334.054958 -430.689766)
					(mid 333.245206 -430.689766)
					(end 334.054958 -430.689766)
				)
			)
		)
	)
	(zone
		(layers "B.Cu" "In13.Cu" "In15.Cu")
		(hatch none 0.5)
		(connect_pads
			(clearance 0)
		)
		(min_thickness 0.25)
		(keepout
			(tracks not_allowed)
			(vias allowed)
			(pads allowed)
			(copperpour not_allowed)
			(footprints allowed)
		)
		(placement
			(enabled no)
			(sheetname "")
		)
		(fill yes
			(thermal_gap 0.5)
			(thermal_bridge_width 0.5)
			(island_removal_mode 0)
		)
		(polygon
			(pts
				(arc
					(start 349.09887 -244.73662)
					(mid 348.44609 -244.73662)
					(end 349.09887 -244.73662)
				)
			)
		)
	)
	(zone
		(layers "B.Cu" "In13.Cu" "In15.Cu")
		(hatch none 0.5)
		(connect_pads
			(clearance 0)
		)
		(min_thickness 0.25)
		(keepout
			(tracks not_allowed)
			(vias allowed)
			(pads allowed)
			(copperpour not_allowed)
			(footprints allowed)
		)
		(placement
			(enabled no)
			(sheetname "")
		)
		(fill yes
			(thermal_gap 0.5)
			(thermal_bridge_width 0.5)
			(island_removal_mode 0)
		)
		(polygon
			(pts
				(arc
					(start 265.055604 -252.566678)
					(mid 264.402824 -252.566678)
					(end 265.055604 -252.566678)
				)
			)
		)
	)
	(zone
		(layers "B.Cu" "In13.Cu" "In15.Cu")
		(hatch none 0.5)
		(connect_pads
			(clearance 0)
		)
		(min_thickness 0.25)
		(keepout
			(tracks not_allowed)
			(vias allowed)
			(pads allowed)
			(copperpour not_allowed)
			(footprints allowed)
		)
		(placement
			(enabled no)
			(sheetname "")
		)
		(fill yes
			(thermal_gap 0.5)
			(thermal_bridge_width 0.5)
			(island_removal_mode 0)
		)
		(polygon
			(pts
				(arc
					(start 409.3972 -403.883876)
					(mid 408.69362 -403.883876)
					(end 409.3972 -403.883876)
				)
			)
		)
	)
	(zone
		(layers "B.Cu" "In13.Cu" "In15.Cu")
		(hatch none 0.5)
		(connect_pads
			(clearance 0)
		)
		(min_thickness 0.25)
		(keepout
			(tracks not_allowed)
			(vias allowed)
			(pads allowed)
			(copperpour not_allowed)
			(footprints allowed)
		)
		(placement
			(enabled no)
			(sheetname "")
		)
		(fill yes
			(thermal_gap 0.5)
			(thermal_bridge_width 0.5)
			(island_removal_mode 0)
		)
		(polygon
			(pts
				(arc
					(start 346.859606 -268.569694)
					(mid 346.206826 -268.569694)
					(end 346.859606 -268.569694)
				)
			)
		)
	)
	(zone
		(layers "B.Cu" "In13.Cu" "In15.Cu")
		(hatch none 0.5)
		(connect_pads
			(clearance 0)
		)
		(min_thickness 0.25)
		(keepout
			(tracks not_allowed)
			(vias allowed)
			(pads allowed)
			(copperpour not_allowed)
			(footprints allowed)
		)
		(placement
			(enabled no)
			(sheetname "")
		)
		(fill yes
			(thermal_gap 0.5)
			(thermal_bridge_width 0.5)
			(island_removal_mode 0)
		)
		(polygon
			(pts
				(arc
					(start 451.237604 -200.716642)
					(mid 450.584824 -200.716642)
					(end 451.237604 -200.716642)
				)
			)
		)
	)
	(zone
		(layers "B.Cu" "In13.Cu" "In15.Cu")
		(hatch none 0.5)
		(connect_pads
			(clearance 0)
		)
		(min_thickness 0.25)
		(keepout
			(tracks not_allowed)
			(vias allowed)
			(pads allowed)
			(copperpour not_allowed)
			(footprints allowed)
		)
		(placement
			(enabled no)
			(sheetname "")
		)
		(fill yes
			(thermal_gap 0.5)
			(thermal_bridge_width 0.5)
			(island_removal_mode 0)
		)
		(polygon
			(pts
				(arc
					(start 124.184156 -242.294918)
					(mid 123.531376 -242.294918)
					(end 124.184156 -242.294918)
				)
			)
		)
	)
	(zone
		(layers "B.Cu" "In13.Cu" "In15.Cu")
		(hatch none 0.5)
		(connect_pads
			(clearance 0)
		)
		(min_thickness 0.25)
		(keepout
			(tracks not_allowed)
			(vias allowed)
			(pads allowed)
			(copperpour not_allowed)
			(footprints allowed)
		)
		(placement
			(enabled no)
			(sheetname "")
		)
		(fill yes
			(thermal_gap 0.5)
			(thermal_bridge_width 0.5)
			(island_removal_mode 0)
		)
		(polygon
			(pts
				(arc
					(start 128.413002 -246.364506)
					(mid 127.760222 -246.364506)
					(end 128.413002 -246.364506)
				)
			)
		)
	)
	(zone
		(layers "B.Cu" "In13.Cu" "In15.Cu")
		(hatch none 0.5)
		(connect_pads
			(clearance 0)
		)
		(min_thickness 0.25)
		(keepout
			(tracks not_allowed)
			(vias allowed)
			(pads allowed)
			(copperpour not_allowed)
			(footprints allowed)
		)
		(placement
			(enabled no)
			(sheetname "")
		)
		(fill yes
			(thermal_gap 0.5)
			(thermal_bridge_width 0.5)
			(island_removal_mode 0)
		)
		(polygon
			(pts
				(arc
					(start 349.208852 -272.639282)
					(mid 348.556072 -272.639282)
					(end 349.208852 -272.639282)
				)
			)
		)
	)
	(zone
		(layers "B.Cu" "In13.Cu" "In15.Cu")
		(hatch none 0.5)
		(connect_pads
			(clearance 0)
		)
		(min_thickness 0.25)
		(keepout
			(tracks not_allowed)
			(vias allowed)
			(pads allowed)
			(copperpour not_allowed)
			(footprints allowed)
		)
		(placement
			(enabled no)
			(sheetname "")
		)
		(fill yes
			(thermal_gap 0.5)
			(thermal_bridge_width 0.5)
			(island_removal_mode 0)
		)
		(polygon
			(pts
				(arc
					(start 355.787452 -277.522432)
					(mid 355.134672 -277.522432)
					(end 355.787452 -277.522432)
				)
			)
		)
	)
	(zone
		(layers "B.Cu" "In13.Cu" "In15.Cu")
		(hatch none 0.5)
		(connect_pads
			(clearance 0)
		)
		(min_thickness 0.25)
		(keepout
			(tracks not_allowed)
			(vias allowed)
			(pads allowed)
			(copperpour not_allowed)
			(footprints allowed)
		)
		(placement
			(enabled no)
			(sheetname "")
		)
		(fill yes
			(thermal_gap 0.5)
			(thermal_bridge_width 0.5)
			(island_removal_mode 0)
		)
		(polygon
			(pts
				(arc
					(start 125.593602 -228.45903)
					(mid 124.940822 -228.45903)
					(end 125.593602 -228.45903)
				)
			)
		)
	)
	(zone
		(layers "B.Cu" "In13.Cu" "In15.Cu")
		(hatch none 0.5)
		(connect_pads
			(clearance 0)
		)
		(min_thickness 0.25)
		(keepout
			(tracks not_allowed)
			(vias allowed)
			(pads allowed)
			(copperpour not_allowed)
			(footprints allowed)
		)
		(placement
			(enabled no)
			(sheetname "")
		)
		(fill yes
			(thermal_gap 0.5)
			(thermal_bridge_width 0.5)
			(island_removal_mode 0)
		)
		(polygon
			(pts
				(arc
					(start 347.329252 -279.150318)
					(mid 346.676472 -279.150318)
					(end 347.329252 -279.150318)
				)
			)
		)
	)
	(zone
		(layers "B.Cu" "In13.Cu" "In15.Cu")
		(hatch none 0.5)
		(connect_pads
			(clearance 0)
		)
		(min_thickness 0.25)
		(keepout
			(tracks not_allowed)
			(vias allowed)
			(pads allowed)
			(copperpour not_allowed)
			(footprints allowed)
		)
		(placement
			(enabled no)
			(sheetname "")
		)
		(fill yes
			(thermal_gap 0.5)
			(thermal_bridge_width 0.5)
			(island_removal_mode 0)
		)
		(polygon
			(pts
				(arc
					(start 348.269052 -267.755878)
					(mid 347.616272 -267.755878)
					(end 348.269052 -267.755878)
				)
			)
		)
	)
	(zone
		(layers "B.Cu" "In13.Cu" "In15.Cu")
		(hatch none 0.5)
		(connect_pads
			(clearance 0)
		)
		(min_thickness 0.25)
		(keepout
			(tracks not_allowed)
			(vias allowed)
			(pads allowed)
			(copperpour not_allowed)
			(footprints allowed)
		)
		(placement
			(enabled no)
			(sheetname "")
		)
		(fill yes
			(thermal_gap 0.5)
			(thermal_bridge_width 0.5)
			(island_removal_mode 0)
		)
		(polygon
			(pts
				(arc
					(start 358.497124 -221.94774)
					(mid 357.844344 -221.94774)
					(end 358.497124 -221.94774)
				)
			)
		)
	)
	(zone
		(layers "B.Cu" "In13.Cu" "In15.Cu")
		(hatch none 0.5)
		(connect_pads
			(clearance 0)
		)
		(min_thickness 0.25)
		(keepout
			(tracks not_allowed)
			(vias allowed)
			(pads allowed)
			(copperpour not_allowed)
			(footprints allowed)
		)
		(placement
			(enabled no)
			(sheetname "")
		)
		(fill yes
			(thermal_gap 0.5)
			(thermal_bridge_width 0.5)
			(island_removal_mode 0)
		)
		(polygon
			(pts
				(arc
					(start 98.809556 -235.783882)
					(mid 98.156776 -235.783882)
					(end 98.809556 -235.783882)
				)
			)
		)
	)
	(zone
		(layers "B.Cu" "In13.Cu" "In15.Cu")
		(hatch none 0.5)
		(connect_pads
			(clearance 0)
		)
		(min_thickness 0.25)
		(keepout
			(tracks not_allowed)
			(vias allowed)
			(pads allowed)
			(copperpour not_allowed)
			(footprints allowed)
		)
		(placement
			(enabled no)
			(sheetname "")
		)
		(fill yes
			(thermal_gap 0.5)
			(thermal_bridge_width 0.5)
			(island_removal_mode 0)
		)
		(polygon
			(pts
				(arc
					(start 17.115536 -237.266734)
					(mid 16.462756 -237.266734)
					(end 17.115536 -237.266734)
				)
			)
		)
	)
	(zone
		(layers "B.Cu" "In13.Cu" "In15.Cu")
		(hatch none 0.5)
		(connect_pads
			(clearance 0)
		)
		(min_thickness 0.25)
		(keepout
			(tracks not_allowed)
			(vias allowed)
			(pads allowed)
			(copperpour not_allowed)
			(footprints allowed)
		)
		(placement
			(enabled no)
			(sheetname "")
		)
		(fill yes
			(thermal_gap 0.5)
			(thermal_bridge_width 0.5)
			(island_removal_mode 0)
		)
		(polygon
			(pts
				(arc
					(start 455.337672 -293.366698)
					(mid 454.684892 -293.366698)
					(end 455.337672 -293.366698)
				)
			)
		)
	)
	(zone
		(layers "B.Cu" "In13.Cu" "In15.Cu")
		(hatch none 0.5)
		(connect_pads
			(clearance 0)
		)
		(min_thickness 0.25)
		(keepout
			(tracks not_allowed)
			(vias allowed)
			(pads allowed)
			(copperpour not_allowed)
			(footprints allowed)
		)
		(placement
			(enabled no)
			(sheetname "")
		)
		(fill yes
			(thermal_gap 0.5)
			(thermal_bridge_width 0.5)
			(island_removal_mode 0)
		)
		(polygon
			(pts
				(arc
					(start 269.155672 -250.016772)
					(mid 268.502892 -250.016772)
					(end 269.155672 -250.016772)
				)
			)
		)
	)
	(zone
		(layers "B.Cu" "In13.Cu" "In15.Cu")
		(hatch none 0.5)
		(connect_pads
			(clearance 0)
		)
		(min_thickness 0.25)
		(keepout
			(tracks not_allowed)
			(vias allowed)
			(pads allowed)
			(copperpour not_allowed)
			(footprints allowed)
		)
		(placement
			(enabled no)
			(sheetname "")
		)
		(fill yes
			(thermal_gap 0.5)
			(thermal_bridge_width 0.5)
			(island_removal_mode 0)
		)
		(polygon
			(pts
				(arc
					(start 334.110838 -410.030168)
					(mid 333.407258 -410.030168)
					(end 334.110838 -410.030168)
				)
			)
		)
	)
	(zone
		(layers "B.Cu" "In13.Cu" "In15.Cu")
		(hatch none 0.5)
		(connect_pads
			(clearance 0)
		)
		(min_thickness 0.25)
		(keepout
			(tracks not_allowed)
			(vias allowed)
			(pads allowed)
			(copperpour not_allowed)
			(footprints allowed)
		)
		(placement
			(enabled no)
			(sheetname "")
		)
		(fill yes
			(thermal_gap 0.5)
			(thermal_bridge_width 0.5)
			(island_removal_mode 0)
		)
		(polygon
			(pts
				(arc
					(start 203.297536 -291.666676)
					(mid 202.644756 -291.666676)
					(end 203.297536 -291.666676)
				)
			)
		)
	)
	(zone
		(layers "B.Cu" "In13.Cu" "In15.Cu")
		(hatch none 0.5)
		(connect_pads
			(clearance 0)
		)
		(min_thickness 0.25)
		(keepout
			(tracks not_allowed)
			(vias allowed)
			(pads allowed)
			(copperpour not_allowed)
			(footprints allowed)
		)
		(placement
			(enabled no)
			(sheetname "")
		)
		(fill yes
			(thermal_gap 0.5)
			(thermal_bridge_width 0.5)
			(island_removal_mode 0)
		)
		(polygon
			(pts
				(arc
					(start 265.055604 -228.766624)
					(mid 264.402824 -228.766624)
					(end 265.055604 -228.766624)
				)
			)
		)
	)
	(zone
		(layers "B.Cu" "In13.Cu" "In15.Cu")
		(hatch none 0.5)
		(connect_pads
			(clearance 0)
		)
		(min_thickness 0.25)
		(keepout
			(tracks not_allowed)
			(vias allowed)
			(pads allowed)
			(copperpour not_allowed)
			(footprints allowed)
		)
		(placement
			(enabled no)
			(sheetname "")
		)
		(fill yes
			(thermal_gap 0.5)
			(thermal_bridge_width 0.5)
			(island_removal_mode 0)
		)
		(polygon
			(pts
				(arc
					(start 363.666024 -221.133924)
					(mid 363.013244 -221.133924)
					(end 363.666024 -221.133924)
				)
			)
		)
	)
	(zone
		(layers "B.Cu" "In13.Cu" "In15.Cu")
		(hatch none 0.5)
		(connect_pads
			(clearance 0)
		)
		(min_thickness 0.25)
		(keepout
			(tracks not_allowed)
			(vias allowed)
			(pads allowed)
			(copperpour not_allowed)
			(footprints allowed)
		)
		(placement
			(enabled no)
			(sheetname "")
		)
		(fill yes
			(thermal_gap 0.5)
			(thermal_bridge_width 0.5)
			(island_removal_mode 0)
		)
		(polygon
			(pts
				(arc
					(start 311.804558 -410.030168)
					(mid 311.100978 -410.030168)
					(end 311.804558 -410.030168)
				)
			)
		)
	)
	(zone
		(layers "B.Cu" "In13.Cu" "In15.Cu")
		(hatch none 0.5)
		(connect_pads
			(clearance 0)
		)
		(min_thickness 0.25)
		(keepout
			(tracks not_allowed)
			(vias allowed)
			(pads allowed)
			(copperpour not_allowed)
			(footprints allowed)
		)
		(placement
			(enabled no)
			(sheetname "")
		)
		(fill yes
			(thermal_gap 0.5)
			(thermal_bridge_width 0.5)
			(island_removal_mode 0)
		)
		(polygon
			(pts
				(arc
					(start 128.154938 -428.28972)
					(mid 127.345186 -428.28972)
					(end 128.154938 -428.28972)
				)
			)
		)
	)
	(zone
		(layers "B.Cu" "In13.Cu" "In15.Cu")
		(hatch none 0.5)
		(connect_pads
			(clearance 0)
		)
		(min_thickness 0.25)
		(keepout
			(tracks not_allowed)
			(vias allowed)
			(pads allowed)
			(copperpour not_allowed)
			(footprints allowed)
		)
		(placement
			(enabled no)
			(sheetname "")
		)
		(fill yes
			(thermal_gap 0.5)
			(thermal_bridge_width 0.5)
			(island_removal_mode 0)
		)
		(polygon
			(pts
				(arc
					(start 412.46044 -403.883876)
					(mid 411.75686 -403.883876)
					(end 412.46044 -403.883876)
				)
			)
		)
	)
	(zone
		(layers "B.Cu" "In13.Cu" "In15.Cu")
		(hatch none 0.5)
		(connect_pads
			(clearance 0)
		)
		(min_thickness 0.25)
		(keepout
			(tracks not_allowed)
			(vias allowed)
			(pads allowed)
			(copperpour not_allowed)
			(footprints allowed)
		)
		(placement
			(enabled no)
			(sheetname "")
		)
		(fill yes
			(thermal_gap 0.5)
			(thermal_bridge_width 0.5)
			(island_removal_mode 0)
		)
		(polygon
			(pts
				(arc
					(start 17.115536 -196.466714)
					(mid 16.462756 -196.466714)
					(end 17.115536 -196.466714)
				)
			)
		)
	)
	(zone
		(layers "B.Cu" "In13.Cu" "In15.Cu")
		(hatch none 0.5)
		(connect_pads
			(clearance 0)
		)
		(min_thickness 0.25)
		(keepout
			(tracks not_allowed)
			(vias allowed)
			(pads allowed)
			(copperpour not_allowed)
			(footprints allowed)
		)
		(placement
			(enabled no)
			(sheetname "")
		)
		(fill yes
			(thermal_gap 0.5)
			(thermal_bridge_width 0.5)
			(island_removal_mode 0)
		)
		(polygon
			(pts
				(arc
					(start 101.268784 -267.755878)
					(mid 100.616004 -267.755878)
					(end 101.268784 -267.755878)
				)
			)
		)
	)
	(zone
		(layers "B.Cu" "In13.Cu" "In15.Cu")
		(hatch none 0.5)
		(connect_pads
			(clearance 0)
		)
		(min_thickness 0.25)
		(keepout
			(tracks not_allowed)
			(vias allowed)
			(pads allowed)
			(copperpour not_allowed)
			(footprints allowed)
		)
		(placement
			(enabled no)
			(sheetname "")
		)
		(fill yes
			(thermal_gap 0.5)
			(thermal_bridge_width 0.5)
			(island_removal_mode 0)
		)
		(polygon
			(pts
				(arc
					(start 17.115536 -284.866588)
					(mid 16.462756 -284.866588)
					(end 17.115536 -284.866588)
				)
			)
		)
	)
	(zone
		(layers "B.Cu" "In13.Cu" "In15.Cu")
		(hatch none 0.5)
		(connect_pads
			(clearance 0)
		)
		(min_thickness 0.25)
		(keepout
			(tracks not_allowed)
			(vias allowed)
			(pads allowed)
			(copperpour not_allowed)
			(footprints allowed)
		)
		(placement
			(enabled no)
			(sheetname "")
		)
		(fill yes
			(thermal_gap 0.5)
			(thermal_bridge_width 0.5)
			(island_removal_mode 0)
		)
		(polygon
			(pts
				(arc
					(start 451.237604 -250.866656)
					(mid 450.584824 -250.866656)
					(end 451.237604 -250.866656)
				)
			)
		)
	)
	(zone
		(layers "B.Cu" "In13.Cu" "In15.Cu")
		(hatch none 0.5)
		(connect_pads
			(clearance 0)
		)
		(min_thickness 0.25)
		(keepout
			(tracks not_allowed)
			(vias allowed)
			(pads allowed)
			(copperpour not_allowed)
			(footprints allowed)
		)
		(placement
			(enabled no)
			(sheetname "")
		)
		(fill yes
			(thermal_gap 0.5)
			(thermal_bridge_width 0.5)
			(island_removal_mode 0)
		)
		(polygon
			(pts
				(arc
					(start 265.055604 -293.366698)
					(mid 264.402824 -293.366698)
					(end 265.055604 -293.366698)
				)
			)
		)
	)
	(zone
		(layers "B.Cu" "In13.Cu" "In15.Cu")
		(hatch none 0.5)
		(connect_pads
			(clearance 0)
		)
		(min_thickness 0.25)
		(keepout
			(tracks not_allowed)
			(vias allowed)
			(pads allowed)
			(copperpour not_allowed)
			(footprints allowed)
		)
		(placement
			(enabled no)
			(sheetname "")
		)
		(fill yes
			(thermal_gap 0.5)
			(thermal_bridge_width 0.5)
			(island_removal_mode 0)
		)
		(polygon
			(pts
				(arc
					(start 265.055604 -200.716642)
					(mid 264.402824 -200.716642)
					(end 265.055604 -200.716642)
				)
			)
		)
	)
	(zone
		(layers "B.Cu" "In13.Cu" "In15.Cu")
		(hatch none 0.5)
		(connect_pads
			(clearance 0)
		)
		(min_thickness 0.25)
		(keepout
			(tracks not_allowed)
			(vias allowed)
			(pads allowed)
			(copperpour not_allowed)
			(footprints allowed)
		)
		(placement
			(enabled no)
			(sheetname "")
		)
		(fill yes
			(thermal_gap 0.5)
			(thermal_bridge_width 0.5)
			(island_removal_mode 0)
		)
		(polygon
			(pts
				(arc
					(start 124.184156 -235.783882)
					(mid 123.531376 -235.783882)
					(end 124.184156 -235.783882)
				)
			)
		)
	)
	(zone
		(layers "B.Cu" "In13.Cu" "In15.Cu")
		(hatch none 0.5)
		(connect_pads
			(clearance 0)
		)
		(min_thickness 0.25)
		(keepout
			(tracks not_allowed)
			(vias allowed)
			(pads allowed)
			(copperpour not_allowed)
			(footprints allowed)
		)
		(placement
			(enabled no)
			(sheetname "")
		)
		(fill yes
			(thermal_gap 0.5)
			(thermal_bridge_width 0.5)
			(island_removal_mode 0)
		)
		(polygon
			(pts
				(arc
					(start 21.215604 -237.266734)
					(mid 20.562824 -237.266734)
					(end 21.215604 -237.266734)
				)
			)
		)
	)
	(zone
		(layers "B.Cu" "In13.Cu" "In15.Cu")
		(hatch none 0.5)
		(connect_pads
			(clearance 0)
		)
		(min_thickness 0.25)
		(keepout
			(tracks not_allowed)
			(vias allowed)
			(pads allowed)
			(copperpour not_allowed)
			(footprints allowed)
		)
		(placement
			(enabled no)
			(sheetname "")
		)
		(fill yes
			(thermal_gap 0.5)
			(thermal_bridge_width 0.5)
			(island_removal_mode 0)
		)
		(polygon
			(pts
				(arc
					(start 451.237604 -291.666676)
					(mid 450.584824 -291.666676)
					(end 451.237604 -291.666676)
				)
			)
		)
	)
	(zone
		(layers "B.Cu" "In13.Cu" "In15.Cu")
		(hatch none 0.5)
		(connect_pads
			(clearance 0)
		)
		(min_thickness 0.25)
		(keepout
			(tracks not_allowed)
			(vias allowed)
			(pads allowed)
			(copperpour not_allowed)
			(footprints allowed)
		)
		(placement
			(enabled no)
			(sheetname "")
		)
		(fill yes
			(thermal_gap 0.5)
			(thermal_bridge_width 0.5)
			(island_removal_mode 0)
		)
		(polygon
			(pts
				(arc
					(start 123.714002 -236.597952)
					(mid 123.061222 -236.597952)
					(end 123.714002 -236.597952)
				)
			)
		)
	)
	(zone
		(layers "B.Cu" "In13.Cu" "In15.Cu")
		(hatch none 0.5)
		(connect_pads
			(clearance 0)
		)
		(min_thickness 0.25)
		(keepout
			(tracks not_allowed)
			(vias allowed)
			(pads allowed)
			(copperpour not_allowed)
			(footprints allowed)
		)
		(placement
			(enabled no)
			(sheetname "")
		)
		(fill yes
			(thermal_gap 0.5)
			(thermal_bridge_width 0.5)
			(island_removal_mode 0)
		)
		(polygon
			(pts
				(arc
					(start 372.234206 -271.825212)
					(mid 371.581426 -271.825212)
					(end 372.234206 -271.825212)
				)
			)
		)
	)
	(zone
		(layers "B.Cu" "In13.Cu" "In15.Cu")
		(hatch none 0.5)
		(connect_pads
			(clearance 0)
		)
		(min_thickness 0.25)
		(keepout
			(tracks not_allowed)
			(vias allowed)
			(pads allowed)
			(copperpour not_allowed)
			(footprints allowed)
		)
		(placement
			(enabled no)
			(sheetname "")
		)
		(fill yes
			(thermal_gap 0.5)
			(thermal_bridge_width 0.5)
			(island_removal_mode 0)
		)
		(polygon
			(pts
				(arc
					(start 265.055604 -305.266598)
					(mid 264.402824 -305.266598)
					(end 265.055604 -305.266598)
				)
			)
		)
	)
	(zone
		(layers "B.Cu" "In13.Cu" "In15.Cu")
		(hatch none 0.5)
		(connect_pads
			(clearance 0)
		)
		(min_thickness 0.25)
		(keepout
			(tracks not_allowed)
			(vias allowed)
			(pads allowed)
			(copperpour not_allowed)
			(footprints allowed)
		)
		(placement
			(enabled no)
			(sheetname "")
		)
		(fill yes
			(thermal_gap 0.5)
			(thermal_bridge_width 0.5)
			(island_removal_mode 0)
		)
		(polygon
			(pts
				(arc
					(start 100.219002 -243.108988)
					(mid 99.566222 -243.108988)
					(end 100.219002 -243.108988)
				)
			)
		)
	)
	(zone
		(layers "B.Cu" "In13.Cu" "In15.Cu")
		(hatch none 0.5)
		(connect_pads
			(clearance 0)
		)
		(min_thickness 0.25)
		(keepout
			(tracks not_allowed)
			(vias allowed)
			(pads allowed)
			(copperpour not_allowed)
			(footprints allowed)
		)
		(placement
			(enabled no)
			(sheetname "")
		)
		(fill yes
			(thermal_gap 0.5)
			(thermal_bridge_width 0.5)
			(island_removal_mode 0)
		)
		(polygon
			(pts
				(arc
					(start 336.054954 -430.889918)
					(mid 335.245202 -430.889918)
					(end 336.054954 -430.889918)
				)
			)
		)
	)
	(zone
		(layers "B.Cu" "In13.Cu" "In15.Cu")
		(hatch none 0.5)
		(connect_pads
			(clearance 0)
		)
		(min_thickness 0.25)
		(keepout
			(tracks not_allowed)
			(vias allowed)
			(pads allowed)
			(copperpour not_allowed)
			(footprints allowed)
		)
		(placement
			(enabled no)
			(sheetname "")
		)
		(fill yes
			(thermal_gap 0.5)
			(thermal_bridge_width 0.5)
			(island_removal_mode 0)
		)
		(polygon
			(pts
				(arc
					(start 21.215604 -270.416782)
					(mid 20.562824 -270.416782)
					(end 21.215604 -270.416782)
				)
			)
		)
	)
	(zone
		(layers "B.Cu" "In13.Cu" "In15.Cu")
		(hatch none 0.5)
		(connect_pads
			(clearance 0)
		)
		(min_thickness 0.25)
		(keepout
			(tracks not_allowed)
			(vias allowed)
			(pads allowed)
			(copperpour not_allowed)
			(footprints allowed)
		)
		(placement
			(enabled no)
			(sheetname "")
		)
		(fill yes
			(thermal_gap 0.5)
			(thermal_bridge_width 0.5)
			(island_removal_mode 0)
		)
		(polygon
			(pts
				(arc
					(start 269.155672 -270.416782)
					(mid 268.502892 -270.416782)
					(end 269.155672 -270.416782)
				)
			)
		)
	)
	(zone
		(layers "B.Cu" "In13.Cu" "In15.Cu")
		(hatch none 0.5)
		(connect_pads
			(clearance 0)
		)
		(min_thickness 0.25)
		(keepout
			(tracks not_allowed)
			(vias allowed)
			(pads allowed)
			(copperpour not_allowed)
			(footprints allowed)
		)
		(placement
			(enabled no)
			(sheetname "")
		)
		(fill yes
			(thermal_gap 0.5)
			(thermal_bridge_width 0.5)
			(island_removal_mode 0)
		)
		(polygon
			(pts
				(arc
					(start 20.232116 -6.724396)
					(mid 19.528536 -6.724396)
					(end 20.232116 -6.724396)
				)
			)
		)
	)
	(zone
		(layers "B.Cu" "In13.Cu" "In15.Cu")
		(hatch none 0.5)
		(connect_pads
			(clearance 0)
		)
		(min_thickness 0.25)
		(keepout
			(tracks not_allowed)
			(vias allowed)
			(pads allowed)
			(copperpour not_allowed)
			(footprints allowed)
		)
		(placement
			(enabled no)
			(sheetname "")
		)
		(fill yes
			(thermal_gap 0.5)
			(thermal_bridge_width 0.5)
			(island_removal_mode 0)
		)
		(polygon
			(pts
				(arc
					(start 349.208852 -262.872474)
					(mid 348.556072 -262.872474)
					(end 349.208852 -262.872474)
				)
			)
		)
	)
	(zone
		(layers "B.Cu" "In13.Cu" "In15.Cu")
		(hatch none 0.5)
		(connect_pads
			(clearance 0)
		)
		(min_thickness 0.25)
		(keepout
			(tracks not_allowed)
			(vias allowed)
			(pads allowed)
			(copperpour not_allowed)
			(footprints allowed)
		)
		(placement
			(enabled no)
			(sheetname "")
		)
		(fill yes
			(thermal_gap 0.5)
			(thermal_bridge_width 0.5)
			(island_removal_mode 0)
		)
		(polygon
			(pts
				(arc
					(start 346.27947 -230.086662)
					(mid 345.62669 -230.086662)
					(end 346.27947 -230.086662)
				)
			)
		)
	)
	(zone
		(layers "B.Cu" "In13.Cu" "In15.Cu")
		(hatch none 0.5)
		(connect_pads
			(clearance 0)
		)
		(min_thickness 0.25)
		(keepout
			(tracks not_allowed)
			(vias allowed)
			(pads allowed)
			(copperpour not_allowed)
			(footprints allowed)
		)
		(placement
			(enabled no)
			(sheetname "")
		)
		(fill yes
			(thermal_gap 0.5)
			(thermal_bridge_width 0.5)
			(island_removal_mode 0)
		)
		(polygon
			(pts
				(arc
					(start 377.29287 -244.73662)
					(mid 376.64009 -244.73662)
					(end 377.29287 -244.73662)
				)
			)
		)
	)
	(zone
		(layers "B.Cu" "In13.Cu" "In15.Cu")
		(hatch none 0.5)
		(connect_pads
			(clearance 0)
		)
		(min_thickness 0.25)
		(keepout
			(tracks not_allowed)
			(vias allowed)
			(pads allowed)
			(copperpour not_allowed)
			(footprints allowed)
		)
		(placement
			(enabled no)
			(sheetname "")
		)
		(fill yes
			(thermal_gap 0.5)
			(thermal_bridge_width 0.5)
			(island_removal_mode 0)
		)
		(polygon
			(pts
				(arc
					(start 346.859606 -262.058658)
					(mid 346.206826 -262.058658)
					(end 346.859606 -262.058658)
				)
			)
		)
	)
	(zone
		(layers "B.Cu" "In13.Cu" "In15.Cu")
		(hatch none 0.5)
		(connect_pads
			(clearance 0)
		)
		(min_thickness 0.25)
		(keepout
			(tracks not_allowed)
			(vias allowed)
			(pads allowed)
			(copperpour not_allowed)
			(footprints allowed)
		)
		(placement
			(enabled no)
			(sheetname "")
		)
		(fill yes
			(thermal_gap 0.5)
			(thermal_bridge_width 0.5)
			(island_removal_mode 0)
		)
		(polygon
			(pts
				(arc
					(start 346.389452 -262.872474)
					(mid 345.736672 -262.872474)
					(end 346.389452 -262.872474)
				)
			)
		)
	)
	(zone
		(layers "B.Cu" "In13.Cu" "In15.Cu")
		(hatch none 0.5)
		(connect_pads
			(clearance 0)
		)
		(min_thickness 0.25)
		(keepout
			(tracks not_allowed)
			(vias allowed)
			(pads allowed)
			(copperpour not_allowed)
			(footprints allowed)
		)
		(placement
			(enabled no)
			(sheetname "")
		)
		(fill yes
			(thermal_gap 0.5)
			(thermal_bridge_width 0.5)
			(island_removal_mode 0)
		)
		(polygon
			(pts
				(arc
					(start 374.003824 -227.64496)
					(mid 373.351044 -227.64496)
					(end 374.003824 -227.64496)
				)
			)
		)
	)
	(zone
		(layers "B.Cu" "In13.Cu" "In15.Cu")
		(hatch none 0.5)
		(connect_pads
			(clearance 0)
		)
		(min_thickness 0.25)
		(keepout
			(tracks not_allowed)
			(vias allowed)
			(pads allowed)
			(copperpour not_allowed)
			(footprints allowed)
		)
		(placement
			(enabled no)
			(sheetname "")
		)
		(fill yes
			(thermal_gap 0.5)
			(thermal_bridge_width 0.5)
			(island_removal_mode 0)
		)
		(polygon
			(pts
				(arc
					(start 31.032196 -6.724396)
					(mid 30.328616 -6.724396)
					(end 31.032196 -6.724396)
				)
			)
		)
	)
	(zone
		(layers "B.Cu" "In13.Cu" "In15.Cu")
		(hatch none 0.5)
		(connect_pads
			(clearance 0)
		)
		(min_thickness 0.25)
		(keepout
			(tracks not_allowed)
			(vias allowed)
			(pads allowed)
			(copperpour not_allowed)
			(footprints allowed)
		)
		(placement
			(enabled no)
			(sheetname "")
		)
		(fill yes
			(thermal_gap 0.5)
			(thermal_bridge_width 0.5)
			(island_removal_mode 0)
		)
		(polygon
			(pts
				(arc
					(start 265.055604 -250.866656)
					(mid 264.402824 -250.866656)
					(end 265.055604 -250.866656)
				)
			)
		)
	)
	(zone
		(layers "B.Cu" "In13.Cu" "In15.Cu")
		(hatch none 0.5)
		(connect_pads
			(clearance 0)
		)
		(min_thickness 0.25)
		(keepout
			(tracks not_allowed)
			(vias allowed)
			(pads allowed)
			(copperpour not_allowed)
			(footprints allowed)
		)
		(placement
			(enabled no)
			(sheetname "")
		)
		(fill yes
			(thermal_gap 0.5)
			(thermal_bridge_width 0.5)
			(island_removal_mode 0)
		)
		(polygon
			(pts
				(arc
					(start 100.328984 -259.616956)
					(mid 99.676204 -259.616956)
					(end 100.328984 -259.616956)
				)
			)
		)
	)
	(zone
		(layers "B.Cu" "In13.Cu" "In15.Cu")
		(hatch none 0.5)
		(connect_pads
			(clearance 0)
		)
		(min_thickness 0.25)
		(keepout
			(tracks not_allowed)
			(vias allowed)
			(pads allowed)
			(copperpour not_allowed)
			(footprints allowed)
		)
		(placement
			(enabled no)
			(sheetname "")
		)
		(fill yes
			(thermal_gap 0.5)
			(thermal_bridge_width 0.5)
			(island_removal_mode 0)
		)
		(polygon
			(pts
				(arc
					(start 88.054942 -430.889918)
					(mid 87.24519 -430.889918)
					(end 88.054942 -430.889918)
				)
			)
		)
	)
	(zone
		(layers "B.Cu" "In13.Cu" "In15.Cu")
		(hatch none 0.5)
		(connect_pads
			(clearance 0)
		)
		(min_thickness 0.25)
		(keepout
			(tracks not_allowed)
			(vias allowed)
			(pads allowed)
			(copperpour not_allowed)
			(footprints allowed)
		)
		(placement
			(enabled no)
			(sheetname "")
		)
		(fill yes
			(thermal_gap 0.5)
			(thermal_bridge_width 0.5)
			(island_removal_mode 0)
		)
		(polygon
			(pts
				(arc
					(start 203.297536 -282.316682)
					(mid 202.644756 -282.316682)
					(end 203.297536 -282.316682)
				)
			)
		)
	)
	(zone
		(layers "B.Cu" "In13.Cu" "In15.Cu")
		(hatch none 0.5)
		(connect_pads
			(clearance 0)
		)
		(min_thickness 0.25)
		(keepout
			(tracks not_allowed)
			(vias allowed)
			(pads allowed)
			(copperpour not_allowed)
			(footprints allowed)
		)
		(placement
			(enabled no)
			(sheetname "")
		)
		(fill yes
			(thermal_gap 0.5)
			(thermal_bridge_width 0.5)
			(island_removal_mode 0)
		)
		(polygon
			(pts
				(arc
					(start 140.154914 -427.089824)
					(mid 139.345162 -427.089824)
					(end 140.154914 -427.089824)
				)
			)
		)
	)
	(zone
		(layers "B.Cu" "In13.Cu" "In15.Cu")
		(hatch none 0.5)
		(connect_pads
			(clearance 0)
		)
		(min_thickness 0.25)
		(keepout
			(tracks not_allowed)
			(vias allowed)
			(pads allowed)
			(copperpour not_allowed)
			(footprints allowed)
		)
		(placement
			(enabled no)
			(sheetname "")
		)
		(fill yes
			(thermal_gap 0.5)
			(thermal_bridge_width 0.5)
			(island_removal_mode 0)
		)
		(polygon
			(pts
				(arc
					(start 100.219002 -228.45903)
					(mid 99.566222 -228.45903)
					(end 100.219002 -228.45903)
				)
			)
		)
	)
	(zone
		(layers "B.Cu" "In13.Cu" "In15.Cu")
		(hatch none 0.5)
		(connect_pads
			(clearance 0)
		)
		(min_thickness 0.25)
		(keepout
			(tracks not_allowed)
			(vias allowed)
			(pads allowed)
			(copperpour not_allowed)
			(footprints allowed)
		)
		(placement
			(enabled no)
			(sheetname "")
		)
		(fill yes
			(thermal_gap 0.5)
			(thermal_bridge_width 0.5)
			(island_removal_mode 0)
		)
		(polygon
			(pts
				(arc
					(start 350.618806 -275.08073)
					(mid 349.966026 -275.08073)
					(end 350.618806 -275.08073)
				)
			)
		)
	)
	(zone
		(layers "B.Cu" "In13.Cu" "In15.Cu")
		(hatch none 0.5)
		(connect_pads
			(clearance 0)
		)
		(min_thickness 0.25)
		(keepout
			(tracks not_allowed)
			(vias allowed)
			(pads allowed)
			(copperpour not_allowed)
			(footprints allowed)
		)
		(placement
			(enabled no)
			(sheetname "")
		)
		(fill yes
			(thermal_gap 0.5)
			(thermal_bridge_width 0.5)
			(island_removal_mode 0)
		)
		(polygon
			(pts
				(arc
					(start 161.192464 -403.883876)
					(mid 160.488884 -403.883876)
					(end 161.192464 -403.883876)
				)
			)
		)
	)
	(zone
		(layers "B.Cu" "In13.Cu" "In15.Cu")
		(hatch none 0.5)
		(connect_pads
			(clearance 0)
		)
		(min_thickness 0.25)
		(keepout
			(tracks not_allowed)
			(vias allowed)
			(pads allowed)
			(copperpour not_allowed)
			(footprints allowed)
		)
		(placement
			(enabled no)
			(sheetname "")
		)
		(fill yes
			(thermal_gap 0.5)
			(thermal_bridge_width 0.5)
			(island_removal_mode 0)
		)
		(polygon
			(pts
				(arc
					(start 371.65407 -241.481102)
					(mid 371.00129 -241.481102)
					(end 371.65407 -241.481102)
				)
			)
		)
	)
	(zone
		(layers "B.Cu" "In13.Cu" "In15.Cu")
		(hatch none 0.5)
		(connect_pads
			(clearance 0)
		)
		(min_thickness 0.25)
		(keepout
			(tracks not_allowed)
			(vias allowed)
			(pads allowed)
			(copperpour not_allowed)
			(footprints allowed)
		)
		(placement
			(enabled no)
			(sheetname "")
		)
		(fill yes
			(thermal_gap 0.5)
			(thermal_bridge_width 0.5)
			(island_removal_mode 0)
		)
		(polygon
			(pts
				(arc
					(start 125.123956 -237.411514)
					(mid 124.471176 -237.411514)
					(end 125.123956 -237.411514)
				)
			)
		)
	)
	(zone
		(layers "B.Cu" "In13.Cu" "In15.Cu")
		(hatch none 0.5)
		(connect_pads
			(clearance 0)
		)
		(min_thickness 0.25)
		(keepout
			(tracks not_allowed)
			(vias allowed)
			(pads allowed)
			(copperpour not_allowed)
			(footprints allowed)
		)
		(placement
			(enabled no)
			(sheetname "")
		)
		(fill yes
			(thermal_gap 0.5)
			(thermal_bridge_width 0.5)
			(island_removal_mode 0)
		)
		(polygon
			(pts
				(arc
					(start 100.219002 -238.225584)
					(mid 99.566222 -238.225584)
					(end 100.219002 -238.225584)
				)
			)
		)
	)
	(zone
		(layers "B.Cu" "In13.Cu" "In15.Cu")
		(hatch none 0.5)
		(connect_pads
			(clearance 0)
		)
		(min_thickness 0.25)
		(keepout
			(tracks not_allowed)
			(vias allowed)
			(pads allowed)
			(copperpour not_allowed)
			(footprints allowed)
		)
		(placement
			(enabled no)
			(sheetname "")
		)
		(fill yes
			(thermal_gap 0.5)
			(thermal_bridge_width 0.5)
			(island_removal_mode 0)
		)
		(polygon
			(pts
				(arc
					(start 125.593602 -238.225584)
					(mid 124.940822 -238.225584)
					(end 125.593602 -238.225584)
				)
			)
		)
	)
	(zone
		(layers "B.Cu" "In13.Cu" "In15.Cu")
		(hatch none 0.5)
		(connect_pads
			(clearance 0)
		)
		(min_thickness 0.25)
		(keepout
			(tracks not_allowed)
			(vias allowed)
			(pads allowed)
			(copperpour not_allowed)
			(footprints allowed)
		)
		(placement
			(enabled no)
			(sheetname "")
		)
		(fill yes
			(thermal_gap 0.5)
			(thermal_bridge_width 0.5)
			(island_removal_mode 0)
		)
		(polygon
			(pts
				(arc
					(start 455.337672 -199.866758)
					(mid 454.684892 -199.866758)
					(end 455.337672 -199.866758)
				)
			)
		)
	)
	(zone
		(layers "B.Cu" "In13.Cu" "In15.Cu")
		(hatch none 0.5)
		(connect_pads
			(clearance 0)
		)
		(min_thickness 0.25)
		(keepout
			(tracks not_allowed)
			(vias allowed)
			(pads allowed)
			(copperpour not_allowed)
			(footprints allowed)
		)
		(placement
			(enabled no)
			(sheetname "")
		)
		(fill yes
			(thermal_gap 0.5)
			(thermal_bridge_width 0.5)
			(island_removal_mode 0)
		)
		(polygon
			(pts
				(arc
					(start 138.886184 -403.883876)
					(mid 138.182604 -403.883876)
					(end 138.886184 -403.883876)
				)
			)
		)
	)
	(zone
		(layers "B.Cu" "In13.Cu" "In15.Cu")
		(hatch none 0.5)
		(connect_pads
			(clearance 0)
		)
		(min_thickness 0.25)
		(keepout
			(tracks not_allowed)
			(vias allowed)
			(pads allowed)
			(copperpour not_allowed)
			(footprints allowed)
		)
		(placement
			(enabled no)
			(sheetname "")
		)
		(fill yes
			(thermal_gap 0.5)
			(thermal_bridge_width 0.5)
			(island_removal_mode 0)
		)
		(polygon
			(pts
				(arc
					(start 340.054946 -429.689768)
					(mid 339.245194 -429.689768)
					(end 340.054946 -429.689768)
				)
			)
		)
	)
	(zone
		(layers "B.Cu" "In13.Cu" "In15.Cu")
		(hatch none 0.5)
		(connect_pads
			(clearance 0)
		)
		(min_thickness 0.25)
		(keepout
			(tracks not_allowed)
			(vias allowed)
			(pads allowed)
			(copperpour not_allowed)
			(footprints allowed)
		)
		(placement
			(enabled no)
			(sheetname "")
		)
		(fill yes
			(thermal_gap 0.5)
			(thermal_bridge_width 0.5)
			(island_removal_mode 0)
		)
		(polygon
			(pts
				(arc
					(start 207.397604 -284.016704)
					(mid 206.744824 -284.016704)
					(end 207.397604 -284.016704)
				)
			)
		)
	)
	(zone
		(layers "B.Cu" "In13.Cu" "In15.Cu")
		(hatch none 0.5)
		(connect_pads
			(clearance 0)
		)
		(min_thickness 0.25)
		(keepout
			(tracks not_allowed)
			(vias allowed)
			(pads allowed)
			(copperpour not_allowed)
			(footprints allowed)
		)
		(placement
			(enabled no)
			(sheetname "")
		)
		(fill yes
			(thermal_gap 0.5)
			(thermal_bridge_width 0.5)
			(island_removal_mode 0)
		)
		(polygon
			(pts
				(arc
					(start 124.294138 -273.453098)
					(mid 123.641358 -273.453098)
					(end 124.294138 -273.453098)
				)
			)
		)
	)
	(zone
		(layers "B.Cu" "In13.Cu" "In15.Cu")
		(hatch none 0.5)
		(connect_pads
			(clearance 0)
		)
		(min_thickness 0.25)
		(keepout
			(tracks not_allowed)
			(vias allowed)
			(pads allowed)
			(copperpour not_allowed)
			(footprints allowed)
		)
		(placement
			(enabled no)
			(sheetname "")
		)
		(fill yes
			(thermal_gap 0.5)
			(thermal_bridge_width 0.5)
			(island_removal_mode 0)
		)
		(polygon
			(pts
				(arc
					(start 348.739206 -273.453098)
					(mid 348.086426 -273.453098)
					(end 348.739206 -273.453098)
				)
			)
		)
	)
	(zone
		(layers "B.Cu" "In13.Cu" "In15.Cu")
		(hatch none 0.5)
		(connect_pads
			(clearance 0)
		)
		(min_thickness 0.25)
		(keepout
			(tracks not_allowed)
			(vias allowed)
			(pads allowed)
			(copperpour not_allowed)
			(footprints allowed)
		)
		(placement
			(enabled no)
			(sheetname "")
		)
		(fill yes
			(thermal_gap 0.5)
			(thermal_bridge_width 0.5)
			(island_removal_mode 0)
		)
		(polygon
			(pts
				(arc
					(start 125.703584 -264.50036)
					(mid 125.050804 -264.50036)
					(end 125.703584 -264.50036)
				)
			)
		)
	)
	(zone
		(layers "B.Cu" "In13.Cu" "In15.Cu")
		(hatch none 0.5)
		(connect_pads
			(clearance 0)
		)
		(min_thickness 0.25)
		(keepout
			(tracks not_allowed)
			(vias allowed)
			(pads allowed)
			(copperpour not_allowed)
			(footprints allowed)
		)
		(placement
			(enabled no)
			(sheetname "")
		)
		(fill yes
			(thermal_gap 0.5)
			(thermal_bridge_width 0.5)
			(island_removal_mode 0)
		)
		(polygon
			(pts
				(arc
					(start 455.337672 -214.316564)
					(mid 454.684892 -214.316564)
					(end 455.337672 -214.316564)
				)
			)
		)
	)
	(zone
		(layers "B.Cu" "In13.Cu" "In15.Cu")
		(hatch none 0.5)
		(connect_pads
			(clearance 0)
		)
		(min_thickness 0.25)
		(keepout
			(tracks not_allowed)
			(vias allowed)
			(pads allowed)
			(copperpour not_allowed)
			(footprints allowed)
		)
		(placement
			(enabled no)
			(sheetname "")
		)
		(fill yes
			(thermal_gap 0.5)
			(thermal_bridge_width 0.5)
			(island_removal_mode 0)
		)
		(polygon
			(pts
				(arc
					(start 373.064024 -240.667286)
					(mid 372.411244 -240.667286)
					(end 373.064024 -240.667286)
				)
			)
		)
	)
	(zone
		(layers "B.Cu" "In13.Cu" "In15.Cu")
		(hatch none 0.5)
		(connect_pads
			(clearance 0)
		)
		(min_thickness 0.25)
		(keepout
			(tracks not_allowed)
			(vias allowed)
			(pads allowed)
			(copperpour not_allowed)
			(footprints allowed)
		)
		(placement
			(enabled no)
			(sheetname "")
		)
		(fill yes
			(thermal_gap 0.5)
			(thermal_bridge_width 0.5)
			(island_removal_mode 0)
		)
		(polygon
			(pts
				(arc
					(start 348.739206 -258.80314)
					(mid 348.086426 -258.80314)
					(end 348.739206 -258.80314)
				)
			)
		)
	)
	(zone
		(layers "B.Cu" "In13.Cu" "In15.Cu")
		(hatch none 0.5)
		(connect_pads
			(clearance 0)
		)
		(min_thickness 0.25)
		(keepout
			(tracks not_allowed)
			(vias allowed)
			(pads allowed)
			(copperpour not_allowed)
			(footprints allowed)
		)
		(placement
			(enabled no)
			(sheetname "")
		)
		(fill yes
			(thermal_gap 0.5)
			(thermal_bridge_width 0.5)
			(island_removal_mode 0)
		)
		(polygon
			(pts
				(arc
					(start 346.859606 -258.80314)
					(mid 346.206826 -258.80314)
					(end 346.859606 -258.80314)
				)
			)
		)
	)
	(zone
		(layers "B.Cu" "In13.Cu" "In15.Cu")
		(hatch none 0.5)
		(connect_pads
			(clearance 0)
		)
		(min_thickness 0.25)
		(keepout
			(tracks not_allowed)
			(vias allowed)
			(pads allowed)
			(copperpour not_allowed)
			(footprints allowed)
		)
		(placement
			(enabled no)
			(sheetname "")
		)
		(fill yes
			(thermal_gap 0.5)
			(thermal_bridge_width 0.5)
			(island_removal_mode 0)
		)
		(polygon
			(pts
				(arc
					(start 55.321708 -403.883876)
					(mid 54.618128 -403.883876)
					(end 55.321708 -403.883876)
				)
			)
		)
	)
	(zone
		(layers "B.Cu" "In13.Cu" "In15.Cu")
		(hatch none 0.5)
		(connect_pads
			(clearance 0)
		)
		(min_thickness 0.25)
		(keepout
			(tracks not_allowed)
			(vias allowed)
			(pads allowed)
			(copperpour not_allowed)
			(footprints allowed)
		)
		(placement
			(enabled no)
			(sheetname "")
		)
		(fill yes
			(thermal_gap 0.5)
			(thermal_bridge_width 0.5)
			(island_removal_mode 0)
		)
		(polygon
			(pts
				(arc
					(start 214.941404 -267.016738)
					(mid 214.288624 -267.016738)
					(end 214.941404 -267.016738)
				)
			)
		)
	)
	(zone
		(layers "B.Cu" "In13.Cu" "In15.Cu")
		(hatch none 0.5)
		(connect_pads
			(clearance 0)
		)
		(min_thickness 0.25)
		(keepout
			(tracks not_allowed)
			(vias allowed)
			(pads allowed)
			(copperpour not_allowed)
			(footprints allowed)
		)
		(placement
			(enabled no)
			(sheetname "")
		)
		(fill yes
			(thermal_gap 0.5)
			(thermal_bridge_width 0.5)
			(island_removal_mode 0)
		)
		(polygon
			(pts
				(arc
					(start 207.397604 -248.31675)
					(mid 206.744824 -248.31675)
					(end 207.397604 -248.31675)
				)
			)
		)
	)
	(zone
		(layers "B.Cu" "In13.Cu" "In15.Cu")
		(hatch none 0.5)
		(connect_pads
			(clearance 0)
		)
		(min_thickness 0.25)
		(keepout
			(tracks not_allowed)
			(vias allowed)
			(pads allowed)
			(copperpour not_allowed)
			(footprints allowed)
		)
		(placement
			(enabled no)
			(sheetname "")
		)
		(fill yes
			(thermal_gap 0.5)
			(thermal_bridge_width 0.5)
			(island_removal_mode 0)
		)
		(polygon
			(pts
				(arc
					(start 42.878502 -6.724396)
					(mid 42.174922 -6.724396)
					(end 42.878502 -6.724396)
				)
			)
		)
	)
	(zone
		(layers "B.Cu" "In13.Cu" "In15.Cu")
		(hatch none 0.5)
		(connect_pads
			(clearance 0)
		)
		(min_thickness 0.25)
		(keepout
			(tracks not_allowed)
			(vias allowed)
			(pads allowed)
			(copperpour not_allowed)
			(footprints allowed)
		)
		(placement
			(enabled no)
			(sheetname "")
		)
		(fill yes
			(thermal_gap 0.5)
			(thermal_bridge_width 0.5)
			(island_removal_mode 0)
		)
		(polygon
			(pts
				(arc
					(start 269.155672 -263.616694)
					(mid 268.502892 -263.616694)
					(end 269.155672 -263.616694)
				)
			)
		)
	)
	(zone
		(layers "B.Cu" "In13.Cu" "In15.Cu")
		(hatch none 0.5)
		(connect_pads
			(clearance 0)
		)
		(min_thickness 0.25)
		(keepout
			(tracks not_allowed)
			(vias allowed)
			(pads allowed)
			(copperpour not_allowed)
			(footprints allowed)
		)
		(placement
			(enabled no)
			(sheetname "")
		)
		(fill yes
			(thermal_gap 0.5)
			(thermal_bridge_width 0.5)
			(island_removal_mode 0)
		)
		(polygon
			(pts
				(arc
					(start 21.215604 -260.21665)
					(mid 20.562824 -260.21665)
					(end 21.215604 -260.21665)
				)
			)
		)
	)
	(zone
		(layers "B.Cu" "In13.Cu" "In15.Cu")
		(hatch none 0.5)
		(connect_pads
			(clearance 0)
		)
		(min_thickness 0.25)
		(keepout
			(tracks not_allowed)
			(vias allowed)
			(pads allowed)
			(copperpour not_allowed)
			(footprints allowed)
		)
		(placement
			(enabled no)
			(sheetname "")
		)
		(fill yes
			(thermal_gap 0.5)
			(thermal_bridge_width 0.5)
			(island_removal_mode 0)
		)
		(polygon
			(pts
				(arc
					(start 125.233938 -275.08073)
					(mid 124.581158 -275.08073)
					(end 125.233938 -275.08073)
				)
			)
		)
	)
	(zone
		(layers "B.Cu" "In13.Cu" "In15.Cu")
		(hatch none 0.5)
		(connect_pads
			(clearance 0)
		)
		(min_thickness 0.25)
		(keepout
			(tracks not_allowed)
			(vias allowed)
			(pads allowed)
			(copperpour not_allowed)
			(footprints allowed)
		)
		(placement
			(enabled no)
			(sheetname "")
		)
		(fill yes
			(thermal_gap 0.5)
			(thermal_bridge_width 0.5)
			(island_removal_mode 0)
		)
		(polygon
			(pts
				(arc
					(start 203.297536 -277.216616)
					(mid 202.644756 -277.216616)
					(end 203.297536 -277.216616)
				)
			)
		)
	)
	(zone
		(layers "B.Cu" "In13.Cu" "In15.Cu")
		(hatch none 0.5)
		(connect_pads
			(clearance 0)
		)
		(min_thickness 0.25)
		(keepout
			(tracks not_allowed)
			(vias allowed)
			(pads allowed)
			(copperpour not_allowed)
			(footprints allowed)
		)
		(placement
			(enabled no)
			(sheetname "")
		)
		(fill yes
			(thermal_gap 0.5)
			(thermal_bridge_width 0.5)
			(island_removal_mode 0)
		)
		(polygon
			(pts
				(arc
					(start 265.055604 -218.566746)
					(mid 264.402824 -218.566746)
					(end 265.055604 -218.566746)
				)
			)
		)
	)
	(zone
		(layers "B.Cu" "In13.Cu" "In15.Cu")
		(hatch none 0.5)
		(connect_pads
			(clearance 0)
		)
		(min_thickness 0.25)
		(keepout
			(tracks not_allowed)
			(vias allowed)
			(pads allowed)
			(copperpour not_allowed)
			(footprints allowed)
		)
		(placement
			(enabled no)
			(sheetname "")
		)
		(fill yes
			(thermal_gap 0.5)
			(thermal_bridge_width 0.5)
			(island_removal_mode 0)
		)
		(polygon
			(pts
				(arc
					(start 373.643652 -261.244842)
					(mid 372.990872 -261.244842)
					(end 373.643652 -261.244842)
				)
			)
		)
	)
	(zone
		(layers "B.Cu" "In13.Cu" "In15.Cu")
		(hatch none 0.5)
		(connect_pads
			(clearance 0)
		)
		(min_thickness 0.25)
		(keepout
			(tracks not_allowed)
			(vias allowed)
			(pads allowed)
			(copperpour not_allowed)
			(footprints allowed)
		)
		(placement
			(enabled no)
			(sheetname "")
		)
		(fill yes
			(thermal_gap 0.5)
			(thermal_bridge_width 0.5)
			(island_removal_mode 0)
		)
		(polygon
			(pts
				(arc
					(start 396.28064 -403.883876)
					(mid 395.57706 -403.883876)
					(end 396.28064 -403.883876)
				)
			)
		)
	)
	(zone
		(layers "B.Cu" "In13.Cu" "In15.Cu")
		(hatch none 0.5)
		(connect_pads
			(clearance 0)
		)
		(min_thickness 0.25)
		(keepout
			(tracks not_allowed)
			(vias allowed)
			(pads allowed)
			(copperpour not_allowed)
			(footprints allowed)
		)
		(placement
			(enabled no)
			(sheetname "")
		)
		(fill yes
			(thermal_gap 0.5)
			(thermal_bridge_width 0.5)
			(island_removal_mode 0)
		)
		(polygon
			(pts
				(arc
					(start 392.154918 -428.28972)
					(mid 391.345166 -428.28972)
					(end 392.154918 -428.28972)
				)
			)
		)
	)
	(zone
		(layers "B.Cu" "In13.Cu" "In15.Cu")
		(hatch none 0.5)
		(connect_pads
			(clearance 0)
		)
		(min_thickness 0.25)
		(keepout
			(tracks not_allowed)
			(vias allowed)
			(pads allowed)
			(copperpour not_allowed)
			(footprints allowed)
		)
		(placement
			(enabled no)
			(sheetname "")
		)
		(fill yes
			(thermal_gap 0.5)
			(thermal_bridge_width 0.5)
			(island_removal_mode 0)
		)
		(polygon
			(pts
				(arc
					(start 317.054992 -431.889916)
					(mid 316.24524 -431.889916)
					(end 317.054992 -431.889916)
				)
			)
		)
	)
	(zone
		(layers "B.Cu" "In13.Cu" "In15.Cu")
		(hatch none 0.5)
		(connect_pads
			(clearance 0)
		)
		(min_thickness 0.25)
		(keepout
			(tracks not_allowed)
			(vias allowed)
			(pads allowed)
			(copperpour not_allowed)
			(footprints allowed)
		)
		(placement
			(enabled no)
			(sheetname "")
		)
		(fill yes
			(thermal_gap 0.5)
			(thermal_bridge_width 0.5)
			(island_removal_mode 0)
		)
		(polygon
			(pts
				(arc
					(start 372.234206 -253.919736)
					(mid 371.581426 -253.919736)
					(end 372.234206 -253.919736)
				)
			)
		)
	)
	(zone
		(layers "B.Cu" "In13.Cu" "In15.Cu")
		(hatch none 0.5)
		(connect_pads
			(clearance 0)
		)
		(min_thickness 0.25)
		(keepout
			(tracks not_allowed)
			(vias allowed)
			(pads allowed)
			(copperpour not_allowed)
			(footprints allowed)
		)
		(placement
			(enabled no)
			(sheetname "")
		)
		(fill yes
			(thermal_gap 0.5)
			(thermal_bridge_width 0.5)
			(island_removal_mode 0)
		)
		(polygon
			(pts
				(arc
					(start 373.643652 -274.266914)
					(mid 372.990872 -274.266914)
					(end 373.643652 -274.266914)
				)
			)
		)
	)
	(zone
		(layers "B.Cu" "In13.Cu" "In15.Cu")
		(hatch none 0.5)
		(connect_pads
			(clearance 0)
		)
		(min_thickness 0.25)
		(keepout
			(tracks not_allowed)
			(vias allowed)
			(pads allowed)
			(copperpour not_allowed)
			(footprints allowed)
		)
		(placement
			(enabled no)
			(sheetname "")
		)
		(fill yes
			(thermal_gap 0.5)
			(thermal_bridge_width 0.5)
			(island_removal_mode 0)
		)
		(polygon
			(pts
				(arc
					(start 269.155672 -304.416714)
					(mid 268.502892 -304.416714)
					(end 269.155672 -304.416714)
				)
			)
		)
	)
	(zone
		(layers "B.Cu" "In13.Cu" "In15.Cu")
		(hatch none 0.5)
		(connect_pads
			(clearance 0)
		)
		(min_thickness 0.25)
		(keepout
			(tracks not_allowed)
			(vias allowed)
			(pads allowed)
			(copperpour not_allowed)
			(footprints allowed)
		)
		(placement
			(enabled no)
			(sheetname "")
		)
		(fill yes
			(thermal_gap 0.5)
			(thermal_bridge_width 0.5)
			(island_removal_mode 0)
		)
		(polygon
			(pts
				(arc
					(start 414.66008 -403.883876)
					(mid 413.9565 -403.883876)
					(end 414.66008 -403.883876)
				)
			)
		)
	)
	(zone
		(layers "B.Cu" "In13.Cu" "In15.Cu")
		(hatch none 0.5)
		(connect_pads
			(clearance 0)
		)
		(min_thickness 0.25)
		(keepout
			(tracks not_allowed)
			(vias allowed)
			(pads allowed)
			(copperpour not_allowed)
			(footprints allowed)
		)
		(placement
			(enabled no)
			(sheetname "")
		)
		(fill yes
			(thermal_gap 0.5)
			(thermal_bridge_width 0.5)
			(island_removal_mode 0)
		)
		(polygon
			(pts
				(arc
					(start 455.337672 -304.416714)
					(mid 454.684892 -304.416714)
					(end 455.337672 -304.416714)
				)
			)
		)
	)
	(zone
		(layers "B.Cu" "In13.Cu" "In15.Cu")
		(hatch none 0.5)
		(connect_pads
			(clearance 0)
		)
		(min_thickness 0.25)
		(keepout
			(tracks not_allowed)
			(vias allowed)
			(pads allowed)
			(copperpour not_allowed)
			(footprints allowed)
		)
		(placement
			(enabled no)
			(sheetname "")
		)
		(fill yes
			(thermal_gap 0.5)
			(thermal_bridge_width 0.5)
			(island_removal_mode 0)
		)
		(polygon
			(pts
				(arc
					(start 207.397604 -201.56678)
					(mid 206.744824 -201.56678)
					(end 207.397604 -201.56678)
				)
			)
		)
	)
	(zone
		(layers "B.Cu" "In13.Cu" "In15.Cu")
		(hatch none 0.5)
		(connect_pads
			(clearance 0)
		)
		(min_thickness 0.25)
		(keepout
			(tracks not_allowed)
			(vias allowed)
			(pads allowed)
			(copperpour not_allowed)
			(footprints allowed)
		)
		(placement
			(enabled no)
			(sheetname "")
		)
		(fill yes
			(thermal_gap 0.5)
			(thermal_bridge_width 0.5)
			(island_removal_mode 0)
		)
		(polygon
			(pts
				(arc
					(start 123.823984 -274.266914)
					(mid 123.171204 -274.266914)
					(end 123.823984 -274.266914)
				)
			)
		)
	)
	(zone
		(layers "B.Cu" "In13.Cu" "In15.Cu")
		(hatch none 0.5)
		(connect_pads
			(clearance 0)
		)
		(min_thickness 0.25)
		(keepout
			(tracks not_allowed)
			(vias allowed)
			(pads allowed)
			(copperpour not_allowed)
			(footprints allowed)
		)
		(placement
			(enabled no)
			(sheetname "")
		)
		(fill yes
			(thermal_gap 0.5)
			(thermal_bridge_width 0.5)
			(island_removal_mode 0)
		)
		(polygon
			(pts
				(arc
					(start 207.397604 -306.116736)
					(mid 206.744824 -306.116736)
					(end 207.397604 -306.116736)
				)
			)
		)
	)
	(zone
		(layers "B.Cu" "In13.Cu" "In15.Cu")
		(hatch none 0.5)
		(connect_pads
			(clearance 0)
		)
		(min_thickness 0.25)
		(keepout
			(tracks not_allowed)
			(vias allowed)
			(pads allowed)
			(copperpour not_allowed)
			(footprints allowed)
		)
		(placement
			(enabled no)
			(sheetname "")
		)
		(fill yes
			(thermal_gap 0.5)
			(thermal_bridge_width 0.5)
			(island_removal_mode 0)
		)
		(polygon
			(pts
				(arc
					(start 98.919538 -258.80314)
					(mid 98.266758 -258.80314)
					(end 98.919538 -258.80314)
				)
			)
		)
	)
	(zone
		(layers "B.Cu" "In13.Cu" "In15.Cu")
		(hatch none 0.5)
		(connect_pads
			(clearance 0)
		)
		(min_thickness 0.25)
		(keepout
			(tracks not_allowed)
			(vias allowed)
			(pads allowed)
			(copperpour not_allowed)
			(footprints allowed)
		)
		(placement
			(enabled no)
			(sheetname "")
		)
		(fill yes
			(thermal_gap 0.5)
			(thermal_bridge_width 0.5)
			(island_removal_mode 0)
		)
		(polygon
			(pts
				(arc
					(start 17.115536 -277.216616)
					(mid 16.462756 -277.216616)
					(end 17.115536 -277.216616)
				)
			)
		)
	)
	(zone
		(layers "B.Cu" "In13.Cu" "In15.Cu")
		(hatch none 0.5)
		(connect_pads
			(clearance 0)
		)
		(min_thickness 0.25)
		(keepout
			(tracks not_allowed)
			(vias allowed)
			(pads allowed)
			(copperpour not_allowed)
			(footprints allowed)
		)
		(placement
			(enabled no)
			(sheetname "")
		)
		(fill yes
			(thermal_gap 0.5)
			(thermal_bridge_width 0.5)
			(island_removal_mode 0)
		)
		(polygon
			(pts
				(arc
					(start 346.749624 -234.15625)
					(mid 346.096844 -234.15625)
					(end 346.749624 -234.15625)
				)
			)
		)
	)
	(zone
		(layers "B.Cu" "In13.Cu" "In15.Cu")
		(hatch none 0.5)
		(connect_pads
			(clearance 0)
		)
		(min_thickness 0.25)
		(keepout
			(tracks not_allowed)
			(vias allowed)
			(pads allowed)
			(copperpour not_allowed)
			(footprints allowed)
		)
		(placement
			(enabled no)
			(sheetname "")
		)
		(fill yes
			(thermal_gap 0.5)
			(thermal_bridge_width 0.5)
			(island_removal_mode 0)
		)
		(polygon
			(pts
				(arc
					(start 21.215604 -251.716794)
					(mid 20.562824 -251.716794)
					(end 21.215604 -251.716794)
				)
			)
		)
	)
	(zone
		(layers "B.Cu" "In13.Cu" "In15.Cu")
		(hatch none 0.5)
		(connect_pads
			(clearance 0)
		)
		(min_thickness 0.25)
		(keepout
			(tracks not_allowed)
			(vias allowed)
			(pads allowed)
			(copperpour not_allowed)
			(footprints allowed)
		)
		(placement
			(enabled no)
			(sheetname "")
		)
		(fill yes
			(thermal_gap 0.5)
			(thermal_bridge_width 0.5)
			(island_removal_mode 0)
		)
		(polygon
			(pts
				(arc
					(start 455.337672 -220.266768)
					(mid 454.684892 -220.266768)
					(end 455.337672 -220.266768)
				)
			)
		)
	)
	(zone
		(layers "B.Cu" "In13.Cu" "In15.Cu")
		(hatch none 0.5)
		(connect_pads
			(clearance 0)
		)
		(min_thickness 0.25)
		(keepout
			(tracks not_allowed)
			(vias allowed)
			(pads allowed)
			(copperpour not_allowed)
			(footprints allowed)
		)
		(placement
			(enabled no)
			(sheetname "")
		)
		(fill yes
			(thermal_gap 0.5)
			(thermal_bridge_width 0.5)
			(island_removal_mode 0)
		)
		(polygon
			(pts
				(arc
					(start 372.124224 -245.55069)
					(mid 371.471444 -245.55069)
					(end 372.124224 -245.55069)
				)
			)
		)
	)
	(zone
		(layers "B.Cu" "In13.Cu" "In15.Cu")
		(hatch none 0.5)
		(connect_pads
			(clearance 0)
		)
		(min_thickness 0.25)
		(keepout
			(tracks not_allowed)
			(vias allowed)
			(pads allowed)
			(copperpour not_allowed)
			(footprints allowed)
		)
		(placement
			(enabled no)
			(sheetname "")
		)
		(fill yes
			(thermal_gap 0.5)
			(thermal_bridge_width 0.5)
			(island_removal_mode 0)
		)
		(polygon
			(pts
				(arc
					(start 21.215604 -229.616762)
					(mid 20.562824 -229.616762)
					(end 21.215604 -229.616762)
				)
			)
		)
	)
	(zone
		(layers "B.Cu" "In13.Cu" "In15.Cu")
		(hatch none 0.5)
		(connect_pads
			(clearance 0)
		)
		(min_thickness 0.25)
		(keepout
			(tracks not_allowed)
			(vias allowed)
			(pads allowed)
			(copperpour not_allowed)
			(footprints allowed)
		)
		(placement
			(enabled no)
			(sheetname "")
		)
		(fill yes
			(thermal_gap 0.5)
			(thermal_bridge_width 0.5)
			(island_removal_mode 0)
		)
		(polygon
			(pts
				(arc
					(start 335.111852 -280.778204)
					(mid 334.459072 -280.778204)
					(end 335.111852 -280.778204)
				)
			)
		)
	)
	(zone
		(layers "B.Cu" "In13.Cu" "In15.Cu")
		(hatch none 0.5)
		(connect_pads
			(clearance 0)
		)
		(min_thickness 0.25)
		(keepout
			(tracks not_allowed)
			(vias allowed)
			(pads allowed)
			(copperpour not_allowed)
			(footprints allowed)
		)
		(placement
			(enabled no)
			(sheetname "")
		)
		(fill yes
			(thermal_gap 0.5)
			(thermal_bridge_width 0.5)
			(island_removal_mode 0)
		)
		(polygon
			(pts
				(arc
					(start 125.703584 -256.361438)
					(mid 125.050804 -256.361438)
					(end 125.703584 -256.361438)
				)
			)
		)
	)
	(zone
		(layers "B.Cu" "In13.Cu" "In15.Cu")
		(hatch none 0.5)
		(connect_pads
			(clearance 0)
		)
		(min_thickness 0.25)
		(keepout
			(tracks not_allowed)
			(vias allowed)
			(pads allowed)
			(copperpour not_allowed)
			(footprints allowed)
		)
		(placement
			(enabled no)
			(sheetname "")
		)
		(fill yes
			(thermal_gap 0.5)
			(thermal_bridge_width 0.5)
			(island_removal_mode 0)
		)
		(polygon
			(pts
				(arc
					(start 104.088184 -282.405836)
					(mid 103.435404 -282.405836)
					(end 104.088184 -282.405836)
				)
			)
		)
	)
	(zone
		(layers "B.Cu" "In13.Cu" "In15.Cu")
		(hatch none 0.5)
		(connect_pads
			(clearance 0)
		)
		(min_thickness 0.25)
		(keepout
			(tracks not_allowed)
			(vias allowed)
			(pads allowed)
			(copperpour not_allowed)
			(footprints allowed)
		)
		(placement
			(enabled no)
			(sheetname "")
		)
		(fill yes
			(thermal_gap 0.5)
			(thermal_bridge_width 0.5)
			(island_removal_mode 0)
		)
		(polygon
			(pts
				(arc
					(start 148.075904 -403.883876)
					(mid 147.372324 -403.883876)
					(end 148.075904 -403.883876)
				)
			)
		)
	)
	(zone
		(layers "B.Cu" "In13.Cu" "In15.Cu")
		(hatch none 0.5)
		(connect_pads
			(clearance 0)
		)
		(min_thickness 0.25)
		(keepout
			(tracks not_allowed)
			(vias allowed)
			(pads allowed)
			(copperpour not_allowed)
			(footprints allowed)
		)
		(placement
			(enabled no)
			(sheetname "")
		)
		(fill yes
			(thermal_gap 0.5)
			(thermal_bridge_width 0.5)
			(island_removal_mode 0)
		)
		(polygon
			(pts
				(arc
					(start 371.764052 -261.244842)
					(mid 371.111272 -261.244842)
					(end 371.764052 -261.244842)
				)
			)
		)
	)
	(zone
		(layers "B.Cu" "In13.Cu" "In15.Cu")
		(hatch none 0.5)
		(connect_pads
			(clearance 0)
		)
		(min_thickness 0.25)
		(keepout
			(tracks not_allowed)
			(vias allowed)
			(pads allowed)
			(copperpour not_allowed)
			(footprints allowed)
		)
		(placement
			(enabled no)
			(sheetname "")
		)
		(fill yes
			(thermal_gap 0.5)
			(thermal_bridge_width 0.5)
			(island_removal_mode 0)
		)
		(polygon
			(pts
				(arc
					(start 374.113806 -275.08073)
					(mid 373.461026 -275.08073)
					(end 374.113806 -275.08073)
				)
			)
		)
	)
	(zone
		(layers "B.Cu" "In13.Cu" "In15.Cu")
		(hatch none 0.5)
		(connect_pads
			(clearance 0)
		)
		(min_thickness 0.25)
		(keepout
			(tracks not_allowed)
			(vias allowed)
			(pads allowed)
			(copperpour not_allowed)
			(footprints allowed)
		)
		(placement
			(enabled no)
			(sheetname "")
		)
		(fill yes
			(thermal_gap 0.5)
			(thermal_bridge_width 0.5)
			(island_removal_mode 0)
		)
		(polygon
			(pts
				(arc
					(start 308.741318 -410.030168)
					(mid 308.037738 -410.030168)
					(end 308.741318 -410.030168)
				)
			)
		)
	)
	(zone
		(layers "B.Cu" "In13.Cu" "In15.Cu")
		(hatch none 0.5)
		(connect_pads
			(clearance 0)
		)
		(min_thickness 0.25)
		(keepout
			(tracks not_allowed)
			(vias allowed)
			(pads allowed)
			(copperpour not_allowed)
			(footprints allowed)
		)
		(placement
			(enabled no)
			(sheetname "")
		)
		(fill yes
			(thermal_gap 0.5)
			(thermal_bridge_width 0.5)
			(island_removal_mode 0)
		)
		(polygon
			(pts
				(arc
					(start 399.34388 -403.883876)
					(mid 398.6403 -403.883876)
					(end 399.34388 -403.883876)
				)
			)
		)
	)
	(zone
		(layers "B.Cu" "In13.Cu" "In15.Cu")
		(hatch none 0.5)
		(connect_pads
			(clearance 0)
		)
		(min_thickness 0.25)
		(keepout
			(tracks not_allowed)
			(vias allowed)
			(pads allowed)
			(copperpour not_allowed)
			(footprints allowed)
		)
		(placement
			(enabled no)
			(sheetname "")
		)
		(fill yes
			(thermal_gap 0.5)
			(thermal_bridge_width 0.5)
			(island_removal_mode 0)
		)
		(polygon
			(pts
				(arc
					(start 207.397604 -234.716574)
					(mid 206.744824 -234.716574)
					(end 207.397604 -234.716574)
				)
			)
		)
	)
	(zone
		(layers "B.Cu" "In13.Cu" "In15.Cu")
		(hatch none 0.5)
		(connect_pads
			(clearance 0)
		)
		(min_thickness 0.25)
		(keepout
			(tracks not_allowed)
			(vias allowed)
			(pads allowed)
			(copperpour not_allowed)
			(footprints allowed)
		)
		(placement
			(enabled no)
			(sheetname "")
		)
		(fill yes
			(thermal_gap 0.5)
			(thermal_bridge_width 0.5)
			(island_removal_mode 0)
		)
		(polygon
			(pts
				(arc
					(start 214.941404 -259.366766)
					(mid 214.288624 -259.366766)
					(end 214.941404 -259.366766)
				)
			)
		)
	)
	(zone
		(layers "B.Cu" "In13.Cu" "In15.Cu")
		(hatch none 0.5)
		(connect_pads
			(clearance 0)
		)
		(min_thickness 0.25)
		(keepout
			(tracks not_allowed)
			(vias allowed)
			(pads allowed)
			(copperpour not_allowed)
			(footprints allowed)
		)
		(placement
			(enabled no)
			(sheetname "")
		)
		(fill yes
			(thermal_gap 0.5)
			(thermal_bridge_width 0.5)
			(island_removal_mode 0)
		)
		(polygon
			(pts
				(arc
					(start 451.237604 -202.416664)
					(mid 450.584824 -202.416664)
					(end 451.237604 -202.416664)
				)
			)
		)
	)
	(zone
		(layers "B.Cu" "In13.Cu" "In15.Cu")
		(hatch none 0.5)
		(connect_pads
			(clearance 0)
		)
		(min_thickness 0.25)
		(keepout
			(tracks not_allowed)
			(vias allowed)
			(pads allowed)
			(copperpour not_allowed)
			(footprints allowed)
		)
		(placement
			(enabled no)
			(sheetname "")
		)
		(fill yes
			(thermal_gap 0.5)
			(thermal_bridge_width 0.5)
			(island_removal_mode 0)
		)
		(polygon
			(pts
				(arc
					(start 25.636728 -4.962652)
					(mid 24.933148 -4.962652)
					(end 25.636728 -4.962652)
				)
			)
		)
	)
	(zone
		(layers "B.Cu" "In13.Cu" "In15.Cu")
		(hatch none 0.5)
		(connect_pads
			(clearance 0)
		)
		(min_thickness 0.25)
		(keepout
			(tracks not_allowed)
			(vias allowed)
			(pads allowed)
			(copperpour not_allowed)
			(footprints allowed)
		)
		(placement
			(enabled no)
			(sheetname "")
		)
		(fill yes
			(thermal_gap 0.5)
			(thermal_bridge_width 0.5)
			(island_removal_mode 0)
		)
		(polygon
			(pts
				(arc
					(start 317.931038 -410.030168)
					(mid 317.227458 -410.030168)
					(end 317.931038 -410.030168)
				)
			)
		)
	)
	(zone
		(layers "B.Cu" "In13.Cu" "In15.Cu")
		(hatch none 0.5)
		(connect_pads
			(clearance 0)
		)
		(min_thickness 0.25)
		(keepout
			(tracks not_allowed)
			(vias allowed)
			(pads allowed)
			(copperpour not_allowed)
			(footprints allowed)
		)
		(placement
			(enabled no)
			(sheetname "")
		)
		(fill yes
			(thermal_gap 0.5)
			(thermal_bridge_width 0.5)
			(island_removal_mode 0)
		)
		(polygon
			(pts
				(arc
					(start 362.256324 -221.94774)
					(mid 361.603544 -221.94774)
					(end 362.256324 -221.94774)
				)
			)
		)
	)
	(zone
		(layers "B.Cu" "In13.Cu" "In15.Cu")
		(hatch none 0.5)
		(connect_pads
			(clearance 0)
		)
		(min_thickness 0.25)
		(keepout
			(tracks not_allowed)
			(vias allowed)
			(pads allowed)
			(copperpour not_allowed)
			(footprints allowed)
		)
		(placement
			(enabled no)
			(sheetname "")
		)
		(fill yes
			(thermal_gap 0.5)
			(thermal_bridge_width 0.5)
			(island_removal_mode 0)
		)
		(polygon
			(pts
				(arc
					(start 370.71427 -226.831144)
					(mid 370.06149 -226.831144)
					(end 370.71427 -226.831144)
				)
			)
		)
	)
	(zone
		(layers "B.Cu" "In13.Cu" "In15.Cu")
		(hatch none 0.5)
		(connect_pads
			(clearance 0)
		)
		(min_thickness 0.25)
		(keepout
			(tracks not_allowed)
			(vias allowed)
			(pads allowed)
			(copperpour not_allowed)
			(footprints allowed)
		)
		(placement
			(enabled no)
			(sheetname "")
		)
		(fill yes
			(thermal_gap 0.5)
			(thermal_bridge_width 0.5)
			(island_removal_mode 0)
		)
		(polygon
			(pts
				(arc
					(start 98.339402 -234.970066)
					(mid 97.686622 -234.970066)
					(end 98.339402 -234.970066)
				)
			)
		)
	)
	(zone
		(layers "B.Cu" "In13.Cu" "In15.Cu")
		(hatch none 0.5)
		(connect_pads
			(clearance 0)
		)
		(min_thickness 0.25)
		(keepout
			(tracks not_allowed)
			(vias allowed)
			(pads allowed)
			(copperpour not_allowed)
			(footprints allowed)
		)
		(placement
			(enabled no)
			(sheetname "")
		)
		(fill yes
			(thermal_gap 0.5)
			(thermal_bridge_width 0.5)
			(island_removal_mode 0)
		)
		(polygon
			(pts
				(arc
					(start 347.21927 -239.853216)
					(mid 346.56649 -239.853216)
					(end 347.21927 -239.853216)
				)
			)
		)
	)
	(zone
		(layers "B.Cu" "In13.Cu" "In15.Cu")
		(hatch none 0.5)
		(connect_pads
			(clearance 0)
		)
		(min_thickness 0.25)
		(keepout
			(tracks not_allowed)
			(vias allowed)
			(pads allowed)
			(copperpour not_allowed)
			(footprints allowed)
		)
		(placement
			(enabled no)
			(sheetname "")
		)
		(fill yes
			(thermal_gap 0.5)
			(thermal_bridge_width 0.5)
			(island_removal_mode 0)
		)
		(polygon
			(pts
				(arc
					(start 394.154914 -426.089826)
					(mid 393.345162 -426.089826)
					(end 394.154914 -426.089826)
				)
			)
		)
	)
	(zone
		(layers "B.Cu" "In13.Cu" "In15.Cu")
		(hatch none 0.5)
		(connect_pads
			(clearance 0)
		)
		(min_thickness 0.25)
		(keepout
			(tracks not_allowed)
			(vias allowed)
			(pads allowed)
			(copperpour not_allowed)
			(footprints allowed)
		)
		(placement
			(enabled no)
			(sheetname "")
		)
		(fill yes
			(thermal_gap 0.5)
			(thermal_bridge_width 0.5)
			(island_removal_mode 0)
		)
		(polygon
			(pts
				(arc
					(start 76.054966 -430.889918)
					(mid 75.245214 -430.889918)
					(end 76.054966 -430.889918)
				)
			)
		)
	)
	(zone
		(layers "B.Cu" "In13.Cu" "In15.Cu")
		(hatch none 0.5)
		(connect_pads
			(clearance 0)
		)
		(min_thickness 0.25)
		(keepout
			(tracks not_allowed)
			(vias allowed)
			(pads allowed)
			(copperpour not_allowed)
			(footprints allowed)
		)
		(placement
			(enabled no)
			(sheetname "")
		)
		(fill yes
			(thermal_gap 0.5)
			(thermal_bridge_width 0.5)
			(island_removal_mode 0)
		)
		(polygon
			(pts
				(arc
					(start 365.545624 -221.133924)
					(mid 364.892844 -221.133924)
					(end 365.545624 -221.133924)
				)
			)
		)
	)
	(zone
		(layers "B.Cu" "In13.Cu" "In15.Cu")
		(hatch none 0.5)
		(connect_pads
			(clearance 0)
		)
		(min_thickness 0.25)
		(keepout
			(tracks not_allowed)
			(vias allowed)
			(pads allowed)
			(copperpour not_allowed)
			(footprints allowed)
		)
		(placement
			(enabled no)
			(sheetname "")
		)
		(fill yes
			(thermal_gap 0.5)
			(thermal_bridge_width 0.5)
			(island_removal_mode 0)
		)
		(polygon
			(pts
				(arc
					(start 319.054988 -429.689768)
					(mid 318.245236 -429.689768)
					(end 319.054988 -429.689768)
				)
			)
		)
	)
	(zone
		(layers "B.Cu" "In13.Cu" "In15.Cu")
		(hatch none 0.5)
		(connect_pads
			(clearance 0)
		)
		(min_thickness 0.25)
		(keepout
			(tracks not_allowed)
			(vias allowed)
			(pads allowed)
			(copperpour not_allowed)
			(footprints allowed)
		)
		(placement
			(enabled no)
			(sheetname "")
		)
		(fill yes
			(thermal_gap 0.5)
			(thermal_bridge_width 0.5)
			(island_removal_mode 0)
		)
		(polygon
			(pts
				(arc
					(start 372.124224 -229.272846)
					(mid 371.471444 -229.272846)
					(end 372.124224 -229.272846)
				)
			)
		)
	)
	(zone
		(layers "B.Cu" "In13.Cu" "In15.Cu")
		(hatch none 0.5)
		(connect_pads
			(clearance 0)
		)
		(min_thickness 0.25)
		(keepout
			(tracks not_allowed)
			(vias allowed)
			(pads allowed)
			(copperpour not_allowed)
			(footprints allowed)
		)
		(placement
			(enabled no)
			(sheetname "")
		)
		(fill yes
			(thermal_gap 0.5)
			(thermal_bridge_width 0.5)
			(island_removal_mode 0)
		)
		(polygon
			(pts
				(arc
					(start 384.89128 -403.883876)
					(mid 384.1877 -403.883876)
					(end 384.89128 -403.883876)
				)
			)
		)
	)
	(zone
		(layers "B.Cu" "In13.Cu" "In15.Cu")
		(hatch none 0.5)
		(connect_pads
			(clearance 0)
		)
		(min_thickness 0.25)
		(keepout
			(tracks not_allowed)
			(vias allowed)
			(pads allowed)
			(copperpour not_allowed)
			(footprints allowed)
		)
		(placement
			(enabled no)
			(sheetname "")
		)
		(fill yes
			(thermal_gap 0.5)
			(thermal_bridge_width 0.5)
			(island_removal_mode 0)
		)
		(polygon
			(pts
				(arc
					(start 371.764052 -256.361438)
					(mid 371.111272 -256.361438)
					(end 371.764052 -256.361438)
				)
			)
		)
	)
	(zone
		(layers "B.Cu" "In13.Cu" "In15.Cu")
		(hatch none 0.5)
		(connect_pads
			(clearance 0)
		)
		(min_thickness 0.25)
		(keepout
			(tracks not_allowed)
			(vias allowed)
			(pads allowed)
			(copperpour not_allowed)
			(footprints allowed)
		)
		(placement
			(enabled no)
			(sheetname "")
		)
		(fill yes
			(thermal_gap 0.5)
			(thermal_bridge_width 0.5)
			(island_removal_mode 0)
		)
		(polygon
			(pts
				(arc
					(start 98.339402 -249.620024)
					(mid 97.686622 -249.620024)
					(end 98.339402 -249.620024)
				)
			)
		)
	)
	(zone
		(layers "B.Cu" "In13.Cu" "In15.Cu")
		(hatch none 0.5)
		(connect_pads
			(clearance 0)
		)
		(min_thickness 0.25)
		(keepout
			(tracks not_allowed)
			(vias allowed)
			(pads allowed)
			(copperpour not_allowed)
			(footprints allowed)
		)
		(placement
			(enabled no)
			(sheetname "")
		)
		(fill yes
			(thermal_gap 0.5)
			(thermal_bridge_width 0.5)
			(island_removal_mode 0)
		)
		(polygon
			(pts
				(arc
					(start 203.297536 -305.266598)
					(mid 202.644756 -305.266598)
					(end 203.297536 -305.266598)
				)
			)
		)
	)
	(zone
		(layers "B.Cu" "In13.Cu" "In15.Cu")
		(hatch none 0.5)
		(connect_pads
			(clearance 0)
		)
		(min_thickness 0.25)
		(keepout
			(tracks not_allowed)
			(vias allowed)
			(pads allowed)
			(copperpour not_allowed)
			(footprints allowed)
		)
		(placement
			(enabled no)
			(sheetname "")
		)
		(fill yes
			(thermal_gap 0.5)
			(thermal_bridge_width 0.5)
			(island_removal_mode 0)
		)
		(polygon
			(pts
				(arc
					(start 353.328224 -221.133924)
					(mid 352.675444 -221.133924)
					(end 353.328224 -221.133924)
				)
			)
		)
	)
	(zone
		(layers "B.Cu" "In13.Cu" "In15.Cu")
		(hatch none 0.5)
		(connect_pads
			(clearance 0)
		)
		(min_thickness 0.25)
		(keepout
			(tracks not_allowed)
			(vias allowed)
			(pads allowed)
			(copperpour not_allowed)
			(footprints allowed)
		)
		(placement
			(enabled no)
			(sheetname "")
		)
		(fill yes
			(thermal_gap 0.5)
			(thermal_bridge_width 0.5)
			(island_removal_mode 0)
		)
		(polygon
			(pts
				(arc
					(start 394.081 -403.883876)
					(mid 393.37742 -403.883876)
					(end 394.081 -403.883876)
				)
			)
		)
	)
	(zone
		(layers "B.Cu" "In13.Cu" "In15.Cu")
		(hatch none 0.5)
		(connect_pads
			(clearance 0)
		)
		(min_thickness 0.25)
		(keepout
			(tracks not_allowed)
			(vias allowed)
			(pads allowed)
			(copperpour not_allowed)
			(footprints allowed)
		)
		(placement
			(enabled no)
			(sheetname "")
		)
		(fill yes
			(thermal_gap 0.5)
			(thermal_bridge_width 0.5)
			(island_removal_mode 0)
		)
		(polygon
			(pts
				(arc
					(start 98.809556 -245.55069)
					(mid 98.156776 -245.55069)
					(end 98.809556 -245.55069)
				)
			)
		)
	)
	(zone
		(layers "B.Cu" "In13.Cu" "In15.Cu")
		(hatch none 0.5)
		(connect_pads
			(clearance 0)
		)
		(min_thickness 0.25)
		(keepout
			(tracks not_allowed)
			(vias allowed)
			(pads allowed)
			(copperpour not_allowed)
			(footprints allowed)
		)
		(placement
			(enabled no)
			(sheetname "")
		)
		(fill yes
			(thermal_gap 0.5)
			(thermal_bridge_width 0.5)
			(island_removal_mode 0)
		)
		(polygon
			(pts
				(arc
					(start 348.15907 -247.992138)
					(mid 347.50629 -247.992138)
					(end 348.15907 -247.992138)
				)
			)
		)
	)
	(zone
		(layers "B.Cu" "In13.Cu" "In15.Cu")
		(hatch none 0.5)
		(connect_pads
			(clearance 0)
		)
		(min_thickness 0.25)
		(keepout
			(tracks not_allowed)
			(vias allowed)
			(pads allowed)
			(copperpour not_allowed)
			(footprints allowed)
		)
		(placement
			(enabled no)
			(sheetname "")
		)
		(fill yes
			(thermal_gap 0.5)
			(thermal_bridge_width 0.5)
			(island_removal_mode 0)
		)
		(polygon
			(pts
				(arc
					(start 203.297536 -297.616626)
					(mid 202.644756 -297.616626)
					(end 203.297536 -297.616626)
				)
			)
		)
	)
	(zone
		(layers "B.Cu" "In13.Cu" "In15.Cu")
		(hatch none 0.5)
		(connect_pads
			(clearance 0)
		)
		(min_thickness 0.25)
		(keepout
			(tracks not_allowed)
			(vias allowed)
			(pads allowed)
			(copperpour not_allowed)
			(footprints allowed)
		)
		(placement
			(enabled no)
			(sheetname "")
		)
		(fill yes
			(thermal_gap 0.5)
			(thermal_bridge_width 0.5)
			(island_removal_mode 0)
		)
		(polygon
			(pts
				(arc
					(start 21.215604 -199.01662)
					(mid 20.562824 -199.01662)
					(end 21.215604 -199.01662)
				)
			)
		)
	)
	(zone
		(layers "B.Cu" "In13.Cu" "In15.Cu")
		(hatch none 0.5)
		(connect_pads
			(clearance 0)
		)
		(min_thickness 0.25)
		(keepout
			(tracks not_allowed)
			(vias allowed)
			(pads allowed)
			(copperpour not_allowed)
			(footprints allowed)
		)
		(placement
			(enabled no)
			(sheetname "")
		)
		(fill yes
			(thermal_gap 0.5)
			(thermal_bridge_width 0.5)
			(island_removal_mode 0)
		)
		(polygon
			(pts
				(arc
					(start 373.064024 -247.178322)
					(mid 372.411244 -247.178322)
					(end 373.064024 -247.178322)
				)
			)
		)
	)
	(zone
		(layers "B.Cu" "In13.Cu" "In15.Cu")
		(hatch none 0.5)
		(connect_pads
			(clearance 0)
		)
		(min_thickness 0.25)
		(keepout
			(tracks not_allowed)
			(vias allowed)
			(pads allowed)
			(copperpour not_allowed)
			(footprints allowed)
		)
		(placement
			(enabled no)
			(sheetname "")
		)
		(fill yes
			(thermal_gap 0.5)
			(thermal_bridge_width 0.5)
			(island_removal_mode 0)
		)
		(polygon
			(pts
				(arc
					(start 455.337672 -216.016586)
					(mid 454.684892 -216.016586)
					(end 455.337672 -216.016586)
				)
			)
		)
	)
	(zone
		(layers "B.Cu" "In13.Cu" "In15.Cu")
		(hatch none 0.5)
		(connect_pads
			(clearance 0)
		)
		(min_thickness 0.25)
		(keepout
			(tracks not_allowed)
			(vias allowed)
			(pads allowed)
			(copperpour not_allowed)
			(footprints allowed)
		)
		(placement
			(enabled no)
			(sheetname "")
		)
		(fill yes
			(thermal_gap 0.5)
			(thermal_bridge_width 0.5)
			(island_removal_mode 0)
		)
		(polygon
			(pts
				(arc
					(start 207.397604 -233.016806)
					(mid 206.744824 -233.016806)
					(end 207.397604 -233.016806)
				)
			)
		)
	)
	(zone
		(layers "B.Cu" "In13.Cu" "In15.Cu")
		(hatch none 0.5)
		(connect_pads
			(clearance 0)
		)
		(min_thickness 0.25)
		(keepout
			(tracks not_allowed)
			(vias allowed)
			(pads allowed)
			(copperpour not_allowed)
			(footprints allowed)
		)
		(placement
			(enabled no)
			(sheetname "")
		)
		(fill yes
			(thermal_gap 0.5)
			(thermal_bridge_width 0.5)
			(island_removal_mode 0)
		)
		(polygon
			(pts
				(arc
					(start 265.055604 -302.716692)
					(mid 264.402824 -302.716692)
					(end 265.055604 -302.716692)
				)
			)
		)
	)
	(zone
		(layers "B.Cu" "In13.Cu" "In15.Cu")
		(hatch none 0.5)
		(connect_pads
			(clearance 0)
		)
		(min_thickness 0.25)
		(keepout
			(tracks not_allowed)
			(vias allowed)
			(pads allowed)
			(copperpour not_allowed)
			(footprints allowed)
		)
		(placement
			(enabled no)
			(sheetname "")
		)
		(fill yes
			(thermal_gap 0.5)
			(thermal_bridge_width 0.5)
			(island_removal_mode 0)
		)
		(polygon
			(pts
				(arc
					(start 125.233938 -271.825212)
					(mid 124.581158 -271.825212)
					(end 125.233938 -271.825212)
				)
			)
		)
	)
	(zone
		(layers "B.Cu" "In13.Cu" "In15.Cu")
		(hatch none 0.5)
		(connect_pads
			(clearance 0)
		)
		(min_thickness 0.25)
		(keepout
			(tracks not_allowed)
			(vias allowed)
			(pads allowed)
			(copperpour not_allowed)
			(footprints allowed)
		)
		(placement
			(enabled no)
			(sheetname "")
		)
		(fill yes
			(thermal_gap 0.5)
			(thermal_bridge_width 0.5)
			(island_removal_mode 0)
		)
		(polygon
			(pts
				(arc
					(start 347.21927 -238.225584)
					(mid 346.56649 -238.225584)
					(end 347.21927 -238.225584)
				)
			)
		)
	)
	(zone
		(layers "B.Cu" "In13.Cu" "In15.Cu")
		(hatch none 0.5)
		(connect_pads
			(clearance 0)
		)
		(min_thickness 0.25)
		(keepout
			(tracks not_allowed)
			(vias allowed)
			(pads allowed)
			(copperpour not_allowed)
			(footprints allowed)
		)
		(placement
			(enabled no)
			(sheetname "")
		)
		(fill yes
			(thermal_gap 0.5)
			(thermal_bridge_width 0.5)
			(island_removal_mode 0)
		)
		(polygon
			(pts
				(arc
					(start 354.847652 -277.522432)
					(mid 354.194872 -277.522432)
					(end 354.847652 -277.522432)
				)
			)
		)
	)
	(zone
		(layers "B.Cu" "In13.Cu" "In15.Cu")
		(hatch none 0.5)
		(connect_pads
			(clearance 0)
		)
		(min_thickness 0.25)
		(keepout
			(tracks not_allowed)
			(vias allowed)
			(pads allowed)
			(copperpour not_allowed)
			(footprints allowed)
		)
		(placement
			(enabled no)
			(sheetname "")
		)
		(fill yes
			(thermal_gap 0.5)
			(thermal_bridge_width 0.5)
			(island_removal_mode 0)
		)
		(polygon
			(pts
				(arc
					(start 115.725956 -221.133924)
					(mid 115.073176 -221.133924)
					(end 115.725956 -221.133924)
				)
			)
		)
	)
	(zone
		(layers "B.Cu" "In13.Cu" "In15.Cu")
		(hatch none 0.5)
		(connect_pads
			(clearance 0)
		)
		(min_thickness 0.25)
		(keepout
			(tracks not_allowed)
			(vias allowed)
			(pads allowed)
			(copperpour not_allowed)
			(footprints allowed)
		)
		(placement
			(enabled no)
			(sheetname "")
		)
		(fill yes
			(thermal_gap 0.5)
			(thermal_bridge_width 0.5)
			(island_removal_mode 0)
		)
		(polygon
			(pts
				(arc
					(start 100.689156 -243.922804)
					(mid 100.036376 -243.922804)
					(end 100.689156 -243.922804)
				)
			)
		)
	)
	(zone
		(layers "B.Cu" "In13.Cu" "In15.Cu")
		(hatch none 0.5)
		(connect_pads
			(clearance 0)
		)
		(min_thickness 0.25)
		(keepout
			(tracks not_allowed)
			(vias allowed)
			(pads allowed)
			(copperpour not_allowed)
			(footprints allowed)
		)
		(placement
			(enabled no)
			(sheetname "")
		)
		(fill yes
			(thermal_gap 0.5)
			(thermal_bridge_width 0.5)
			(island_removal_mode 0)
		)
		(polygon
			(pts
				(arc
					(start 455.337672 -273.816572)
					(mid 454.684892 -273.816572)
					(end 455.337672 -273.816572)
				)
			)
		)
	)
	(zone
		(layers "B.Cu" "In13.Cu" "In15.Cu")
		(hatch none 0.5)
		(connect_pads
			(clearance 0)
		)
		(min_thickness 0.25)
		(keepout
			(tracks not_allowed)
			(vias allowed)
			(pads allowed)
			(copperpour not_allowed)
			(footprints allowed)
		)
		(placement
			(enabled no)
			(sheetname "")
		)
		(fill yes
			(thermal_gap 0.5)
			(thermal_bridge_width 0.5)
			(island_removal_mode 0)
		)
		(polygon
			(pts
				(arc
					(start 346.27947 -249.620024)
					(mid 345.62669 -249.620024)
					(end 346.27947 -249.620024)
				)
			)
		)
	)
	(zone
		(layers "B.Cu" "In13.Cu" "In15.Cu")
		(hatch none 0.5)
		(connect_pads
			(clearance 0)
		)
		(min_thickness 0.25)
		(keepout
			(tracks not_allowed)
			(vias allowed)
			(pads allowed)
			(copperpour not_allowed)
			(footprints allowed)
		)
		(placement
			(enabled no)
			(sheetname "")
		)
		(fill yes
			(thermal_gap 0.5)
			(thermal_bridge_width 0.5)
			(island_removal_mode 0)
		)
		(polygon
			(pts
				(arc
					(start 346.389452 -282.405836)
					(mid 345.736672 -282.405836)
					(end 346.389452 -282.405836)
				)
			)
		)
	)
	(zone
		(layers "B.Cu" "In13.Cu" "In15.Cu")
		(hatch none 0.5)
		(connect_pads
			(clearance 0)
		)
		(min_thickness 0.25)
		(keepout
			(tracks not_allowed)
			(vias allowed)
			(pads allowed)
			(copperpour not_allowed)
			(footprints allowed)
		)
		(placement
			(enabled no)
			(sheetname "")
		)
		(fill yes
			(thermal_gap 0.5)
			(thermal_bridge_width 0.5)
			(island_removal_mode 0)
		)
		(polygon
			(pts
				(arc
					(start 151.139144 -403.883876)
					(mid 150.435564 -403.883876)
					(end 151.139144 -403.883876)
				)
			)
		)
	)
	(zone
		(layers "B.Cu" "In13.Cu" "In15.Cu")
		(hatch none 0.5)
		(connect_pads
			(clearance 0)
		)
		(min_thickness 0.25)
		(keepout
			(tracks not_allowed)
			(vias allowed)
			(pads allowed)
			(copperpour not_allowed)
			(footprints allowed)
		)
		(placement
			(enabled no)
			(sheetname "")
		)
		(fill yes
			(thermal_gap 0.5)
			(thermal_bridge_width 0.5)
			(island_removal_mode 0)
		)
		(polygon
			(pts
				(arc
					(start 125.703584 -274.266914)
					(mid 125.050804 -274.266914)
					(end 125.703584 -274.266914)
				)
			)
		)
	)
	(zone
		(layers "B.Cu" "In13.Cu" "In15.Cu")
		(hatch none 0.5)
		(connect_pads
			(clearance 0)
		)
		(min_thickness 0.25)
		(keepout
			(tracks not_allowed)
			(vias allowed)
			(pads allowed)
			(copperpour not_allowed)
			(footprints allowed)
		)
		(placement
			(enabled no)
			(sheetname "")
		)
		(fill yes
			(thermal_gap 0.5)
			(thermal_bridge_width 0.5)
			(island_removal_mode 0)
		)
		(polygon
			(pts
				(arc
					(start 148.939504 -403.883876)
					(mid 148.235924 -403.883876)
					(end 148.939504 -403.883876)
				)
			)
		)
	)
	(zone
		(layers "B.Cu" "In13.Cu" "In15.Cu")
		(hatch none 0.5)
		(connect_pads
			(clearance 0)
		)
		(min_thickness 0.25)
		(keepout
			(tracks not_allowed)
			(vias allowed)
			(pads allowed)
			(copperpour not_allowed)
			(footprints allowed)
		)
		(placement
			(enabled no)
			(sheetname "")
		)
		(fill yes
			(thermal_gap 0.5)
			(thermal_bridge_width 0.5)
			(island_removal_mode 0)
		)
		(polygon
			(pts
				(arc
					(start 63.647828 -403.883876)
					(mid 62.944248 -403.883876)
					(end 63.647828 -403.883876)
				)
			)
		)
	)
	(zone
		(layers "B.Cu" "In13.Cu" "In15.Cu")
		(hatch none 0.5)
		(connect_pads
			(clearance 0)
		)
		(min_thickness 0.25)
		(keepout
			(tracks not_allowed)
			(vias allowed)
			(pads allowed)
			(copperpour not_allowed)
			(footprints allowed)
		)
		(placement
			(enabled no)
			(sheetname "")
		)
		(fill yes
			(thermal_gap 0.5)
			(thermal_bridge_width 0.5)
			(island_removal_mode 0)
		)
		(polygon
			(pts
				(arc
					(start 345.449652 -282.405836)
					(mid 344.796872 -282.405836)
					(end 345.449652 -282.405836)
				)
			)
		)
	)
	(zone
		(layers "B.Cu" "In13.Cu" "In15.Cu")
		(hatch none 0.5)
		(connect_pads
			(clearance 0)
		)
		(min_thickness 0.25)
		(keepout
			(tracks not_allowed)
			(vias allowed)
			(pads allowed)
			(copperpour not_allowed)
			(footprints allowed)
		)
		(placement
			(enabled no)
			(sheetname "")
		)
		(fill yes
			(thermal_gap 0.5)
			(thermal_bridge_width 0.5)
			(island_removal_mode 0)
		)
		(polygon
			(pts
				(arc
					(start 153.154888 -428.28972)
					(mid 152.345136 -428.28972)
					(end 153.154888 -428.28972)
				)
			)
		)
	)
	(zone
		(layers "B.Cu" "In13.Cu" "In15.Cu")
		(hatch none 0.5)
		(connect_pads
			(clearance 0)
		)
		(min_thickness 0.25)
		(keepout
			(tracks not_allowed)
			(vias allowed)
			(pads allowed)
			(copperpour not_allowed)
			(footprints allowed)
		)
		(placement
			(enabled no)
			(sheetname "")
		)
		(fill yes
			(thermal_gap 0.5)
			(thermal_bridge_width 0.5)
			(island_removal_mode 0)
		)
		(polygon
			(pts
				(arc
					(start 117.605556 -221.133924)
					(mid 116.952776 -221.133924)
					(end 117.605556 -221.133924)
				)
			)
		)
	)
	(zone
		(layers "B.Cu" "In13.Cu" "In15.Cu")
		(hatch none 0.5)
		(connect_pads
			(clearance 0)
		)
		(min_thickness 0.25)
		(keepout
			(tracks not_allowed)
			(vias allowed)
			(pads allowed)
			(copperpour not_allowed)
			(footprints allowed)
		)
		(placement
			(enabled no)
			(sheetname "")
		)
		(fill yes
			(thermal_gap 0.5)
			(thermal_bridge_width 0.5)
			(island_removal_mode 0)
		)
		(polygon
			(pts
				(arc
					(start 203.297536 -250.866656)
					(mid 202.644756 -250.866656)
					(end 203.297536 -250.866656)
				)
			)
		)
	)
	(zone
		(layers "B.Cu" "In13.Cu" "In15.Cu")
		(hatch none 0.5)
		(connect_pads
			(clearance 0)
		)
		(min_thickness 0.25)
		(keepout
			(tracks not_allowed)
			(vias allowed)
			(pads allowed)
			(copperpour not_allowed)
			(footprints allowed)
		)
		(placement
			(enabled no)
			(sheetname "")
		)
		(fill yes
			(thermal_gap 0.5)
			(thermal_bridge_width 0.5)
			(island_removal_mode 0)
		)
		(polygon
			(pts
				(arc
					(start 13.671804 -267.016738)
					(mid 13.019024 -267.016738)
					(end 13.671804 -267.016738)
				)
			)
		)
	)
	(zone
		(layers "B.Cu" "In13.Cu" "In15.Cu")
		(hatch none 0.5)
		(connect_pads
			(clearance 0)
		)
		(min_thickness 0.25)
		(keepout
			(tracks not_allowed)
			(vias allowed)
			(pads allowed)
			(copperpour not_allowed)
			(footprints allowed)
		)
		(placement
			(enabled no)
			(sheetname "")
		)
		(fill yes
			(thermal_gap 0.5)
			(thermal_bridge_width 0.5)
			(island_removal_mode 0)
		)
		(polygon
			(pts
				(arc
					(start 100.799138 -281.59202)
					(mid 100.146358 -281.59202)
					(end 100.799138 -281.59202)
				)
			)
		)
	)
	(zone
		(layers "B.Cu" "In13.Cu" "In15.Cu")
		(hatch none 0.5)
		(connect_pads
			(clearance 0)
		)
		(min_thickness 0.25)
		(keepout
			(tracks not_allowed)
			(vias allowed)
			(pads allowed)
			(copperpour not_allowed)
			(footprints allowed)
		)
		(placement
			(enabled no)
			(sheetname "")
		)
		(fill yes
			(thermal_gap 0.5)
			(thermal_bridge_width 0.5)
			(island_removal_mode 0)
		)
		(polygon
			(pts
				(arc
					(start 203.297536 -302.716692)
					(mid 202.644756 -302.716692)
					(end 203.297536 -302.716692)
				)
			)
		)
	)
	(zone
		(layers "B.Cu" "In13.Cu" "In15.Cu")
		(hatch none 0.5)
		(connect_pads
			(clearance 0)
		)
		(min_thickness 0.25)
		(keepout
			(tracks not_allowed)
			(vias allowed)
			(pads allowed)
			(copperpour not_allowed)
			(footprints allowed)
		)
		(placement
			(enabled no)
			(sheetname "")
		)
		(fill yes
			(thermal_gap 0.5)
			(thermal_bridge_width 0.5)
			(island_removal_mode 0)
		)
		(polygon
			(pts
				(arc
					(start 21.215604 -259.366766)
					(mid 20.562824 -259.366766)
					(end 21.215604 -259.366766)
				)
			)
		)
	)
	(zone
		(layers "B.Cu" "In13.Cu" "In15.Cu")
		(hatch none 0.5)
		(connect_pads
			(clearance 0)
		)
		(min_thickness 0.25)
		(keepout
			(tracks not_allowed)
			(vias allowed)
			(pads allowed)
			(copperpour not_allowed)
			(footprints allowed)
		)
		(placement
			(enabled no)
			(sheetname "")
		)
		(fill yes
			(thermal_gap 0.5)
			(thermal_bridge_width 0.5)
			(island_removal_mode 0)
		)
		(polygon
			(pts
				(arc
					(start 100.328984 -274.266914)
					(mid 99.676204 -274.266914)
					(end 100.328984 -274.266914)
				)
			)
		)
	)
	(zone
		(layers "B.Cu" "In13.Cu" "In15.Cu")
		(hatch none 0.5)
		(connect_pads
			(clearance 0)
		)
		(min_thickness 0.25)
		(keepout
			(tracks not_allowed)
			(vias allowed)
			(pads allowed)
			(copperpour not_allowed)
			(footprints allowed)
		)
		(placement
			(enabled no)
			(sheetname "")
		)
		(fill yes
			(thermal_gap 0.5)
			(thermal_bridge_width 0.5)
			(island_removal_mode 0)
		)
		(polygon
			(pts
				(arc
					(start 21.215604 -281.466798)
					(mid 20.562824 -281.466798)
					(end 21.215604 -281.466798)
				)
			)
		)
	)
	(zone
		(layers "B.Cu" "In13.Cu" "In15.Cu")
		(hatch none 0.5)
		(connect_pads
			(clearance 0)
		)
		(min_thickness 0.25)
		(keepout
			(tracks not_allowed)
			(vias allowed)
			(pads allowed)
			(copperpour not_allowed)
			(footprints allowed)
		)
		(placement
			(enabled no)
			(sheetname "")
		)
		(fill yes
			(thermal_gap 0.5)
			(thermal_bridge_width 0.5)
			(island_removal_mode 0)
		)
		(polygon
			(pts
				(arc
					(start 90.054938 -431.889916)
					(mid 89.245186 -431.889916)
					(end 90.054938 -431.889916)
				)
			)
		)
	)
	(zone
		(layers "B.Cu" "In13.Cu" "In15.Cu")
		(hatch none 0.5)
		(connect_pads
			(clearance 0)
		)
		(min_thickness 0.25)
		(keepout
			(tracks not_allowed)
			(vias allowed)
			(pads allowed)
			(copperpour not_allowed)
			(footprints allowed)
		)
		(placement
			(enabled no)
			(sheetname "")
		)
		(fill yes
			(thermal_gap 0.5)
			(thermal_bridge_width 0.5)
			(island_removal_mode 0)
		)
		(polygon
			(pts
				(arc
					(start 346.363798 -410.030168)
					(mid 345.660218 -410.030168)
					(end 346.363798 -410.030168)
				)
			)
		)
	)
	(zone
		(layers "B.Cu" "In13.Cu" "In15.Cu")
		(hatch none 0.5)
		(connect_pads
			(clearance 0)
		)
		(min_thickness 0.25)
		(keepout
			(tracks not_allowed)
			(vias allowed)
			(pads allowed)
			(copperpour not_allowed)
			(footprints allowed)
		)
		(placement
			(enabled no)
			(sheetname "")
		)
		(fill yes
			(thermal_gap 0.5)
			(thermal_bridge_width 0.5)
			(island_removal_mode 0)
		)
		(polygon
			(pts
				(arc
					(start 372.234206 -260.430772)
					(mid 371.581426 -260.430772)
					(end 372.234206 -260.430772)
				)
			)
		)
	)
	(zone
		(layers "B.Cu" "In13.Cu" "In15.Cu")
		(hatch none 0.5)
		(connect_pads
			(clearance 0)
		)
		(min_thickness 0.25)
		(keepout
			(tracks not_allowed)
			(vias allowed)
			(pads allowed)
			(copperpour not_allowed)
			(footprints allowed)
		)
		(placement
			(enabled no)
			(sheetname "")
		)
		(fill yes
			(thermal_gap 0.5)
			(thermal_bridge_width 0.5)
			(island_removal_mode 0)
		)
		(polygon
			(pts
				(arc
					(start 396.544292 -4.95173)
					(mid 395.840712 -4.95173)
					(end 396.544292 -4.95173)
				)
			)
		)
	)
	(zone
		(layers "B.Cu" "In13.Cu" "In15.Cu")
		(hatch none 0.5)
		(connect_pads
			(clearance 0)
		)
		(min_thickness 0.25)
		(keepout
			(tracks not_allowed)
			(vias allowed)
			(pads allowed)
			(copperpour not_allowed)
			(footprints allowed)
		)
		(placement
			(enabled no)
			(sheetname "")
		)
		(fill yes
			(thermal_gap 0.5)
			(thermal_bridge_width 0.5)
			(island_removal_mode 0)
		)
		(polygon
			(pts
				(arc
					(start 109.257084 -273.453098)
					(mid 108.604304 -273.453098)
					(end 109.257084 -273.453098)
				)
			)
		)
	)
	(zone
		(layers "B.Cu" "In13.Cu" "In15.Cu")
		(hatch none 0.5)
		(connect_pads
			(clearance 0)
		)
		(min_thickness 0.25)
		(keepout
			(tracks not_allowed)
			(vias allowed)
			(pads allowed)
			(copperpour not_allowed)
			(footprints allowed)
		)
		(placement
			(enabled no)
			(sheetname "")
		)
		(fill yes
			(thermal_gap 0.5)
			(thermal_bridge_width 0.5)
			(island_removal_mode 0)
		)
		(polygon
			(pts
				(arc
					(start 315.731398 -410.030168)
					(mid 315.027818 -410.030168)
					(end 315.731398 -410.030168)
				)
			)
		)
	)
	(zone
		(layers "B.Cu" "In13.Cu" "In15.Cu")
		(hatch none 0.5)
		(connect_pads
			(clearance 0)
		)
		(min_thickness 0.25)
		(keepout
			(tracks not_allowed)
			(vias allowed)
			(pads allowed)
			(copperpour not_allowed)
			(footprints allowed)
		)
		(placement
			(enabled no)
			(sheetname "")
		)
		(fill yes
			(thermal_gap 0.5)
			(thermal_bridge_width 0.5)
			(island_removal_mode 0)
		)
		(polygon
			(pts
				(arc
					(start 21.215604 -276.366732)
					(mid 20.562824 -276.366732)
					(end 21.215604 -276.366732)
				)
			)
		)
	)
	(zone
		(layers "B.Cu" "In13.Cu" "In15.Cu")
		(hatch none 0.5)
		(connect_pads
			(clearance 0)
		)
		(min_thickness 0.25)
		(keepout
			(tracks not_allowed)
			(vias allowed)
			(pads allowed)
			(copperpour not_allowed)
			(footprints allowed)
		)
		(placement
			(enabled no)
			(sheetname "")
		)
		(fill yes
			(thermal_gap 0.5)
			(thermal_bridge_width 0.5)
			(island_removal_mode 0)
		)
		(polygon
			(pts
				(arc
					(start 401.1549 -427.089824)
					(mid 400.345148 -427.089824)
					(end 401.1549 -427.089824)
				)
			)
		)
	)
	(zone
		(layers "B.Cu" "In13.Cu" "In15.Cu")
		(hatch none 0.5)
		(connect_pads
			(clearance 0)
		)
		(min_thickness 0.25)
		(keepout
			(tracks not_allowed)
			(vias allowed)
			(pads allowed)
			(copperpour not_allowed)
			(footprints allowed)
		)
		(placement
			(enabled no)
			(sheetname "")
		)
		(fill yes
			(thermal_gap 0.5)
			(thermal_bridge_width 0.5)
			(island_removal_mode 0)
		)
		(polygon
			(pts
				(arc
					(start 321.857878 -410.030168)
					(mid 321.154298 -410.030168)
					(end 321.857878 -410.030168)
				)
			)
		)
	)
	(zone
		(layers "B.Cu" "In13.Cu" "In15.Cu")
		(hatch none 0.5)
		(connect_pads
			(clearance 0)
		)
		(min_thickness 0.25)
		(keepout
			(tracks not_allowed)
			(vias allowed)
			(pads allowed)
			(copperpour not_allowed)
			(footprints allowed)
		)
		(placement
			(enabled no)
			(sheetname "")
		)
		(fill yes
			(thermal_gap 0.5)
			(thermal_bridge_width 0.5)
			(island_removal_mode 0)
		)
		(polygon
			(pts
				(arc
					(start 123.823984 -256.361438)
					(mid 123.171204 -256.361438)
					(end 123.823984 -256.361438)
				)
			)
		)
	)
	(zone
		(layers "B.Cu" "In13.Cu" "In15.Cu")
		(hatch none 0.5)
		(connect_pads
			(clearance 0)
		)
		(min_thickness 0.25)
		(keepout
			(tracks not_allowed)
			(vias allowed)
			(pads allowed)
			(copperpour not_allowed)
			(footprints allowed)
		)
		(placement
			(enabled no)
			(sheetname "")
		)
		(fill yes
			(thermal_gap 0.5)
			(thermal_bridge_width 0.5)
			(island_removal_mode 0)
		)
		(polygon
			(pts
				(arc
					(start 82.027268 -403.883876)
					(mid 81.323688 -403.883876)
					(end 82.027268 -403.883876)
				)
			)
		)
	)
	(zone
		(layers "B.Cu" "In13.Cu" "In15.Cu")
		(hatch none 0.5)
		(connect_pads
			(clearance 0)
		)
		(min_thickness 0.25)
		(keepout
			(tracks not_allowed)
			(vias allowed)
			(pads allowed)
			(copperpour not_allowed)
			(footprints allowed)
		)
		(placement
			(enabled no)
			(sheetname "")
		)
		(fill yes
			(thermal_gap 0.5)
			(thermal_bridge_width 0.5)
			(island_removal_mode 0)
		)
		(polygon
			(pts
				(arc
					(start 123.244356 -242.294918)
					(mid 122.591576 -242.294918)
					(end 123.244356 -242.294918)
				)
			)
		)
	)
	(zone
		(layers "B.Cu" "In13.Cu" "In15.Cu")
		(hatch none 0.5)
		(connect_pads
			(clearance 0)
		)
		(min_thickness 0.25)
		(keepout
			(tracks not_allowed)
			(vias allowed)
			(pads allowed)
			(copperpour not_allowed)
			(footprints allowed)
		)
		(placement
			(enabled no)
			(sheetname "")
		)
		(fill yes
			(thermal_gap 0.5)
			(thermal_bridge_width 0.5)
			(island_removal_mode 0)
		)
		(polygon
			(pts
				(arc
					(start 455.337672 -199.01662)
					(mid 454.684892 -199.01662)
					(end 455.337672 -199.01662)
				)
			)
		)
	)
	(zone
		(layers "B.Cu" "In13.Cu" "In15.Cu")
		(hatch none 0.5)
		(connect_pads
			(clearance 0)
		)
		(min_thickness 0.25)
		(keepout
			(tracks not_allowed)
			(vias allowed)
			(pads allowed)
			(copperpour not_allowed)
			(footprints allowed)
		)
		(placement
			(enabled no)
			(sheetname "")
		)
		(fill yes
			(thermal_gap 0.5)
			(thermal_bridge_width 0.5)
			(island_removal_mode 0)
		)
		(polygon
			(pts
				(arc
					(start 338.401152 -279.964134)
					(mid 337.748372 -279.964134)
					(end 338.401152 -279.964134)
				)
			)
		)
	)
	(zone
		(layers "B.Cu" "In13.Cu" "In15.Cu")
		(hatch none 0.5)
		(connect_pads
			(clearance 0)
		)
		(min_thickness 0.25)
		(keepout
			(tracks not_allowed)
			(vias allowed)
			(pads allowed)
			(copperpour not_allowed)
			(footprints allowed)
		)
		(placement
			(enabled no)
			(sheetname "")
		)
		(fill yes
			(thermal_gap 0.5)
			(thermal_bridge_width 0.5)
			(island_removal_mode 0)
		)
		(polygon
			(pts
				(arc
					(start 17.115536 -280.61666)
					(mid 16.462756 -280.61666)
					(end 17.115536 -280.61666)
				)
			)
		)
	)
	(zone
		(layers "B.Cu" "In13.Cu" "In15.Cu")
		(hatch none 0.5)
		(connect_pads
			(clearance 0)
		)
		(min_thickness 0.25)
		(keepout
			(tracks not_allowed)
			(vias allowed)
			(pads allowed)
			(copperpour not_allowed)
			(footprints allowed)
		)
		(placement
			(enabled no)
			(sheetname "")
		)
		(fill yes
			(thermal_gap 0.5)
			(thermal_bridge_width 0.5)
			(island_removal_mode 0)
		)
		(polygon
			(pts
				(arc
					(start 451.237604 -293.366698)
					(mid 450.584824 -293.366698)
					(end 451.237604 -293.366698)
				)
			)
		)
	)
	(zone
		(layers "B.Cu" "In13.Cu" "In15.Cu")
		(hatch none 0.5)
		(connect_pads
			(clearance 0)
		)
		(min_thickness 0.25)
		(keepout
			(tracks not_allowed)
			(vias allowed)
			(pads allowed)
			(copperpour not_allowed)
			(footprints allowed)
		)
		(placement
			(enabled no)
			(sheetname "")
		)
		(fill yes
			(thermal_gap 0.5)
			(thermal_bridge_width 0.5)
			(island_removal_mode 0)
		)
		(polygon
			(pts
				(arc
					(start 86.054946 -431.889916)
					(mid 85.245194 -431.889916)
					(end 86.054946 -431.889916)
				)
			)
		)
	)
	(zone
		(layers "B.Cu" "In13.Cu" "In15.Cu")
		(hatch none 0.5)
		(connect_pads
			(clearance 0)
		)
		(min_thickness 0.25)
		(keepout
			(tracks not_allowed)
			(vias allowed)
			(pads allowed)
			(copperpour not_allowed)
			(footprints allowed)
		)
		(placement
			(enabled no)
			(sheetname "")
		)
		(fill yes
			(thermal_gap 0.5)
			(thermal_bridge_width 0.5)
			(island_removal_mode 0)
		)
		(polygon
			(pts
				(arc
					(start 371.65407 -228.45903)
					(mid 371.00129 -228.45903)
					(end 371.65407 -228.45903)
				)
			)
		)
	)
	(zone
		(layers "B.Cu" "In13.Cu" "In15.Cu")
		(hatch none 0.5)
		(connect_pads
			(clearance 0)
		)
		(min_thickness 0.25)
		(keepout
			(tracks not_allowed)
			(vias allowed)
			(pads allowed)
			(copperpour not_allowed)
			(footprints allowed)
		)
		(placement
			(enabled no)
			(sheetname "")
		)
		(fill yes
			(thermal_gap 0.5)
			(thermal_bridge_width 0.5)
			(island_removal_mode 0)
		)
		(polygon
			(pts
				(arc
					(start 348.739206 -262.058658)
					(mid 348.086426 -262.058658)
					(end 348.739206 -262.058658)
				)
			)
		)
	)
	(zone
		(layers "B.Cu" "In13.Cu" "In15.Cu")
		(hatch none 0.5)
		(connect_pads
			(clearance 0)
		)
		(min_thickness 0.25)
		(keepout
			(tracks not_allowed)
			(vias allowed)
			(pads allowed)
			(copperpour not_allowed)
			(footprints allowed)
		)
		(placement
			(enabled no)
			(sheetname "")
		)
		(fill yes
			(thermal_gap 0.5)
			(thermal_bridge_width 0.5)
			(island_removal_mode 0)
		)
		(polygon
			(pts
				(arc
					(start 125.703584 -266.128246)
					(mid 125.050804 -266.128246)
					(end 125.703584 -266.128246)
				)
			)
		)
	)
	(zone
		(layers "B.Cu" "In13.Cu" "In15.Cu")
		(hatch none 0.5)
		(connect_pads
			(clearance 0)
		)
		(min_thickness 0.25)
		(keepout
			(tracks not_allowed)
			(vias allowed)
			(pads allowed)
			(copperpour not_allowed)
			(footprints allowed)
		)
		(placement
			(enabled no)
			(sheetname "")
		)
		(fill yes
			(thermal_gap 0.5)
			(thermal_bridge_width 0.5)
			(island_removal_mode 0)
		)
		(polygon
			(pts
				(arc
					(start 455.337672 -289.11677)
					(mid 454.684892 -289.11677)
					(end 455.337672 -289.11677)
				)
			)
		)
	)
	(zone
		(layers "B.Cu" "In13.Cu" "In15.Cu")
		(hatch none 0.5)
		(connect_pads
			(clearance 0)
		)
		(min_thickness 0.25)
		(keepout
			(tracks not_allowed)
			(vias allowed)
			(pads allowed)
			(copperpour not_allowed)
			(footprints allowed)
		)
		(placement
			(enabled no)
			(sheetname "")
		)
		(fill yes
			(thermal_gap 0.5)
			(thermal_bridge_width 0.5)
			(island_removal_mode 0)
		)
		(polygon
			(pts
				(arc
					(start 451.237604 -238.116618)
					(mid 450.584824 -238.116618)
					(end 451.237604 -238.116618)
				)
			)
		)
	)
	(zone
		(layers "B.Cu" "In13.Cu" "In15.Cu")
		(hatch none 0.5)
		(connect_pads
			(clearance 0)
		)
		(min_thickness 0.25)
		(keepout
			(tracks not_allowed)
			(vias allowed)
			(pads allowed)
			(copperpour not_allowed)
			(footprints allowed)
		)
		(placement
			(enabled no)
			(sheetname "")
		)
		(fill yes
			(thermal_gap 0.5)
			(thermal_bridge_width 0.5)
			(island_removal_mode 0)
		)
		(polygon
			(pts
				(arc
					(start 455.337672 -250.016772)
					(mid 454.684892 -250.016772)
					(end 455.337672 -250.016772)
				)
			)
		)
	)
	(zone
		(layers "B.Cu" "In13.Cu" "In15.Cu")
		(hatch none 0.5)
		(connect_pads
			(clearance 0)
		)
		(min_thickness 0.25)
		(keepout
			(tracks not_allowed)
			(vias allowed)
			(pads allowed)
			(copperpour not_allowed)
			(footprints allowed)
		)
		(placement
			(enabled no)
			(sheetname "")
		)
		(fill yes
			(thermal_gap 0.5)
			(thermal_bridge_width 0.5)
			(island_removal_mode 0)
		)
		(polygon
			(pts
				(arc
					(start 352.498406 -276.708616)
					(mid 351.845626 -276.708616)
					(end 352.498406 -276.708616)
				)
			)
		)
	)
	(zone
		(layers "B.Cu" "In13.Cu" "In15.Cu")
		(hatch none 0.5)
		(connect_pads
			(clearance 0)
		)
		(min_thickness 0.25)
		(keepout
			(tracks not_allowed)
			(vias allowed)
			(pads allowed)
			(copperpour not_allowed)
			(footprints allowed)
		)
		(placement
			(enabled no)
			(sheetname "")
		)
		(fill yes
			(thermal_gap 0.5)
			(thermal_bridge_width 0.5)
			(island_removal_mode 0)
		)
		(polygon
			(pts
				(arc
					(start 111.026956 -221.133924)
					(mid 110.374176 -221.133924)
					(end 111.026956 -221.133924)
				)
			)
		)
	)
	(zone
		(layers "B.Cu" "In13.Cu" "In15.Cu")
		(hatch none 0.5)
		(connect_pads
			(clearance 0)
		)
		(min_thickness 0.25)
		(keepout
			(tracks not_allowed)
			(vias allowed)
			(pads allowed)
			(copperpour not_allowed)
			(footprints allowed)
		)
		(placement
			(enabled no)
			(sheetname "")
		)
		(fill yes
			(thermal_gap 0.5)
			(thermal_bridge_width 0.5)
			(island_removal_mode 0)
		)
		(polygon
			(pts
				(arc
					(start 138.154918 -427.289976)
					(mid 137.345166 -427.289976)
					(end 138.154918 -427.289976)
				)
			)
		)
	)
	(zone
		(layers "B.Cu" "In13.Cu" "In15.Cu")
		(hatch none 0.5)
		(connect_pads
			(clearance 0)
		)
		(min_thickness 0.25)
		(keepout
			(tracks not_allowed)
			(vias allowed)
			(pads allowed)
			(copperpour not_allowed)
			(footprints allowed)
		)
		(placement
			(enabled no)
			(sheetname "")
		)
		(fill yes
			(thermal_gap 0.5)
			(thermal_bridge_width 0.5)
			(island_removal_mode 0)
		)
		(polygon
			(pts
				(arc
					(start 371.184424 -247.178322)
					(mid 370.531644 -247.178322)
					(end 371.184424 -247.178322)
				)
			)
		)
	)
	(zone
		(layers "B.Cu" "In13.Cu" "In15.Cu")
		(hatch none 0.5)
		(connect_pads
			(clearance 0)
		)
		(min_thickness 0.25)
		(keepout
			(tracks not_allowed)
			(vias allowed)
			(pads allowed)
			(copperpour not_allowed)
			(footprints allowed)
		)
		(placement
			(enabled no)
			(sheetname "")
		)
		(fill yes
			(thermal_gap 0.5)
			(thermal_bridge_width 0.5)
			(island_removal_mode 0)
		)
		(polygon
			(pts
				(arc
					(start 265.055604 -196.466714)
					(mid 264.402824 -196.466714)
					(end 265.055604 -196.466714)
				)
			)
		)
	)
	(zone
		(layers "B.Cu" "In13.Cu" "In15.Cu")
		(hatch none 0.5)
		(connect_pads
			(clearance 0)
		)
		(min_thickness 0.25)
		(keepout
			(tracks not_allowed)
			(vias allowed)
			(pads allowed)
			(copperpour not_allowed)
			(footprints allowed)
		)
		(placement
			(enabled no)
			(sheetname "")
		)
		(fill yes
			(thermal_gap 0.5)
			(thermal_bridge_width 0.5)
			(island_removal_mode 0)
		)
		(polygon
			(pts
				(arc
					(start 207.397604 -263.616694)
					(mid 206.744824 -263.616694)
					(end 207.397604 -263.616694)
				)
			)
		)
	)
	(zone
		(layers "B.Cu" "In13.Cu" "In15.Cu")
		(hatch none 0.5)
		(connect_pads
			(clearance 0)
		)
		(min_thickness 0.25)
		(keepout
			(tracks not_allowed)
			(vias allowed)
			(pads allowed)
			(copperpour not_allowed)
			(footprints allowed)
		)
		(placement
			(enabled no)
			(sheetname "")
		)
		(fill yes
			(thermal_gap 0.5)
			(thermal_bridge_width 0.5)
			(island_removal_mode 0)
		)
		(polygon
			(pts
				(arc
					(start 149.154896 -427.089824)
					(mid 148.345144 -427.089824)
					(end 149.154896 -427.089824)
				)
			)
		)
	)
	(zone
		(layers "B.Cu" "In13.Cu" "In15.Cu")
		(hatch none 0.5)
		(connect_pads
			(clearance 0)
		)
		(min_thickness 0.25)
		(keepout
			(tracks not_allowed)
			(vias allowed)
			(pads allowed)
			(copperpour not_allowed)
			(footprints allowed)
		)
		(placement
			(enabled no)
			(sheetname "")
		)
		(fill yes
			(thermal_gap 0.5)
			(thermal_bridge_width 0.5)
			(island_removal_mode 0)
		)
		(polygon
			(pts
				(arc
					(start 124.294138 -268.569694)
					(mid 123.641358 -268.569694)
					(end 124.294138 -268.569694)
				)
			)
		)
	)
	(zone
		(layers "B.Cu" "In13.Cu" "In15.Cu")
		(hatch none 0.5)
		(connect_pads
			(clearance 0)
		)
		(min_thickness 0.25)
		(keepout
			(tracks not_allowed)
			(vias allowed)
			(pads allowed)
			(copperpour not_allowed)
			(footprints allowed)
		)
		(placement
			(enabled no)
			(sheetname "")
		)
		(fill yes
			(thermal_gap 0.5)
			(thermal_bridge_width 0.5)
			(island_removal_mode 0)
		)
		(polygon
			(pts
				(arc
					(start 82.890868 -403.883876)
					(mid 82.187288 -403.883876)
					(end 82.890868 -403.883876)
				)
			)
		)
	)
	(zone
		(layers "B.Cu" "In13.Cu" "In15.Cu")
		(hatch none 0.5)
		(connect_pads
			(clearance 0)
		)
		(min_thickness 0.25)
		(keepout
			(tracks not_allowed)
			(vias allowed)
			(pads allowed)
			(copperpour not_allowed)
			(footprints allowed)
		)
		(placement
			(enabled no)
			(sheetname "")
		)
		(fill yes
			(thermal_gap 0.5)
			(thermal_bridge_width 0.5)
			(island_removal_mode 0)
		)
		(polygon
			(pts
				(arc
					(start 49.195228 -403.883876)
					(mid 48.491648 -403.883876)
					(end 49.195228 -403.883876)
				)
			)
		)
	)
	(zone
		(layers "B.Cu" "In13.Cu" "In15.Cu")
		(hatch none 0.5)
		(connect_pads
			(clearance 0)
		)
		(min_thickness 0.25)
		(keepout
			(tracks not_allowed)
			(vias allowed)
			(pads allowed)
			(copperpour not_allowed)
			(footprints allowed)
		)
		(placement
			(enabled no)
			(sheetname "")
		)
		(fill yes
			(thermal_gap 0.5)
			(thermal_bridge_width 0.5)
			(island_removal_mode 0)
		)
		(polygon
			(pts
				(arc
					(start 32.836866 -4.962652)
					(mid 32.133286 -4.962652)
					(end 32.836866 -4.962652)
				)
			)
		)
	)
	(zone
		(layers "B.Cu" "In13.Cu" "In15.Cu")
		(hatch none 0.5)
		(connect_pads
			(clearance 0)
		)
		(min_thickness 0.25)
		(keepout
			(tracks not_allowed)
			(vias allowed)
			(pads allowed)
			(copperpour not_allowed)
			(footprints allowed)
		)
		(placement
			(enabled no)
			(sheetname "")
		)
		(fill yes
			(thermal_gap 0.5)
			(thermal_bridge_width 0.5)
			(island_removal_mode 0)
		)
		(polygon
			(pts
				(arc
					(start 96.929956 -248.806208)
					(mid 96.277176 -248.806208)
					(end 96.929956 -248.806208)
				)
			)
		)
	)
	(zone
		(layers "B.Cu" "In13.Cu" "In15.Cu")
		(hatch none 0.5)
		(connect_pads
			(clearance 0)
		)
		(min_thickness 0.25)
		(keepout
			(tracks not_allowed)
			(vias allowed)
			(pads allowed)
			(copperpour not_allowed)
			(footprints allowed)
		)
		(placement
			(enabled no)
			(sheetname "")
		)
		(fill yes
			(thermal_gap 0.5)
			(thermal_bridge_width 0.5)
			(island_removal_mode 0)
		)
		(polygon
			(pts
				(arc
					(start 107.737402 -220.319854)
					(mid 107.084622 -220.319854)
					(end 107.737402 -220.319854)
				)
			)
		)
	)
	(zone
		(layers "B.Cu" "In13.Cu" "In15.Cu")
		(hatch none 0.5)
		(connect_pads
			(clearance 0)
		)
		(min_thickness 0.25)
		(keepout
			(tracks not_allowed)
			(vias allowed)
			(pads allowed)
			(copperpour not_allowed)
			(footprints allowed)
		)
		(placement
			(enabled no)
			(sheetname "")
		)
		(fill yes
			(thermal_gap 0.5)
			(thermal_bridge_width 0.5)
			(island_removal_mode 0)
		)
		(polygon
			(pts
				(arc
					(start 17.115536 -199.866758)
					(mid 16.462756 -199.866758)
					(end 17.115536 -199.866758)
				)
			)
		)
	)
	(zone
		(layers "B.Cu" "In13.Cu" "In15.Cu")
		(hatch none 0.5)
		(connect_pads
			(clearance 0)
		)
		(min_thickness 0.25)
		(keepout
			(tracks not_allowed)
			(vias allowed)
			(pads allowed)
			(copperpour not_allowed)
			(footprints allowed)
		)
		(placement
			(enabled no)
			(sheetname "")
		)
		(fill yes
			(thermal_gap 0.5)
			(thermal_bridge_width 0.5)
			(island_removal_mode 0)
		)
		(polygon
			(pts
				(arc
					(start 373.064024 -232.528364)
					(mid 372.411244 -232.528364)
					(end 373.064024 -232.528364)
				)
			)
		)
	)
	(zone
		(layers "B.Cu" "In13.Cu" "In15.Cu")
		(hatch none 0.5)
		(connect_pads
			(clearance 0)
		)
		(min_thickness 0.25)
		(keepout
			(tracks not_allowed)
			(vias allowed)
			(pads allowed)
			(copperpour not_allowed)
			(footprints allowed)
		)
		(placement
			(enabled no)
			(sheetname "")
		)
		(fill yes
			(thermal_gap 0.5)
			(thermal_bridge_width 0.5)
			(island_removal_mode 0)
		)
		(polygon
			(pts
				(arc
					(start 17.115536 -278.916638)
					(mid 16.462756 -278.916638)
					(end 17.115536 -278.916638)
				)
			)
		)
	)
	(zone
		(layers "B.Cu" "In13.Cu" "In15.Cu")
		(hatch none 0.5)
		(connect_pads
			(clearance 0)
		)
		(min_thickness 0.25)
		(keepout
			(tracks not_allowed)
			(vias allowed)
			(pads allowed)
			(copperpour not_allowed)
			(footprints allowed)
		)
		(placement
			(enabled no)
			(sheetname "")
		)
		(fill yes
			(thermal_gap 0.5)
			(thermal_bridge_width 0.5)
			(island_removal_mode 0)
		)
		(polygon
			(pts
				(arc
					(start 58.384948 -403.883876)
					(mid 57.681368 -403.883876)
					(end 58.384948 -403.883876)
				)
			)
		)
	)
	(zone
		(layers "B.Cu" "In13.Cu" "In15.Cu")
		(hatch none 0.5)
		(connect_pads
			(clearance 0)
		)
		(min_thickness 0.25)
		(keepout
			(tracks not_allowed)
			(vias allowed)
			(pads allowed)
			(copperpour not_allowed)
			(footprints allowed)
		)
		(placement
			(enabled no)
			(sheetname "")
		)
		(fill yes
			(thermal_gap 0.5)
			(thermal_bridge_width 0.5)
			(island_removal_mode 0)
		)
		(polygon
			(pts
				(arc
					(start 346.859606 -271.825212)
					(mid 346.206826 -271.825212)
					(end 346.859606 -271.825212)
				)
			)
		)
	)
	(zone
		(layers "B.Cu" "In13.Cu" "In15.Cu")
		(hatch none 0.5)
		(connect_pads
			(clearance 0)
		)
		(min_thickness 0.25)
		(keepout
			(tracks not_allowed)
			(vias allowed)
			(pads allowed)
			(copperpour not_allowed)
			(footprints allowed)
		)
		(placement
			(enabled no)
			(sheetname "")
		)
		(fill yes
			(thermal_gap 0.5)
			(thermal_bridge_width 0.5)
			(island_removal_mode 0)
		)
		(polygon
			(pts
				(arc
					(start 347.21927 -246.364506)
					(mid 346.56649 -246.364506)
					(end 347.21927 -246.364506)
				)
			)
		)
	)
	(zone
		(layers "B.Cu" "In13.Cu" "In15.Cu")
		(hatch none 0.5)
		(connect_pads
			(clearance 0)
		)
		(min_thickness 0.25)
		(keepout
			(tracks not_allowed)
			(vias allowed)
			(pads allowed)
			(copperpour not_allowed)
			(footprints allowed)
		)
		(placement
			(enabled no)
			(sheetname "")
		)
		(fill yes
			(thermal_gap 0.5)
			(thermal_bridge_width 0.5)
			(island_removal_mode 0)
		)
		(polygon
			(pts
				(arc
					(start 348.15907 -249.620024)
					(mid 347.50629 -249.620024)
					(end 348.15907 -249.620024)
				)
			)
		)
	)
	(zone
		(layers "B.Cu" "In13.Cu" "In15.Cu")
		(hatch none 0.5)
		(connect_pads
			(clearance 0)
		)
		(min_thickness 0.25)
		(keepout
			(tracks not_allowed)
			(vias allowed)
			(pads allowed)
			(copperpour not_allowed)
			(footprints allowed)
		)
		(placement
			(enabled no)
			(sheetname "")
		)
		(fill yes
			(thermal_gap 0.5)
			(thermal_bridge_width 0.5)
			(island_removal_mode 0)
		)
		(polygon
			(pts
				(arc
					(start 348.15907 -236.597952)
					(mid 347.50629 -236.597952)
					(end 348.15907 -236.597952)
				)
			)
		)
	)
	(zone
		(layers "B.Cu" "In13.Cu" "In15.Cu")
		(hatch none 0.5)
		(connect_pads
			(clearance 0)
		)
		(min_thickness 0.25)
		(keepout
			(tracks not_allowed)
			(vias allowed)
			(pads allowed)
			(copperpour not_allowed)
			(footprints allowed)
		)
		(placement
			(enabled no)
			(sheetname "")
		)
		(fill yes
			(thermal_gap 0.5)
			(thermal_bridge_width 0.5)
			(island_removal_mode 0)
		)
		(polygon
			(pts
				(arc
					(start 167.318944 -403.883876)
					(mid 166.615364 -403.883876)
					(end 167.318944 -403.883876)
				)
			)
		)
	)
	(zone
		(layers "B.Cu" "In13.Cu" "In15.Cu")
		(hatch none 0.5)
		(connect_pads
			(clearance 0)
		)
		(min_thickness 0.25)
		(keepout
			(tracks not_allowed)
			(vias allowed)
			(pads allowed)
			(copperpour not_allowed)
			(footprints allowed)
		)
		(placement
			(enabled no)
			(sheetname "")
		)
		(fill yes
			(thermal_gap 0.5)
			(thermal_bridge_width 0.5)
			(island_removal_mode 0)
		)
		(polygon
			(pts
				(arc
					(start 323.05498 -429.689768)
					(mid 322.245228 -429.689768)
					(end 323.05498 -429.689768)
				)
			)
		)
	)
	(zone
		(layers "B.Cu" "In13.Cu" "In15.Cu")
		(hatch none 0.5)
		(connect_pads
			(clearance 0)
		)
		(min_thickness 0.25)
		(keepout
			(tracks not_allowed)
			(vias allowed)
			(pads allowed)
			(copperpour not_allowed)
			(footprints allowed)
		)
		(placement
			(enabled no)
			(sheetname "")
		)
		(fill yes
			(thermal_gap 0.5)
			(thermal_bridge_width 0.5)
			(island_removal_mode 0)
		)
		(polygon
			(pts
				(arc
					(start 100.219002 -249.620024)
					(mid 99.566222 -249.620024)
					(end 100.219002 -249.620024)
				)
			)
		)
	)
	(zone
		(layers "B.Cu" "In13.Cu" "In15.Cu")
		(hatch none 0.5)
		(connect_pads
			(clearance 0)
		)
		(min_thickness 0.25)
		(keepout
			(tracks not_allowed)
			(vias allowed)
			(pads allowed)
			(copperpour not_allowed)
			(footprints allowed)
		)
		(placement
			(enabled no)
			(sheetname "")
		)
		(fill yes
			(thermal_gap 0.5)
			(thermal_bridge_width 0.5)
			(island_removal_mode 0)
		)
		(polygon
			(pts
				(arc
					(start 207.397604 -270.416782)
					(mid 206.744824 -270.416782)
					(end 207.397604 -270.416782)
				)
			)
		)
	)
	(zone
		(layers "B.Cu" "In13.Cu" "In15.Cu")
		(hatch none 0.5)
		(connect_pads
			(clearance 0)
		)
		(min_thickness 0.25)
		(keepout
			(tracks not_allowed)
			(vias allowed)
			(pads allowed)
			(copperpour not_allowed)
			(footprints allowed)
		)
		(placement
			(enabled no)
			(sheetname "")
		)
		(fill yes
			(thermal_gap 0.5)
			(thermal_bridge_width 0.5)
			(island_removal_mode 0)
		)
		(polygon
			(pts
				(arc
					(start 125.593602 -236.597952)
					(mid 124.940822 -236.597952)
					(end 125.593602 -236.597952)
				)
			)
		)
	)
	(zone
		(layers "B.Cu" "In13.Cu" "In15.Cu")
		(hatch none 0.5)
		(connect_pads
			(clearance 0)
		)
		(min_thickness 0.25)
		(keepout
			(tracks not_allowed)
			(vias allowed)
			(pads allowed)
			(copperpour not_allowed)
			(footprints allowed)
		)
		(placement
			(enabled no)
			(sheetname "")
		)
		(fill yes
			(thermal_gap 0.5)
			(thermal_bridge_width 0.5)
			(island_removal_mode 0)
		)
		(polygon
			(pts
				(arc
					(start 451.237604 -288.266632)
					(mid 450.584824 -288.266632)
					(end 451.237604 -288.266632)
				)
			)
		)
	)
	(zone
		(layers "B.Cu" "In13.Cu" "In15.Cu")
		(hatch none 0.5)
		(connect_pads
			(clearance 0)
		)
		(min_thickness 0.25)
		(keepout
			(tracks not_allowed)
			(vias allowed)
			(pads allowed)
			(copperpour not_allowed)
			(footprints allowed)
		)
		(placement
			(enabled no)
			(sheetname "")
		)
		(fill yes
			(thermal_gap 0.5)
			(thermal_bridge_width 0.5)
			(island_removal_mode 0)
		)
		(polygon
			(pts
				(arc
					(start 21.215604 -273.816572)
					(mid 20.562824 -273.816572)
					(end 21.215604 -273.816572)
				)
			)
		)
	)
	(zone
		(layers "B.Cu" "In13.Cu" "In15.Cu")
		(hatch none 0.5)
		(connect_pads
			(clearance 0)
		)
		(min_thickness 0.25)
		(keepout
			(tracks not_allowed)
			(vias allowed)
			(pads allowed)
			(copperpour not_allowed)
			(footprints allowed)
		)
		(placement
			(enabled no)
			(sheetname "")
		)
		(fill yes
			(thermal_gap 0.5)
			(thermal_bridge_width 0.5)
			(island_removal_mode 0)
		)
		(polygon
			(pts
				(arc
					(start 21.215604 -218.566746)
					(mid 20.562824 -218.566746)
					(end 21.215604 -218.566746)
				)
			)
		)
	)
	(zone
		(layers "B.Cu" "In13.Cu" "In15.Cu")
		(hatch none 0.5)
		(connect_pads
			(clearance 0)
		)
		(min_thickness 0.25)
		(keepout
			(tracks not_allowed)
			(vias allowed)
			(pads allowed)
			(copperpour not_allowed)
			(footprints allowed)
		)
		(placement
			(enabled no)
			(sheetname "")
		)
		(fill yes
			(thermal_gap 0.5)
			(thermal_bridge_width 0.5)
			(island_removal_mode 0)
		)
		(polygon
			(pts
				(arc
					(start 380.96444 -403.883876)
					(mid 380.26086 -403.883876)
					(end 380.96444 -403.883876)
				)
			)
		)
	)
	(zone
		(layers "B.Cu" "In13.Cu" "In15.Cu")
		(hatch none 0.5)
		(connect_pads
			(clearance 0)
		)
		(min_thickness 0.25)
		(keepout
			(tracks not_allowed)
			(vias allowed)
			(pads allowed)
			(copperpour not_allowed)
			(footprints allowed)
		)
		(placement
			(enabled no)
			(sheetname "")
		)
		(fill yes
			(thermal_gap 0.5)
			(thermal_bridge_width 0.5)
			(island_removal_mode 0)
		)
		(polygon
			(pts
				(arc
					(start 323.05498 -430.889918)
					(mid 322.245228 -430.889918)
					(end 323.05498 -430.889918)
				)
			)
		)
	)
	(zone
		(layers "B.Cu" "In13.Cu" "In15.Cu")
		(hatch none 0.5)
		(connect_pads
			(clearance 0)
		)
		(min_thickness 0.25)
		(keepout
			(tracks not_allowed)
			(vias allowed)
			(pads allowed)
			(copperpour not_allowed)
			(footprints allowed)
		)
		(placement
			(enabled no)
			(sheetname "")
		)
		(fill yes
			(thermal_gap 0.5)
			(thermal_bridge_width 0.5)
			(island_removal_mode 0)
		)
		(polygon
			(pts
				(arc
					(start 145.012664 -403.883876)
					(mid 144.309084 -403.883876)
					(end 145.012664 -403.883876)
				)
			)
		)
	)
	(zone
		(layers "B.Cu" "In13.Cu" "In15.Cu")
		(hatch none 0.5)
		(connect_pads
			(clearance 0)
		)
		(min_thickness 0.25)
		(keepout
			(tracks not_allowed)
			(vias allowed)
			(pads allowed)
			(copperpour not_allowed)
			(footprints allowed)
		)
		(placement
			(enabled no)
			(sheetname "")
		)
		(fill yes
			(thermal_gap 0.5)
			(thermal_bridge_width 0.5)
			(island_removal_mode 0)
		)
		(polygon
			(pts
				(arc
					(start 100.328984 -272.639282)
					(mid 99.676204 -272.639282)
					(end 100.328984 -272.639282)
				)
			)
		)
	)
	(zone
		(layers "B.Cu" "In13.Cu" "In15.Cu")
		(hatch none 0.5)
		(connect_pads
			(clearance 0)
		)
		(min_thickness 0.25)
		(keepout
			(tracks not_allowed)
			(vias allowed)
			(pads allowed)
			(copperpour not_allowed)
			(footprints allowed)
		)
		(placement
			(enabled no)
			(sheetname "")
		)
		(fill yes
			(thermal_gap 0.5)
			(thermal_bridge_width 0.5)
			(island_removal_mode 0)
		)
		(polygon
			(pts
				(arc
					(start 203.297536 -299.316648)
					(mid 202.644756 -299.316648)
					(end 203.297536 -299.316648)
				)
			)
		)
	)
	(zone
		(layers "B.Cu" "In13.Cu" "In15.Cu")
		(hatch none 0.5)
		(connect_pads
			(clearance 0)
		)
		(min_thickness 0.25)
		(keepout
			(tracks not_allowed)
			(vias allowed)
			(pads allowed)
			(copperpour not_allowed)
			(footprints allowed)
		)
		(placement
			(enabled no)
			(sheetname "")
		)
		(fill yes
			(thermal_gap 0.5)
			(thermal_bridge_width 0.5)
			(island_removal_mode 0)
		)
		(polygon
			(pts
				(arc
					(start 203.297536 -286.56661)
					(mid 202.644756 -286.56661)
					(end 203.297536 -286.56661)
				)
			)
		)
	)
	(zone
		(layers "B.Cu" "In13.Cu" "In15.Cu")
		(hatch none 0.5)
		(connect_pads
			(clearance 0)
		)
		(min_thickness 0.25)
		(keepout
			(tracks not_allowed)
			(vias allowed)
			(pads allowed)
			(copperpour not_allowed)
			(footprints allowed)
		)
		(placement
			(enabled no)
			(sheetname "")
		)
		(fill yes
			(thermal_gap 0.5)
			(thermal_bridge_width 0.5)
			(island_removal_mode 0)
		)
		(polygon
			(pts
				(arc
					(start 207.397604 -278.066754)
					(mid 206.744824 -278.066754)
					(end 207.397604 -278.066754)
				)
			)
		)
	)
	(zone
		(layers "B.Cu" "In13.Cu" "In15.Cu")
		(hatch none 0.5)
		(connect_pads
			(clearance 0)
		)
		(min_thickness 0.25)
		(keepout
			(tracks not_allowed)
			(vias allowed)
			(pads allowed)
			(copperpour not_allowed)
			(footprints allowed)
		)
		(placement
			(enabled no)
			(sheetname "")
		)
		(fill yes
			(thermal_gap 0.5)
			(thermal_bridge_width 0.5)
			(island_removal_mode 0)
		)
		(polygon
			(pts
				(arc
					(start 98.809556 -234.15625)
					(mid 98.156776 -234.15625)
					(end 98.809556 -234.15625)
				)
			)
		)
	)
	(zone
		(layers "B.Cu" "In13.Cu" "In15.Cu")
		(hatch none 0.5)
		(connect_pads
			(clearance 0)
		)
		(min_thickness 0.25)
		(keepout
			(tracks not_allowed)
			(vias allowed)
			(pads allowed)
			(copperpour not_allowed)
			(footprints allowed)
		)
		(placement
			(enabled no)
			(sheetname "")
		)
		(fill yes
			(thermal_gap 0.5)
			(thermal_bridge_width 0.5)
			(island_removal_mode 0)
		)
		(polygon
			(pts
				(arc
					(start 88.111584 -285.661354)
					(mid 87.458804 -285.661354)
					(end 88.111584 -285.661354)
				)
			)
		)
	)
	(zone
		(layers "B.Cu" "In13.Cu" "In15.Cu")
		(hatch none 0.5)
		(connect_pads
			(clearance 0)
		)
		(min_thickness 0.25)
		(keepout
			(tracks not_allowed)
			(vias allowed)
			(pads allowed)
			(copperpour not_allowed)
			(footprints allowed)
		)
		(placement
			(enabled no)
			(sheetname "")
		)
		(fill yes
			(thermal_gap 0.5)
			(thermal_bridge_width 0.5)
			(island_removal_mode 0)
		)
		(polygon
			(pts
				(arc
					(start 388.154926 -428.28972)
					(mid 387.345174 -428.28972)
					(end 388.154926 -428.28972)
				)
			)
		)
	)
	(zone
		(layers "B.Cu" "In13.Cu" "In15.Cu")
		(hatch none 0.5)
		(connect_pads
			(clearance 0)
		)
		(min_thickness 0.25)
		(keepout
			(tracks not_allowed)
			(vias allowed)
			(pads allowed)
			(copperpour not_allowed)
			(footprints allowed)
		)
		(placement
			(enabled no)
			(sheetname "")
		)
		(fill yes
			(thermal_gap 0.5)
			(thermal_bridge_width 0.5)
			(island_removal_mode 0)
		)
		(polygon
			(pts
				(arc
					(start 105.388156 -221.133924)
					(mid 104.735376 -221.133924)
					(end 105.388156 -221.133924)
				)
			)
		)
	)
	(zone
		(layers "B.Cu" "In13.Cu" "In15.Cu")
		(hatch none 0.5)
		(connect_pads
			(clearance 0)
		)
		(min_thickness 0.25)
		(keepout
			(tracks not_allowed)
			(vias allowed)
			(pads allowed)
			(copperpour not_allowed)
			(footprints allowed)
		)
		(placement
			(enabled no)
			(sheetname "")
		)
		(fill yes
			(thermal_gap 0.5)
			(thermal_bridge_width 0.5)
			(island_removal_mode 0)
		)
		(polygon
			(pts
				(arc
					(start 265.055604 -278.916638)
					(mid 264.402824 -278.916638)
					(end 265.055604 -278.916638)
				)
			)
		)
	)
	(zone
		(layers "B.Cu" "In13.Cu" "In15.Cu")
		(hatch none 0.5)
		(connect_pads
			(clearance 0)
		)
		(min_thickness 0.25)
		(keepout
			(tracks not_allowed)
			(vias allowed)
			(pads allowed)
			(copperpour not_allowed)
			(footprints allowed)
		)
		(placement
			(enabled no)
			(sheetname "")
		)
		(fill yes
			(thermal_gap 0.5)
			(thermal_bridge_width 0.5)
			(island_removal_mode 0)
		)
		(polygon
			(pts
				(arc
					(start 100.328984 -262.872474)
					(mid 99.676204 -262.872474)
					(end 100.328984 -262.872474)
				)
			)
		)
	)
	(zone
		(layers "B.Cu" "In13.Cu" "In15.Cu")
		(hatch none 0.5)
		(connect_pads
			(clearance 0)
		)
		(min_thickness 0.25)
		(keepout
			(tracks not_allowed)
			(vias allowed)
			(pads allowed)
			(copperpour not_allowed)
			(footprints allowed)
		)
		(placement
			(enabled no)
			(sheetname "")
		)
		(fill yes
			(thermal_gap 0.5)
			(thermal_bridge_width 0.5)
			(island_removal_mode 0)
		)
		(polygon
			(pts
				(arc
					(start 82.054954 -430.689766)
					(mid 81.245202 -430.689766)
					(end 82.054954 -430.689766)
				)
			)
		)
	)
	(zone
		(layers "B.Cu" "In13.Cu" "In15.Cu")
		(hatch none 0.5)
		(connect_pads
			(clearance 0)
		)
		(min_thickness 0.25)
		(keepout
			(tracks not_allowed)
			(vias allowed)
			(pads allowed)
			(copperpour not_allowed)
			(footprints allowed)
		)
		(placement
			(enabled no)
			(sheetname "")
		)
		(fill yes
			(thermal_gap 0.5)
			(thermal_bridge_width 0.5)
			(island_removal_mode 0)
		)
		(polygon
			(pts
				(arc
					(start 269.155672 -302.716692)
					(mid 268.502892 -302.716692)
					(end 269.155672 -302.716692)
				)
			)
		)
	)
	(zone
		(layers "B.Cu" "In13.Cu" "In15.Cu")
		(hatch none 0.5)
		(connect_pads
			(clearance 0)
		)
		(min_thickness 0.25)
		(keepout
			(tracks not_allowed)
			(vias allowed)
			(pads allowed)
			(copperpour not_allowed)
			(footprints allowed)
		)
		(placement
			(enabled no)
			(sheetname "")
		)
		(fill yes
			(thermal_gap 0.5)
			(thermal_bridge_width 0.5)
			(island_removal_mode 0)
		)
		(polygon
			(pts
				(arc
					(start 451.237604 -267.866622)
					(mid 450.584824 -267.866622)
					(end 451.237604 -267.866622)
				)
			)
		)
	)
	(zone
		(layers "B.Cu" "In13.Cu" "In15.Cu")
		(hatch none 0.5)
		(connect_pads
			(clearance 0)
		)
		(min_thickness 0.25)
		(keepout
			(tracks not_allowed)
			(vias allowed)
			(pads allowed)
			(copperpour not_allowed)
			(footprints allowed)
		)
		(placement
			(enabled no)
			(sheetname "")
		)
		(fill yes
			(thermal_gap 0.5)
			(thermal_bridge_width 0.5)
			(island_removal_mode 0)
		)
		(polygon
			(pts
				(arc
					(start 371.764052 -269.38351)
					(mid 371.111272 -269.38351)
					(end 371.764052 -269.38351)
				)
			)
		)
	)
	(zone
		(layers "B.Cu" "In13.Cu" "In15.Cu")
		(hatch none 0.5)
		(connect_pads
			(clearance 0)
		)
		(min_thickness 0.25)
		(keepout
			(tracks not_allowed)
			(vias allowed)
			(pads allowed)
			(copperpour not_allowed)
			(footprints allowed)
		)
		(placement
			(enabled no)
			(sheetname "")
		)
		(fill yes
			(thermal_gap 0.5)
			(thermal_bridge_width 0.5)
			(island_removal_mode 0)
		)
		(polygon
			(pts
				(arc
					(start 124.184156 -234.15625)
					(mid 123.531376 -234.15625)
					(end 124.184156 -234.15625)
				)
			)
		)
	)
	(zone
		(layers "B.Cu" "In13.Cu" "In15.Cu")
		(hatch none 0.5)
		(connect_pads
			(clearance 0)
		)
		(min_thickness 0.25)
		(keepout
			(tracks not_allowed)
			(vias allowed)
			(pads allowed)
			(copperpour not_allowed)
			(footprints allowed)
		)
		(placement
			(enabled no)
			(sheetname "")
		)
		(fill yes
			(thermal_gap 0.5)
			(thermal_bridge_width 0.5)
			(island_removal_mode 0)
		)
		(polygon
			(pts
				(arc
					(start 17.115536 -228.766624)
					(mid 16.462756 -228.766624)
					(end 17.115536 -228.766624)
				)
			)
		)
	)
	(zone
		(layers "B.Cu" "In13.Cu" "In15.Cu")
		(hatch none 0.5)
		(connect_pads
			(clearance 0)
		)
		(min_thickness 0.25)
		(keepout
			(tracks not_allowed)
			(vias allowed)
			(pads allowed)
			(copperpour not_allowed)
			(footprints allowed)
		)
		(placement
			(enabled no)
			(sheetname "")
		)
		(fill yes
			(thermal_gap 0.5)
			(thermal_bridge_width 0.5)
			(island_removal_mode 0)
		)
		(polygon
			(pts
				(arc
					(start 67.574668 -403.883876)
					(mid 66.871088 -403.883876)
					(end 67.574668 -403.883876)
				)
			)
		)
	)
	(zone
		(layers "B.Cu" "In13.Cu" "In15.Cu")
		(hatch none 0.5)
		(connect_pads
			(clearance 0)
		)
		(min_thickness 0.25)
		(keepout
			(tracks not_allowed)
			(vias allowed)
			(pads allowed)
			(copperpour not_allowed)
			(footprints allowed)
		)
		(placement
			(enabled no)
			(sheetname "")
		)
		(fill yes
			(thermal_gap 0.5)
			(thermal_bridge_width 0.5)
			(island_removal_mode 0)
		)
		(polygon
			(pts
				(arc
					(start 136.686544 -403.883876)
					(mid 135.982964 -403.883876)
					(end 136.686544 -403.883876)
				)
			)
		)
	)
	(zone
		(layers "B.Cu" "In13.Cu" "In15.Cu")
		(hatch none 0.5)
		(connect_pads
			(clearance 0)
		)
		(min_thickness 0.25)
		(keepout
			(tracks not_allowed)
			(vias allowed)
			(pads allowed)
			(copperpour not_allowed)
			(footprints allowed)
		)
		(placement
			(enabled no)
			(sheetname "")
		)
		(fill yes
			(thermal_gap 0.5)
			(thermal_bridge_width 0.5)
			(island_removal_mode 0)
		)
		(polygon
			(pts
				(arc
					(start 203.297536 -219.41663)
					(mid 202.644756 -219.41663)
					(end 203.297536 -219.41663)
				)
			)
		)
	)
	(zone
		(layers "B.Cu" "In13.Cu" "In15.Cu")
		(hatch none 0.5)
		(connect_pads
			(clearance 0)
		)
		(min_thickness 0.25)
		(keepout
			(tracks not_allowed)
			(vias allowed)
			(pads allowed)
			(copperpour not_allowed)
			(footprints allowed)
		)
		(placement
			(enabled no)
			(sheetname "")
		)
		(fill yes
			(thermal_gap 0.5)
			(thermal_bridge_width 0.5)
			(island_removal_mode 0)
		)
		(polygon
			(pts
				(arc
					(start 207.397604 -298.466764)
					(mid 206.744824 -298.466764)
					(end 207.397604 -298.466764)
				)
			)
		)
	)
	(zone
		(layers "B.Cu" "In13.Cu" "In15.Cu")
		(hatch none 0.5)
		(connect_pads
			(clearance 0)
		)
		(min_thickness 0.25)
		(keepout
			(tracks not_allowed)
			(vias allowed)
			(pads allowed)
			(copperpour not_allowed)
			(footprints allowed)
		)
		(placement
			(enabled no)
			(sheetname "")
		)
		(fill yes
			(thermal_gap 0.5)
			(thermal_bridge_width 0.5)
			(island_removal_mode 0)
		)
		(polygon
			(pts
				(arc
					(start 136.154922 -428.28972)
					(mid 135.34517 -428.28972)
					(end 136.154922 -428.28972)
				)
			)
		)
	)
	(zone
		(layers "B.Cu" "In13.Cu" "In15.Cu")
		(hatch none 0.5)
		(connect_pads
			(clearance 0)
		)
		(min_thickness 0.25)
		(keepout
			(tracks not_allowed)
			(vias allowed)
			(pads allowed)
			(copperpour not_allowed)
			(footprints allowed)
		)
		(placement
			(enabled no)
			(sheetname "")
		)
		(fill yes
			(thermal_gap 0.5)
			(thermal_bridge_width 0.5)
			(island_removal_mode 0)
		)
		(polygon
			(pts
				(arc
					(start 372.124224 -235.783882)
					(mid 371.471444 -235.783882)
					(end 372.124224 -235.783882)
				)
			)
		)
	)
	(zone
		(layers "B.Cu" "In13.Cu" "In15.Cu")
		(hatch none 0.5)
		(connect_pads
			(clearance 0)
		)
		(min_thickness 0.25)
		(keepout
			(tracks not_allowed)
			(vias allowed)
			(pads allowed)
			(copperpour not_allowed)
			(footprints allowed)
		)
		(placement
			(enabled no)
			(sheetname "")
		)
		(fill yes
			(thermal_gap 0.5)
			(thermal_bridge_width 0.5)
			(island_removal_mode 0)
		)
		(polygon
			(pts
				(arc
					(start 102.678738 -283.219906)
					(mid 102.025958 -283.219906)
					(end 102.678738 -283.219906)
				)
			)
		)
	)
	(zone
		(layers "B.Cu" "In13.Cu" "In15.Cu")
		(hatch none 0.5)
		(connect_pads
			(clearance 0)
		)
		(min_thickness 0.25)
		(keepout
			(tracks not_allowed)
			(vias allowed)
			(pads allowed)
			(copperpour not_allowed)
			(footprints allowed)
		)
		(placement
			(enabled no)
			(sheetname "")
		)
		(fill yes
			(thermal_gap 0.5)
			(thermal_bridge_width 0.5)
			(island_removal_mode 0)
		)
		(polygon
			(pts
				(arc
					(start 100.799138 -263.686544)
					(mid 100.146358 -263.686544)
					(end 100.799138 -263.686544)
				)
			)
		)
	)
	(zone
		(layers "B.Cu" "In13.Cu" "In15.Cu")
		(hatch none 0.5)
		(connect_pads
			(clearance 0)
		)
		(min_thickness 0.25)
		(keepout
			(tracks not_allowed)
			(vias allowed)
			(pads allowed)
			(copperpour not_allowed)
			(footprints allowed)
		)
		(placement
			(enabled no)
			(sheetname "")
		)
		(fill yes
			(thermal_gap 0.5)
			(thermal_bridge_width 0.5)
			(island_removal_mode 0)
		)
		(polygon
			(pts
				(arc
					(start 123.823984 -259.616956)
					(mid 123.171204 -259.616956)
					(end 123.823984 -259.616956)
				)
			)
		)
	)
	(zone
		(layers "B.Cu" "In13.Cu" "In15.Cu")
		(hatch none 0.5)
		(connect_pads
			(clearance 0)
		)
		(min_thickness 0.25)
		(keepout
			(tracks not_allowed)
			(vias allowed)
			(pads allowed)
			(copperpour not_allowed)
			(footprints allowed)
		)
		(placement
			(enabled no)
			(sheetname "")
		)
		(fill yes
			(thermal_gap 0.5)
			(thermal_bridge_width 0.5)
			(island_removal_mode 0)
		)
		(polygon
			(pts
				(arc
					(start 203.297536 -224.516696)
					(mid 202.644756 -224.516696)
					(end 203.297536 -224.516696)
				)
			)
		)
	)
	(zone
		(layers "B.Cu" "In13.Cu" "In15.Cu")
		(hatch none 0.5)
		(connect_pads
			(clearance 0)
		)
		(min_thickness 0.25)
		(keepout
			(tracks not_allowed)
			(vias allowed)
			(pads allowed)
			(copperpour not_allowed)
			(footprints allowed)
		)
		(placement
			(enabled no)
			(sheetname "")
		)
		(fill yes
			(thermal_gap 0.5)
			(thermal_bridge_width 0.5)
			(island_removal_mode 0)
		)
		(polygon
			(pts
				(arc
					(start 98.809556 -230.900478)
					(mid 98.156776 -230.900478)
					(end 98.809556 -230.900478)
				)
			)
		)
	)
	(zone
		(layers "B.Cu" "In13.Cu" "In15.Cu")
		(hatch none 0.5)
		(connect_pads
			(clearance 0)
		)
		(min_thickness 0.25)
		(keepout
			(tracks not_allowed)
			(vias allowed)
			(pads allowed)
			(copperpour not_allowed)
			(footprints allowed)
		)
		(placement
			(enabled no)
			(sheetname "")
		)
		(fill yes
			(thermal_gap 0.5)
			(thermal_bridge_width 0.5)
			(island_removal_mode 0)
		)
		(polygon
			(pts
				(arc
					(start 207.397604 -273.816572)
					(mid 206.744824 -273.816572)
					(end 207.397604 -273.816572)
				)
			)
		)
	)
	(zone
		(layers "B.Cu" "In13.Cu" "In15.Cu")
		(hatch none 0.5)
		(connect_pads
			(clearance 0)
		)
		(min_thickness 0.25)
		(keepout
			(tracks not_allowed)
			(vias allowed)
			(pads allowed)
			(copperpour not_allowed)
			(footprints allowed)
		)
		(placement
			(enabled no)
			(sheetname "")
		)
		(fill yes
			(thermal_gap 0.5)
			(thermal_bridge_width 0.5)
			(island_removal_mode 0)
		)
		(polygon
			(pts
				(arc
					(start 372.124224 -234.15625)
					(mid 371.471444 -234.15625)
					(end 372.124224 -234.15625)
				)
			)
		)
	)
	(zone
		(layers "B.Cu" "In13.Cu" "In15.Cu")
		(hatch none 0.5)
		(connect_pads
			(clearance 0)
		)
		(min_thickness 0.25)
		(keepout
			(tracks not_allowed)
			(vias allowed)
			(pads allowed)
			(copperpour not_allowed)
			(footprints allowed)
		)
		(placement
			(enabled no)
			(sheetname "")
		)
		(fill yes
			(thermal_gap 0.5)
			(thermal_bridge_width 0.5)
			(island_removal_mode 0)
		)
		(polygon
			(pts
				(arc
					(start 373.064024 -237.411514)
					(mid 372.411244 -237.411514)
					(end 373.064024 -237.411514)
				)
			)
		)
	)
	(zone
		(layers "B.Cu" "In13.Cu" "In15.Cu")
		(hatch none 0.5)
		(connect_pads
			(clearance 0)
		)
		(min_thickness 0.25)
		(keepout
			(tracks not_allowed)
			(vias allowed)
			(pads allowed)
			(copperpour not_allowed)
			(footprints allowed)
		)
		(placement
			(enabled no)
			(sheetname "")
		)
		(fill yes
			(thermal_gap 0.5)
			(thermal_bridge_width 0.5)
			(island_removal_mode 0)
		)
		(polygon
			(pts
				(arc
					(start 124.184156 -229.272846)
					(mid 123.531376 -229.272846)
					(end 124.184156 -229.272846)
				)
			)
		)
	)
	(zone
		(layers "B.Cu" "In13.Cu" "In15.Cu")
		(hatch none 0.5)
		(connect_pads
			(clearance 0)
		)
		(min_thickness 0.25)
		(keepout
			(tracks not_allowed)
			(vias allowed)
			(pads allowed)
			(copperpour not_allowed)
			(footprints allowed)
		)
		(placement
			(enabled no)
			(sheetname "")
		)
		(fill yes
			(thermal_gap 0.5)
			(thermal_bridge_width 0.5)
			(island_removal_mode 0)
		)
		(polygon
			(pts
				(arc
					(start 26.5684 -6.724396)
					(mid 25.86482 -6.724396)
					(end 26.5684 -6.724396)
				)
			)
		)
	)
	(zone
		(layers "B.Cu" "In13.Cu" "In15.Cu")
		(hatch none 0.5)
		(connect_pads
			(clearance 0)
		)
		(min_thickness 0.25)
		(keepout
			(tracks not_allowed)
			(vias allowed)
			(pads allowed)
			(copperpour not_allowed)
			(footprints allowed)
		)
		(placement
			(enabled no)
			(sheetname "")
		)
		(fill yes
			(thermal_gap 0.5)
			(thermal_bridge_width 0.5)
			(island_removal_mode 0)
		)
		(polygon
			(pts
				(arc
					(start 336.051652 -280.778204)
					(mid 335.398872 -280.778204)
					(end 336.051652 -280.778204)
				)
			)
		)
	)
	(zone
		(layers "B.Cu" "In13.Cu" "In15.Cu")
		(hatch none 0.5)
		(connect_pads
			(clearance 0)
		)
		(min_thickness 0.25)
		(keepout
			(tracks not_allowed)
			(vias allowed)
			(pads allowed)
			(copperpour not_allowed)
			(footprints allowed)
		)
		(placement
			(enabled no)
			(sheetname "")
		)
		(fill yes
			(thermal_gap 0.5)
			(thermal_bridge_width 0.5)
			(island_removal_mode 0)
		)
		(polygon
			(pts
				(arc
					(start 336.054954 -429.689768)
					(mid 335.245202 -429.689768)
					(end 336.054954 -429.689768)
				)
			)
		)
	)
	(zone
		(layers "B.Cu" "In13.Cu" "In15.Cu")
		(hatch none 0.5)
		(connect_pads
			(clearance 0)
		)
		(min_thickness 0.25)
		(keepout
			(tracks not_allowed)
			(vias allowed)
			(pads allowed)
			(copperpour not_allowed)
			(footprints allowed)
		)
		(placement
			(enabled no)
			(sheetname "")
		)
		(fill yes
			(thermal_gap 0.5)
			(thermal_bridge_width 0.5)
			(island_removal_mode 0)
		)
		(polygon
			(pts
				(arc
					(start 455.337672 -285.716726)
					(mid 454.684892 -285.716726)
					(end 455.337672 -285.716726)
				)
			)
		)
	)
	(zone
		(layers "B.Cu" "In13.Cu" "In15.Cu")
		(hatch none 0.5)
		(connect_pads
			(clearance 0)
		)
		(min_thickness 0.25)
		(keepout
			(tracks not_allowed)
			(vias allowed)
			(pads allowed)
			(copperpour not_allowed)
			(footprints allowed)
		)
		(placement
			(enabled no)
			(sheetname "")
		)
		(fill yes
			(thermal_gap 0.5)
			(thermal_bridge_width 0.5)
			(island_removal_mode 0)
		)
		(polygon
			(pts
				(arc
					(start 207.397604 -285.716726)
					(mid 206.744824 -285.716726)
					(end 207.397604 -285.716726)
				)
			)
		)
	)
	(zone
		(layers "B.Cu" "In13.Cu" "In15.Cu")
		(hatch none 0.5)
		(connect_pads
			(clearance 0)
		)
		(min_thickness 0.25)
		(keepout
			(tracks not_allowed)
			(vias allowed)
			(pads allowed)
			(copperpour not_allowed)
			(footprints allowed)
		)
		(placement
			(enabled no)
			(sheetname "")
		)
		(fill yes
			(thermal_gap 0.5)
			(thermal_bridge_width 0.5)
			(island_removal_mode 0)
		)
		(polygon
			(pts
				(arc
					(start 403.154896 -426.089826)
					(mid 402.345144 -426.089826)
					(end 403.154896 -426.089826)
				)
			)
		)
	)
	(zone
		(layers "B.Cu" "In13.Cu" "In15.Cu")
		(hatch none 0.5)
		(connect_pads
			(clearance 0)
		)
		(min_thickness 0.25)
		(keepout
			(tracks not_allowed)
			(vias allowed)
			(pads allowed)
			(copperpour not_allowed)
			(footprints allowed)
		)
		(placement
			(enabled no)
			(sheetname "")
		)
		(fill yes
			(thermal_gap 0.5)
			(thermal_bridge_width 0.5)
			(island_removal_mode 0)
		)
		(polygon
			(pts
				(arc
					(start 99.279202 -228.45903)
					(mid 98.626422 -228.45903)
					(end 99.279202 -228.45903)
				)
			)
		)
	)
	(zone
		(layers "B.Cu" "In13.Cu" "In15.Cu")
		(hatch none 0.5)
		(connect_pads
			(clearance 0)
		)
		(min_thickness 0.25)
		(keepout
			(tracks not_allowed)
			(vias allowed)
			(pads allowed)
			(copperpour not_allowed)
			(footprints allowed)
		)
		(placement
			(enabled no)
			(sheetname "")
		)
		(fill yes
			(thermal_gap 0.5)
			(thermal_bridge_width 0.5)
			(island_removal_mode 0)
		)
		(polygon
			(pts
				(arc
					(start 67.054984 -430.889918)
					(mid 66.245232 -430.889918)
					(end 67.054984 -430.889918)
				)
			)
		)
	)
	(zone
		(layers "B.Cu" "In13.Cu" "In15.Cu")
		(hatch none 0.5)
		(connect_pads
			(clearance 0)
		)
		(min_thickness 0.25)
		(keepout
			(tracks not_allowed)
			(vias allowed)
			(pads allowed)
			(copperpour not_allowed)
			(footprints allowed)
		)
		(placement
			(enabled no)
			(sheetname "")
		)
		(fill yes
			(thermal_gap 0.5)
			(thermal_bridge_width 0.5)
			(island_removal_mode 0)
		)
		(polygon
			(pts
				(arc
					(start 151.154892 -427.289976)
					(mid 150.34514 -427.289976)
					(end 151.154892 -427.289976)
				)
			)
		)
	)
	(zone
		(layers "B.Cu" "In13.Cu" "In15.Cu")
		(hatch none 0.5)
		(connect_pads
			(clearance 0)
		)
		(min_thickness 0.25)
		(keepout
			(tracks not_allowed)
			(vias allowed)
			(pads allowed)
			(copperpour not_allowed)
			(footprints allowed)
		)
		(placement
			(enabled no)
			(sheetname "")
		)
		(fill yes
			(thermal_gap 0.5)
			(thermal_bridge_width 0.5)
			(island_removal_mode 0)
		)
		(polygon
			(pts
				(arc
					(start 327.120758 -410.030168)
					(mid 326.417178 -410.030168)
					(end 327.120758 -410.030168)
				)
			)
		)
	)
	(zone
		(layers "B.Cu" "In13.Cu" "In15.Cu")
		(hatch none 0.5)
		(connect_pads
			(clearance 0)
		)
		(min_thickness 0.25)
		(keepout
			(tracks not_allowed)
			(vias allowed)
			(pads allowed)
			(copperpour not_allowed)
			(footprints allowed)
		)
		(placement
			(enabled no)
			(sheetname "")
		)
		(fill yes
			(thermal_gap 0.5)
			(thermal_bridge_width 0.5)
			(island_removal_mode 0)
		)
		(polygon
			(pts
				(arc
					(start 21.215604 -296.766742)
					(mid 20.562824 -296.766742)
					(end 21.215604 -296.766742)
				)
			)
		)
	)
	(zone
		(layers "B.Cu" "In13.Cu" "In15.Cu")
		(hatch none 0.5)
		(connect_pads
			(clearance 0)
		)
		(min_thickness 0.25)
		(keepout
			(tracks not_allowed)
			(vias allowed)
			(pads allowed)
			(copperpour not_allowed)
			(footprints allowed)
		)
		(placement
			(enabled no)
			(sheetname "")
		)
		(fill yes
			(thermal_gap 0.5)
			(thermal_bridge_width 0.5)
			(island_removal_mode 0)
		)
		(polygon
			(pts
				(arc
					(start 372.234206 -263.686544)
					(mid 371.581426 -263.686544)
					(end 372.234206 -263.686544)
				)
			)
		)
	)
	(zone
		(layers "B.Cu" "In13.Cu" "In15.Cu")
		(hatch none 0.5)
		(connect_pads
			(clearance 0)
		)
		(min_thickness 0.25)
		(keepout
			(tracks not_allowed)
			(vias allowed)
			(pads allowed)
			(copperpour not_allowed)
			(footprints allowed)
		)
		(placement
			(enabled no)
			(sheetname "")
		)
		(fill yes
			(thermal_gap 0.5)
			(thermal_bridge_width 0.5)
			(island_removal_mode 0)
		)
		(polygon
			(pts
				(arc
					(start 451.237604 -249.166634)
					(mid 450.584824 -249.166634)
					(end 451.237604 -249.166634)
				)
			)
		)
	)
	(zone
		(layers "B.Cu" "In13.Cu" "In15.Cu")
		(hatch none 0.5)
		(connect_pads
			(clearance 0)
		)
		(min_thickness 0.25)
		(keepout
			(tracks not_allowed)
			(vias allowed)
			(pads allowed)
			(copperpour not_allowed)
			(footprints allowed)
		)
		(placement
			(enabled no)
			(sheetname "")
		)
		(fill yes
			(thermal_gap 0.5)
			(thermal_bridge_width 0.5)
			(island_removal_mode 0)
		)
		(polygon
			(pts
				(arc
					(start 126.173738 -265.314176)
					(mid 125.520958 -265.314176)
					(end 126.173738 -265.314176)
				)
			)
		)
	)
	(zone
		(layers "B.Cu" "In13.Cu" "In15.Cu")
		(hatch none 0.5)
		(connect_pads
			(clearance 0)
		)
		(min_thickness 0.25)
		(keepout
			(tracks not_allowed)
			(vias allowed)
			(pads allowed)
			(copperpour not_allowed)
			(footprints allowed)
		)
		(placement
			(enabled no)
			(sheetname "")
		)
		(fill yes
			(thermal_gap 0.5)
			(thermal_bridge_width 0.5)
			(island_removal_mode 0)
		)
		(polygon
			(pts
				(arc
					(start 116.665756 -221.133924)
					(mid 116.012976 -221.133924)
					(end 116.665756 -221.133924)
				)
			)
		)
	)
	(zone
		(layers "B.Cu" "In13.Cu" "In15.Cu")
		(hatch none 0.5)
		(connect_pads
			(clearance 0)
		)
		(min_thickness 0.25)
		(keepout
			(tracks not_allowed)
			(vias allowed)
			(pads allowed)
			(copperpour not_allowed)
			(footprints allowed)
		)
		(placement
			(enabled no)
			(sheetname "")
		)
		(fill yes
			(thermal_gap 0.5)
			(thermal_bridge_width 0.5)
			(island_removal_mode 0)
		)
		(polygon
			(pts
				(arc
					(start 329.054968 -431.889916)
					(mid 328.245216 -431.889916)
					(end 329.054968 -431.889916)
				)
			)
		)
	)
	(zone
		(layers "B.Cu" "In13.Cu" "In15.Cu")
		(hatch none 0.5)
		(connect_pads
			(clearance 0)
		)
		(min_thickness 0.25)
		(keepout
			(tracks not_allowed)
			(vias allowed)
			(pads allowed)
			(copperpour not_allowed)
			(footprints allowed)
		)
		(placement
			(enabled no)
			(sheetname "")
		)
		(fill yes
			(thermal_gap 0.5)
			(thermal_bridge_width 0.5)
			(island_removal_mode 0)
		)
		(polygon
			(pts
				(arc
					(start 451.237604 -297.616626)
					(mid 450.584824 -297.616626)
					(end 451.237604 -297.616626)
				)
			)
		)
	)
	(zone
		(layers "B.Cu" "In13.Cu" "In15.Cu")
		(hatch none 0.5)
		(connect_pads
			(clearance 0)
		)
		(min_thickness 0.25)
		(keepout
			(tracks not_allowed)
			(vias allowed)
			(pads allowed)
			(copperpour not_allowed)
			(footprints allowed)
		)
		(placement
			(enabled no)
			(sheetname "")
		)
		(fill yes
			(thermal_gap 0.5)
			(thermal_bridge_width 0.5)
			(island_removal_mode 0)
		)
		(polygon
			(pts
				(arc
					(start 124.184156 -245.55069)
					(mid 123.531376 -245.55069)
					(end 124.184156 -245.55069)
				)
			)
		)
	)
	(zone
		(layers "B.Cu" "In13.Cu" "In15.Cu")
		(hatch none 0.5)
		(connect_pads
			(clearance 0)
		)
		(min_thickness 0.25)
		(keepout
			(tracks not_allowed)
			(vias allowed)
			(pads allowed)
			(copperpour not_allowed)
			(footprints allowed)
		)
		(placement
			(enabled no)
			(sheetname "")
		)
		(fill yes
			(thermal_gap 0.5)
			(thermal_bridge_width 0.5)
			(island_removal_mode 0)
		)
		(polygon
			(pts
				(arc
					(start 203.297536 -259.366766)
					(mid 202.644756 -259.366766)
					(end 203.297536 -259.366766)
				)
			)
		)
	)
	(zone
		(layers "B.Cu" "In13.Cu" "In15.Cu")
		(hatch none 0.5)
		(connect_pads
			(clearance 0)
		)
		(min_thickness 0.25)
		(keepout
			(tracks not_allowed)
			(vias allowed)
			(pads allowed)
			(copperpour not_allowed)
			(footprints allowed)
		)
		(placement
			(enabled no)
			(sheetname "")
		)
		(fill yes
			(thermal_gap 0.5)
			(thermal_bridge_width 0.5)
			(island_removal_mode 0)
		)
		(polygon
			(pts
				(arc
					(start 100.328984 -266.128246)
					(mid 99.676204 -266.128246)
					(end 100.328984 -266.128246)
				)
			)
		)
	)
	(zone
		(layers "B.Cu" "In13.Cu" "In15.Cu")
		(hatch none 0.5)
		(connect_pads
			(clearance 0)
		)
		(min_thickness 0.25)
		(keepout
			(tracks not_allowed)
			(vias allowed)
			(pads allowed)
			(copperpour not_allowed)
			(footprints allowed)
		)
		(placement
			(enabled no)
			(sheetname "")
		)
		(fill yes
			(thermal_gap 0.5)
			(thermal_bridge_width 0.5)
			(island_removal_mode 0)
		)
		(polygon
			(pts
				(arc
					(start 373.53367 -243.108988)
					(mid 372.88089 -243.108988)
					(end 373.53367 -243.108988)
				)
			)
		)
	)
	(zone
		(layers "B.Cu" "In13.Cu" "In15.Cu")
		(hatch none 0.5)
		(connect_pads
			(clearance 0)
		)
		(min_thickness 0.25)
		(keepout
			(tracks not_allowed)
			(vias allowed)
			(pads allowed)
			(copperpour not_allowed)
			(footprints allowed)
		)
		(placement
			(enabled no)
			(sheetname "")
		)
		(fill yes
			(thermal_gap 0.5)
			(thermal_bridge_width 0.5)
			(island_removal_mode 0)
		)
		(polygon
			(pts
				(arc
					(start 207.397604 -225.36658)
					(mid 206.744824 -225.36658)
					(end 207.397604 -225.36658)
				)
			)
		)
	)
	(zone
		(layers "B.Cu" "In13.Cu" "In15.Cu")
		(hatch none 0.5)
		(connect_pads
			(clearance 0)
		)
		(min_thickness 0.25)
		(keepout
			(tracks not_allowed)
			(vias allowed)
			(pads allowed)
			(copperpour not_allowed)
			(footprints allowed)
		)
		(placement
			(enabled no)
			(sheetname "")
		)
		(fill yes
			(thermal_gap 0.5)
			(thermal_bridge_width 0.5)
			(island_removal_mode 0)
		)
		(polygon
			(pts
				(arc
					(start 344.054938 -429.689768)
					(mid 343.245186 -429.689768)
					(end 344.054938 -429.689768)
				)
			)
		)
	)
	(zone
		(layers "B.Cu" "In13.Cu" "In15.Cu")
		(hatch none 0.5)
		(connect_pads
			(clearance 0)
		)
		(min_thickness 0.25)
		(keepout
			(tracks not_allowed)
			(vias allowed)
			(pads allowed)
			(copperpour not_allowed)
			(footprints allowed)
		)
		(placement
			(enabled no)
			(sheetname "")
		)
		(fill yes
			(thermal_gap 0.5)
			(thermal_bridge_width 0.5)
			(island_removal_mode 0)
		)
		(polygon
			(pts
				(arc
					(start 207.397604 -293.366698)
					(mid 206.744824 -293.366698)
					(end 207.397604 -293.366698)
				)
			)
		)
	)
	(zone
		(layers "B.Cu" "In13.Cu" "In15.Cu")
		(hatch none 0.5)
		(connect_pads
			(clearance 0)
		)
		(min_thickness 0.25)
		(keepout
			(tracks not_allowed)
			(vias allowed)
			(pads allowed)
			(copperpour not_allowed)
			(footprints allowed)
		)
		(placement
			(enabled no)
			(sheetname "")
		)
		(fill yes
			(thermal_gap 0.5)
			(thermal_bridge_width 0.5)
			(island_removal_mode 0)
		)
		(polygon
			(pts
				(arc
					(start 269.155672 -203.266802)
					(mid 268.502892 -203.266802)
					(end 269.155672 -203.266802)
				)
			)
		)
	)
	(zone
		(layers "B.Cu" "In13.Cu" "In15.Cu")
		(hatch none 0.5)
		(connect_pads
			(clearance 0)
		)
		(min_thickness 0.25)
		(keepout
			(tracks not_allowed)
			(vias allowed)
			(pads allowed)
			(copperpour not_allowed)
			(footprints allowed)
		)
		(placement
			(enabled no)
			(sheetname "")
		)
		(fill yes
			(thermal_gap 0.5)
			(thermal_bridge_width 0.5)
			(island_removal_mode 0)
		)
		(polygon
			(pts
				(arc
					(start 101.268784 -280.778204)
					(mid 100.616004 -280.778204)
					(end 101.268784 -280.778204)
				)
			)
		)
	)
	(zone
		(layers "B.Cu" "In13.Cu" "In15.Cu")
		(hatch none 0.5)
		(connect_pads
			(clearance 0)
		)
		(min_thickness 0.25)
		(keepout
			(tracks not_allowed)
			(vias allowed)
			(pads allowed)
			(copperpour not_allowed)
			(footprints allowed)
		)
		(placement
			(enabled no)
			(sheetname "")
		)
		(fill yes
			(thermal_gap 0.5)
			(thermal_bridge_width 0.5)
			(island_removal_mode 0)
		)
		(polygon
			(pts
				(arc
					(start 407.344372 -4.95173)
					(mid 406.640792 -4.95173)
					(end 407.344372 -4.95173)
				)
			)
		)
	)
	(zone
		(layers "B.Cu" "In13.Cu" "In15.Cu")
		(hatch none 0.5)
		(connect_pads
			(clearance 0)
		)
		(min_thickness 0.25)
		(keepout
			(tracks not_allowed)
			(vias allowed)
			(pads allowed)
			(copperpour not_allowed)
			(footprints allowed)
		)
		(placement
			(enabled no)
			(sheetname "")
		)
		(fill yes
			(thermal_gap 0.5)
			(thermal_bridge_width 0.5)
			(island_removal_mode 0)
		)
		(polygon
			(pts
				(arc
					(start 125.233938 -253.919736)
					(mid 124.581158 -253.919736)
					(end 125.233938 -253.919736)
				)
			)
		)
	)
	(zone
		(layers "B.Cu" "In13.Cu" "In15.Cu")
		(hatch none 0.5)
		(connect_pads
			(clearance 0)
		)
		(min_thickness 0.25)
		(keepout
			(tracks not_allowed)
			(vias allowed)
			(pads allowed)
			(copperpour not_allowed)
			(footprints allowed)
		)
		(placement
			(enabled no)
			(sheetname "")
		)
		(fill yes
			(thermal_gap 0.5)
			(thermal_bridge_width 0.5)
			(island_removal_mode 0)
		)
		(polygon
			(pts
				(arc
					(start 207.397604 -290.816538)
					(mid 206.744824 -290.816538)
					(end 207.397604 -290.816538)
				)
			)
		)
	)
	(zone
		(layers "B.Cu" "In13.Cu" "In15.Cu")
		(hatch none 0.5)
		(connect_pads
			(clearance 0)
		)
		(min_thickness 0.25)
		(keepout
			(tracks not_allowed)
			(vias allowed)
			(pads allowed)
			(copperpour not_allowed)
			(footprints allowed)
		)
		(placement
			(enabled no)
			(sheetname "")
		)
		(fill yes
			(thermal_gap 0.5)
			(thermal_bridge_width 0.5)
			(island_removal_mode 0)
		)
		(polygon
			(pts
				(arc
					(start 17.115536 -218.566746)
					(mid 16.462756 -218.566746)
					(end 17.115536 -218.566746)
				)
			)
		)
	)
	(zone
		(layers "B.Cu" "In13.Cu" "In15.Cu")
		(hatch none 0.5)
		(connect_pads
			(clearance 0)
		)
		(min_thickness 0.25)
		(keepout
			(tracks not_allowed)
			(vias allowed)
			(pads allowed)
			(copperpour not_allowed)
			(footprints allowed)
		)
		(placement
			(enabled no)
			(sheetname "")
		)
		(fill yes
			(thermal_gap 0.5)
			(thermal_bridge_width 0.5)
			(island_removal_mode 0)
		)
		(polygon
			(pts
				(arc
					(start 320.994278 -410.030168)
					(mid 320.290698 -410.030168)
					(end 320.994278 -410.030168)
				)
			)
		)
	)
	(zone
		(layers "B.Cu" "In13.Cu" "In15.Cu")
		(hatch none 0.5)
		(connect_pads
			(clearance 0)
		)
		(min_thickness 0.25)
		(keepout
			(tracks not_allowed)
			(vias allowed)
			(pads allowed)
			(copperpour not_allowed)
			(footprints allowed)
		)
		(placement
			(enabled no)
			(sheetname "")
		)
		(fill yes
			(thermal_gap 0.5)
			(thermal_bridge_width 0.5)
			(island_removal_mode 0)
		)
		(polygon
			(pts
				(arc
					(start 113.376202 -220.319854)
					(mid 112.723422 -220.319854)
					(end 113.376202 -220.319854)
				)
			)
		)
	)
	(zone
		(layers "B.Cu" "In13.Cu" "In15.Cu")
		(hatch none 0.5)
		(connect_pads
			(clearance 0)
		)
		(min_thickness 0.25)
		(keepout
			(tracks not_allowed)
			(vias allowed)
			(pads allowed)
			(copperpour not_allowed)
			(footprints allowed)
		)
		(placement
			(enabled no)
			(sheetname "")
		)
		(fill yes
			(thermal_gap 0.5)
			(thermal_bridge_width 0.5)
			(island_removal_mode 0)
		)
		(polygon
			(pts
				(arc
					(start 17.115536 -198.166736)
					(mid 16.462756 -198.166736)
					(end 17.115536 -198.166736)
				)
			)
		)
	)
	(zone
		(layers "B.Cu" "In13.Cu" "In15.Cu")
		(hatch none 0.5)
		(connect_pads
			(clearance 0)
		)
		(min_thickness 0.25)
		(keepout
			(tracks not_allowed)
			(vias allowed)
			(pads allowed)
			(copperpour not_allowed)
			(footprints allowed)
		)
		(placement
			(enabled no)
			(sheetname "")
		)
		(fill yes
			(thermal_gap 0.5)
			(thermal_bridge_width 0.5)
			(island_removal_mode 0)
		)
		(polygon
			(pts
				(arc
					(start 269.155672 -306.116736)
					(mid 268.502892 -306.116736)
					(end 269.155672 -306.116736)
				)
			)
		)
	)
	(zone
		(layers "B.Cu" "In13.Cu" "In15.Cu")
		(hatch none 0.5)
		(connect_pads
			(clearance 0)
		)
		(min_thickness 0.25)
		(keepout
			(tracks not_allowed)
			(vias allowed)
			(pads allowed)
			(copperpour not_allowed)
			(footprints allowed)
		)
		(placement
			(enabled no)
			(sheetname "")
		)
		(fill yes
			(thermal_gap 0.5)
			(thermal_bridge_width 0.5)
			(island_removal_mode 0)
		)
		(polygon
			(pts
				(arc
					(start 124.184156 -230.900478)
					(mid 123.531376 -230.900478)
					(end 124.184156 -230.900478)
				)
			)
		)
	)
	(zone
		(layers "B.Cu" "In13.Cu" "In15.Cu")
		(hatch none 0.5)
		(connect_pads
			(clearance 0)
		)
		(min_thickness 0.25)
		(keepout
			(tracks not_allowed)
			(vias allowed)
			(pads allowed)
			(copperpour not_allowed)
			(footprints allowed)
		)
		(placement
			(enabled no)
			(sheetname "")
		)
		(fill yes
			(thermal_gap 0.5)
			(thermal_bridge_width 0.5)
			(island_removal_mode 0)
		)
		(polygon
			(pts
				(arc
					(start 374.003824 -247.178322)
					(mid 373.351044 -247.178322)
					(end 374.003824 -247.178322)
				)
			)
		)
	)
	(zone
		(layers "B.Cu" "In13.Cu" "In15.Cu")
		(hatch none 0.5)
		(connect_pads
			(clearance 0)
		)
		(min_thickness 0.25)
		(keepout
			(tracks not_allowed)
			(vias allowed)
			(pads allowed)
			(copperpour not_allowed)
			(footprints allowed)
		)
		(placement
			(enabled no)
			(sheetname "")
		)
		(fill yes
			(thermal_gap 0.5)
			(thermal_bridge_width 0.5)
			(island_removal_mode 0)
		)
		(polygon
			(pts
				(arc
					(start 51.352196 -6.724396)
					(mid 50.648616 -6.724396)
					(end 51.352196 -6.724396)
				)
			)
		)
	)
	(zone
		(layers "B.Cu" "In13.Cu" "In15.Cu")
		(hatch none 0.5)
		(connect_pads
			(clearance 0)
		)
		(min_thickness 0.25)
		(keepout
			(tracks not_allowed)
			(vias allowed)
			(pads allowed)
			(copperpour not_allowed)
			(footprints allowed)
		)
		(placement
			(enabled no)
			(sheetname "")
		)
		(fill yes
			(thermal_gap 0.5)
			(thermal_bridge_width 0.5)
			(island_removal_mode 0)
		)
		(polygon
			(pts
				(arc
					(start 455.337672 -281.466544)
					(mid 454.684892 -281.466544)
					(end 455.337672 -281.466544)
				)
			)
		)
	)
	(zone
		(layers "B.Cu" "In13.Cu" "In15.Cu")
		(hatch none 0.5)
		(connect_pads
			(clearance 0)
		)
		(min_thickness 0.25)
		(keepout
			(tracks not_allowed)
			(vias allowed)
			(pads allowed)
			(copperpour not_allowed)
			(footprints allowed)
		)
		(placement
			(enabled no)
			(sheetname "")
		)
		(fill yes
			(thermal_gap 0.5)
			(thermal_bridge_width 0.5)
			(island_removal_mode 0)
		)
		(polygon
			(pts
				(arc
					(start 114.786156 -221.133924)
					(mid 114.133376 -221.133924)
					(end 114.786156 -221.133924)
				)
			)
		)
	)
	(zone
		(layers "B.Cu" "In13.Cu" "In15.Cu")
		(hatch none 0.5)
		(connect_pads
			(clearance 0)
		)
		(min_thickness 0.25)
		(keepout
			(tracks not_allowed)
			(vias allowed)
			(pads allowed)
			(copperpour not_allowed)
			(footprints allowed)
		)
		(placement
			(enabled no)
			(sheetname "")
		)
		(fill yes
			(thermal_gap 0.5)
			(thermal_bridge_width 0.5)
			(island_removal_mode 0)
		)
		(polygon
			(pts
				(arc
					(start 145.154904 -427.089824)
					(mid 144.345152 -427.089824)
					(end 145.154904 -427.089824)
				)
			)
		)
	)
	(zone
		(layers "B.Cu" "In13.Cu" "In15.Cu")
		(hatch none 0.5)
		(connect_pads
			(clearance 0)
		)
		(min_thickness 0.25)
		(keepout
			(tracks not_allowed)
			(vias allowed)
			(pads allowed)
			(copperpour not_allowed)
			(footprints allowed)
		)
		(placement
			(enabled no)
			(sheetname "")
		)
		(fill yes
			(thermal_gap 0.5)
			(thermal_bridge_width 0.5)
			(island_removal_mode 0)
		)
		(polygon
			(pts
				(arc
					(start 102.208584 -282.405836)
					(mid 101.555804 -282.405836)
					(end 102.208584 -282.405836)
				)
			)
		)
	)
	(zone
		(layers "B.Cu" "In13.Cu" "In15.Cu")
		(hatch none 0.5)
		(connect_pads
			(clearance 0)
		)
		(min_thickness 0.25)
		(keepout
			(tracks not_allowed)
			(vias allowed)
			(pads allowed)
			(copperpour not_allowed)
			(footprints allowed)
		)
		(placement
			(enabled no)
			(sheetname "")
		)
		(fill yes
			(thermal_gap 0.5)
			(thermal_bridge_width 0.5)
			(island_removal_mode 0)
		)
		(polygon
			(pts
				(arc
					(start 395.680692 -4.95173)
					(mid 394.977112 -4.95173)
					(end 395.680692 -4.95173)
				)
			)
		)
	)
	(zone
		(layers "B.Cu" "In13.Cu" "In15.Cu")
		(hatch none 0.5)
		(connect_pads
			(clearance 0)
		)
		(min_thickness 0.25)
		(keepout
			(tracks not_allowed)
			(vias allowed)
			(pads allowed)
			(copperpour not_allowed)
			(footprints allowed)
		)
		(placement
			(enabled no)
			(sheetname "")
		)
		(fill yes
			(thermal_gap 0.5)
			(thermal_bridge_width 0.5)
			(island_removal_mode 0)
		)
		(polygon
			(pts
				(arc
					(start 17.115536 -226.216718)
					(mid 16.462756 -226.216718)
					(end 17.115536 -226.216718)
				)
			)
		)
	)
	(zone
		(layers "B.Cu" "In13.Cu" "In15.Cu")
		(hatch none 0.5)
		(connect_pads
			(clearance 0)
		)
		(min_thickness 0.25)
		(keepout
			(tracks not_allowed)
			(vias allowed)
			(pads allowed)
			(copperpour not_allowed)
			(footprints allowed)
		)
		(placement
			(enabled no)
			(sheetname "")
		)
		(fill yes
			(thermal_gap 0.5)
			(thermal_bridge_width 0.5)
			(island_removal_mode 0)
		)
		(polygon
			(pts
				(arc
					(start 17.115536 -261.066788)
					(mid 16.462756 -261.066788)
					(end 17.115536 -261.066788)
				)
			)
		)
	)
	(zone
		(layers "B.Cu" "In13.Cu" "In15.Cu")
		(hatch none 0.5)
		(connect_pads
			(clearance 0)
		)
		(min_thickness 0.25)
		(keepout
			(tracks not_allowed)
			(vias allowed)
			(pads allowed)
			(copperpour not_allowed)
			(footprints allowed)
		)
		(placement
			(enabled no)
			(sheetname "")
		)
		(fill yes
			(thermal_gap 0.5)
			(thermal_bridge_width 0.5)
			(island_removal_mode 0)
		)
		(polygon
			(pts
				(arc
					(start 203.297536 -228.766624)
					(mid 202.644756 -228.766624)
					(end 203.297536 -228.766624)
				)
			)
		)
	)
	(zone
		(layers "B.Cu" "In13.Cu" "In15.Cu")
		(hatch none 0.5)
		(connect_pads
			(clearance 0)
		)
		(min_thickness 0.25)
		(keepout
			(tracks not_allowed)
			(vias allowed)
			(pads allowed)
			(copperpour not_allowed)
			(footprints allowed)
		)
		(placement
			(enabled no)
			(sheetname "")
		)
		(fill yes
			(thermal_gap 0.5)
			(thermal_bridge_width 0.5)
			(island_removal_mode 0)
		)
		(polygon
			(pts
				(arc
					(start 354.268024 -221.133924)
					(mid 353.615244 -221.133924)
					(end 354.268024 -221.133924)
				)
			)
		)
	)
	(zone
		(layers "B.Cu" "In13.Cu" "In15.Cu")
		(hatch none 0.5)
		(connect_pads
			(clearance 0)
		)
		(min_thickness 0.25)
		(keepout
			(tracks not_allowed)
			(vias allowed)
			(pads allowed)
			(copperpour not_allowed)
			(footprints allowed)
		)
		(placement
			(enabled no)
			(sheetname "")
		)
		(fill yes
			(thermal_gap 0.5)
			(thermal_bridge_width 0.5)
			(island_removal_mode 0)
		)
		(polygon
			(pts
				(arc
					(start 100.689156 -230.900478)
					(mid 100.036376 -230.900478)
					(end 100.689156 -230.900478)
				)
			)
		)
	)
	(zone
		(layers "B.Cu" "In13.Cu" "In15.Cu")
		(hatch none 0.5)
		(connect_pads
			(clearance 0)
		)
		(min_thickness 0.25)
		(keepout
			(tracks not_allowed)
			(vias allowed)
			(pads allowed)
			(copperpour not_allowed)
			(footprints allowed)
		)
		(placement
			(enabled no)
			(sheetname "")
		)
		(fill yes
			(thermal_gap 0.5)
			(thermal_bridge_width 0.5)
			(island_removal_mode 0)
		)
		(polygon
			(pts
				(arc
					(start 265.055604 -238.116618)
					(mid 264.402824 -238.116618)
					(end 265.055604 -238.116618)
				)
			)
		)
	)
	(zone
		(layers "B.Cu" "In13.Cu" "In15.Cu")
		(hatch none 0.5)
		(connect_pads
			(clearance 0)
		)
		(min_thickness 0.25)
		(keepout
			(tracks not_allowed)
			(vias allowed)
			(pads allowed)
			(copperpour not_allowed)
			(footprints allowed)
		)
		(placement
			(enabled no)
			(sheetname "")
		)
		(fill yes
			(thermal_gap 0.5)
			(thermal_bridge_width 0.5)
			(island_removal_mode 0)
		)
		(polygon
			(pts
				(arc
					(start 21.215604 -227.066602)
					(mid 20.562824 -227.066602)
					(end 21.215604 -227.066602)
				)
			)
		)
	)
	(zone
		(layers "B.Cu" "In13.Cu" "In15.Cu")
		(hatch none 0.5)
		(connect_pads
			(clearance 0)
		)
		(min_thickness 0.25)
		(keepout
			(tracks not_allowed)
			(vias allowed)
			(pads allowed)
			(copperpour not_allowed)
			(footprints allowed)
		)
		(placement
			(enabled no)
			(sheetname "")
		)
		(fill yes
			(thermal_gap 0.5)
			(thermal_bridge_width 0.5)
			(island_removal_mode 0)
		)
		(polygon
			(pts
				(arc
					(start 348.629224 -235.783882)
					(mid 347.976444 -235.783882)
					(end 348.629224 -235.783882)
				)
			)
		)
	)
	(zone
		(layers "B.Cu" "In13.Cu" "In15.Cu")
		(hatch none 0.5)
		(connect_pads
			(clearance 0)
		)
		(min_thickness 0.25)
		(keepout
			(tracks not_allowed)
			(vias allowed)
			(pads allowed)
			(copperpour not_allowed)
			(footprints allowed)
		)
		(placement
			(enabled no)
			(sheetname "")
		)
		(fill yes
			(thermal_gap 0.5)
			(thermal_bridge_width 0.5)
			(island_removal_mode 0)
		)
		(polygon
			(pts
				(arc
					(start 332.054962 -429.689768)
					(mid 331.24521 -429.689768)
					(end 332.054962 -429.689768)
				)
			)
		)
	)
	(zone
		(layers "B.Cu" "In13.Cu" "In15.Cu")
		(hatch none 0.5)
		(connect_pads
			(clearance 0)
		)
		(min_thickness 0.25)
		(keepout
			(tracks not_allowed)
			(vias allowed)
			(pads allowed)
			(copperpour not_allowed)
			(footprints allowed)
		)
		(placement
			(enabled no)
			(sheetname "")
		)
		(fill yes
			(thermal_gap 0.5)
			(thermal_bridge_width 0.5)
			(island_removal_mode 0)
		)
		(polygon
			(pts
				(arc
					(start 44.683172 -4.962652)
					(mid 43.979592 -4.962652)
					(end 44.683172 -4.962652)
				)
			)
		)
	)
	(zone
		(layers "B.Cu" "In13.Cu" "In15.Cu")
		(hatch none 0.5)
		(connect_pads
			(clearance 0)
		)
		(min_thickness 0.25)
		(keepout
			(tracks not_allowed)
			(vias allowed)
			(pads allowed)
			(copperpour not_allowed)
			(footprints allowed)
		)
		(placement
			(enabled no)
			(sheetname "")
		)
		(fill yes
			(thermal_gap 0.5)
			(thermal_bridge_width 0.5)
			(island_removal_mode 0)
		)
		(polygon
			(pts
				(arc
					(start 207.397604 -199.01662)
					(mid 206.744824 -199.01662)
					(end 207.397604 -199.01662)
				)
			)
		)
	)
	(zone
		(layers "B.Cu" "In13.Cu" "In15.Cu")
		(hatch none 0.5)
		(connect_pads
			(clearance 0)
		)
		(min_thickness 0.25)
		(keepout
			(tracks not_allowed)
			(vias allowed)
			(pads allowed)
			(copperpour not_allowed)
			(footprints allowed)
		)
		(placement
			(enabled no)
			(sheetname "")
		)
		(fill yes
			(thermal_gap 0.5)
			(thermal_bridge_width 0.5)
			(island_removal_mode 0)
		)
		(polygon
			(pts
				(arc
					(start 336.521552 -283.219906)
					(mid 335.868772 -283.219906)
					(end 336.521552 -283.219906)
				)
			)
		)
	)
	(zone
		(layers "B.Cu" "In13.Cu" "In15.Cu")
		(hatch none 0.5)
		(connect_pads
			(clearance 0)
		)
		(min_thickness 0.25)
		(keepout
			(tracks not_allowed)
			(vias allowed)
			(pads allowed)
			(copperpour not_allowed)
			(footprints allowed)
		)
		(placement
			(enabled no)
			(sheetname "")
		)
		(fill yes
			(thermal_gap 0.5)
			(thermal_bridge_width 0.5)
			(island_removal_mode 0)
		)
		(polygon
			(pts
				(arc
					(start 344.054938 -430.889918)
					(mid 343.245186 -430.889918)
					(end 344.054938 -430.889918)
				)
			)
		)
	)
	(zone
		(layers "B.Cu" "In13.Cu" "In15.Cu")
		(hatch none 0.5)
		(connect_pads
			(clearance 0)
		)
		(min_thickness 0.25)
		(keepout
			(tracks not_allowed)
			(vias allowed)
			(pads allowed)
			(copperpour not_allowed)
			(footprints allowed)
		)
		(placement
			(enabled no)
			(sheetname "")
		)
		(fill yes
			(thermal_gap 0.5)
			(thermal_bridge_width 0.5)
			(island_removal_mode 0)
		)
		(polygon
			(pts
				(arc
					(start 207.397604 -292.51656)
					(mid 206.744824 -292.51656)
					(end 207.397604 -292.51656)
				)
			)
		)
	)
	(zone
		(layers "B.Cu" "In13.Cu" "In15.Cu")
		(hatch none 0.5)
		(connect_pads
			(clearance 0)
		)
		(min_thickness 0.25)
		(keepout
			(tracks not_allowed)
			(vias allowed)
			(pads allowed)
			(copperpour not_allowed)
			(footprints allowed)
		)
		(placement
			(enabled no)
			(sheetname "")
		)
		(fill yes
			(thermal_gap 0.5)
			(thermal_bridge_width 0.5)
			(island_removal_mode 0)
		)
		(polygon
			(pts
				(arc
					(start 119.485156 -221.133924)
					(mid 118.832376 -221.133924)
					(end 119.485156 -221.133924)
				)
			)
		)
	)
	(zone
		(layers "B.Cu" "In13.Cu" "In15.Cu")
		(hatch none 0.5)
		(connect_pads
			(clearance 0)
		)
		(min_thickness 0.25)
		(keepout
			(tracks not_allowed)
			(vias allowed)
			(pads allowed)
			(copperpour not_allowed)
			(footprints allowed)
		)
		(placement
			(enabled no)
			(sheetname "")
		)
		(fill yes
			(thermal_gap 0.5)
			(thermal_bridge_width 0.5)
			(island_removal_mode 0)
		)
		(polygon
			(pts
				(arc
					(start 371.184424 -237.411514)
					(mid 370.531644 -237.411514)
					(end 371.184424 -237.411514)
				)
			)
		)
	)
	(zone
		(layers "B.Cu" "In13.Cu" "In15.Cu")
		(hatch none 0.5)
		(connect_pads
			(clearance 0)
		)
		(min_thickness 0.25)
		(keepout
			(tracks not_allowed)
			(vias allowed)
			(pads allowed)
			(copperpour not_allowed)
			(footprints allowed)
		)
		(placement
			(enabled no)
			(sheetname "")
		)
		(fill yes
			(thermal_gap 0.5)
			(thermal_bridge_width 0.5)
			(island_removal_mode 0)
		)
		(polygon
			(pts
				(arc
					(start 371.294406 -260.430772)
					(mid 370.641626 -260.430772)
					(end 371.294406 -260.430772)
				)
			)
		)
	)
	(zone
		(layers "B.Cu" "In13.Cu" "In15.Cu")
		(hatch none 0.5)
		(connect_pads
			(clearance 0)
		)
		(min_thickness 0.25)
		(keepout
			(tracks not_allowed)
			(vias allowed)
			(pads allowed)
			(copperpour not_allowed)
			(footprints allowed)
		)
		(placement
			(enabled no)
			(sheetname "")
		)
		(fill yes
			(thermal_gap 0.5)
			(thermal_bridge_width 0.5)
			(island_removal_mode 0)
		)
		(polygon
			(pts
				(arc
					(start 269.155672 -279.766776)
					(mid 268.502892 -279.766776)
					(end 269.155672 -279.766776)
				)
			)
		)
	)
	(zone
		(layers "B.Cu" "In13.Cu" "In15.Cu")
		(hatch none 0.5)
		(connect_pads
			(clearance 0)
		)
		(min_thickness 0.25)
		(keepout
			(tracks not_allowed)
			(vias allowed)
			(pads allowed)
			(copperpour not_allowed)
			(footprints allowed)
		)
		(placement
			(enabled no)
			(sheetname "")
		)
		(fill yes
			(thermal_gap 0.5)
			(thermal_bridge_width 0.5)
			(island_removal_mode 0)
		)
		(polygon
			(pts
				(arc
					(start 99.279202 -239.853216)
					(mid 98.626422 -239.853216)
					(end 99.279202 -239.853216)
				)
			)
		)
	)
	(zone
		(layers "B.Cu" "In13.Cu" "In15.Cu")
		(hatch none 0.5)
		(connect_pads
			(clearance 0)
		)
		(min_thickness 0.25)
		(keepout
			(tracks not_allowed)
			(vias allowed)
			(pads allowed)
			(copperpour not_allowed)
			(footprints allowed)
		)
		(placement
			(enabled no)
			(sheetname "")
		)
		(fill yes
			(thermal_gap 0.5)
			(thermal_bridge_width 0.5)
			(island_removal_mode 0)
		)
		(polygon
			(pts
				(arc
					(start 371.764052 -266.128246)
					(mid 371.111272 -266.128246)
					(end 371.764052 -266.128246)
				)
			)
		)
	)
	(zone
		(layers "B.Cu" "In13.Cu" "In15.Cu")
		(hatch none 0.5)
		(connect_pads
			(clearance 0)
		)
		(min_thickness 0.25)
		(keepout
			(tracks not_allowed)
			(vias allowed)
			(pads allowed)
			(copperpour not_allowed)
			(footprints allowed)
		)
		(placement
			(enabled no)
			(sheetname "")
		)
		(fill yes
			(thermal_gap 0.5)
			(thermal_bridge_width 0.5)
			(island_removal_mode 0)
		)
		(polygon
			(pts
				(arc
					(start 451.237604 -224.516696)
					(mid 450.584824 -224.516696)
					(end 451.237604 -224.516696)
				)
			)
		)
	)
	(zone
		(layers "B.Cu" "In13.Cu" "In15.Cu")
		(hatch none 0.5)
		(connect_pads
			(clearance 0)
		)
		(min_thickness 0.25)
		(keepout
			(tracks not_allowed)
			(vias allowed)
			(pads allowed)
			(copperpour not_allowed)
			(footprints allowed)
		)
		(placement
			(enabled no)
			(sheetname "")
		)
		(fill yes
			(thermal_gap 0.5)
			(thermal_bridge_width 0.5)
			(island_removal_mode 0)
		)
		(polygon
			(pts
				(arc
					(start 125.233938 -268.569694)
					(mid 124.581158 -268.569694)
					(end 125.233938 -268.569694)
				)
			)
		)
	)
	(zone
		(layers "B.Cu" "In13.Cu" "In15.Cu")
		(hatch none 0.5)
		(connect_pads
			(clearance 0)
		)
		(min_thickness 0.25)
		(keepout
			(tracks not_allowed)
			(vias allowed)
			(pads allowed)
			(copperpour not_allowed)
			(footprints allowed)
		)
		(placement
			(enabled no)
			(sheetname "")
		)
		(fill yes
			(thermal_gap 0.5)
			(thermal_bridge_width 0.5)
			(island_removal_mode 0)
		)
		(polygon
			(pts
				(arc
					(start 103.148384 -279.150318)
					(mid 102.495604 -279.150318)
					(end 103.148384 -279.150318)
				)
			)
		)
	)
	(zone
		(layers "B.Cu" "In13.Cu" "In15.Cu")
		(hatch none 0.5)
		(connect_pads
			(clearance 0)
		)
		(min_thickness 0.25)
		(keepout
			(tracks not_allowed)
			(vias allowed)
			(pads allowed)
			(copperpour not_allowed)
			(footprints allowed)
		)
		(placement
			(enabled no)
			(sheetname "")
		)
		(fill yes
			(thermal_gap 0.5)
			(thermal_bridge_width 0.5)
			(island_removal_mode 0)
		)
		(polygon
			(pts
				(arc
					(start 72.837548 -403.883876)
					(mid 72.133968 -403.883876)
					(end 72.837548 -403.883876)
				)
			)
		)
	)
	(zone
		(layers "B.Cu" "In13.Cu" "In15.Cu")
		(hatch none 0.5)
		(connect_pads
			(clearance 0)
		)
		(min_thickness 0.25)
		(keepout
			(tracks not_allowed)
			(vias allowed)
			(pads allowed)
			(copperpour not_allowed)
			(footprints allowed)
		)
		(placement
			(enabled no)
			(sheetname "")
		)
		(fill yes
			(thermal_gap 0.5)
			(thermal_bridge_width 0.5)
			(island_removal_mode 0)
		)
		(polygon
			(pts
				(arc
					(start 455.337672 -259.366766)
					(mid 454.684892 -259.366766)
					(end 455.337672 -259.366766)
				)
			)
		)
	)
	(zone
		(layers "B.Cu" "In13.Cu" "In15.Cu")
		(hatch none 0.5)
		(connect_pads
			(clearance 0)
		)
		(min_thickness 0.25)
		(keepout
			(tracks not_allowed)
			(vias allowed)
			(pads allowed)
			(copperpour not_allowed)
			(footprints allowed)
		)
		(placement
			(enabled no)
			(sheetname "")
		)
		(fill yes
			(thermal_gap 0.5)
			(thermal_bridge_width 0.5)
			(island_removal_mode 0)
		)
		(polygon
			(pts
				(arc
					(start 203.297536 -233.86669)
					(mid 202.644756 -233.86669)
					(end 203.297536 -233.86669)
				)
			)
		)
	)
	(zone
		(layers "B.Cu" "In13.Cu" "In15.Cu")
		(hatch none 0.5)
		(connect_pads
			(clearance 0)
		)
		(min_thickness 0.25)
		(keepout
			(tracks not_allowed)
			(vias allowed)
			(pads allowed)
			(copperpour not_allowed)
			(footprints allowed)
		)
		(placement
			(enabled no)
			(sheetname "")
		)
		(fill yes
			(thermal_gap 0.5)
			(thermal_bridge_width 0.5)
			(island_removal_mode 0)
		)
		(polygon
			(pts
				(arc
					(start 102.678738 -281.59202)
					(mid 102.025958 -281.59202)
					(end 102.678738 -281.59202)
				)
			)
		)
	)
	(zone
		(layers "B.Cu" "In13.Cu" "In15.Cu")
		(hatch none 0.5)
		(connect_pads
			(clearance 0)
		)
		(min_thickness 0.25)
		(keepout
			(tracks not_allowed)
			(vias allowed)
			(pads allowed)
			(copperpour not_allowed)
			(footprints allowed)
		)
		(placement
			(enabled no)
			(sheetname "")
		)
		(fill yes
			(thermal_gap 0.5)
			(thermal_bridge_width 0.5)
			(island_removal_mode 0)
		)
		(polygon
			(pts
				(arc
					(start 269.155672 -217.716608)
					(mid 268.502892 -217.716608)
					(end 269.155672 -217.716608)
				)
			)
		)
	)
	(zone
		(layers "B.Cu" "In13.Cu" "In15.Cu")
		(hatch none 0.5)
		(connect_pads
			(clearance 0)
		)
		(min_thickness 0.25)
		(keepout
			(tracks not_allowed)
			(vias allowed)
			(pads allowed)
			(copperpour not_allowed)
			(footprints allowed)
		)
		(placement
			(enabled no)
			(sheetname "")
		)
		(fill yes
			(thermal_gap 0.5)
			(thermal_bridge_width 0.5)
			(island_removal_mode 0)
		)
		(polygon
			(pts
				(arc
					(start 203.297536 -280.61666)
					(mid 202.644756 -280.61666)
					(end 203.297536 -280.61666)
				)
			)
		)
	)
	(zone
		(layers "B.Cu" "In13.Cu" "In15.Cu")
		(hatch none 0.5)
		(connect_pads
			(clearance 0)
		)
		(min_thickness 0.25)
		(keepout
			(tracks not_allowed)
			(vias allowed)
			(pads allowed)
			(copperpour not_allowed)
			(footprints allowed)
		)
		(placement
			(enabled no)
			(sheetname "")
		)
		(fill yes
			(thermal_gap 0.5)
			(thermal_bridge_width 0.5)
			(island_removal_mode 0)
		)
		(polygon
			(pts
				(arc
					(start 153.154888 -427.089824)
					(mid 152.345136 -427.089824)
					(end 153.154888 -427.089824)
				)
			)
		)
	)
	(zone
		(layers "B.Cu" "In13.Cu" "In15.Cu")
		(hatch none 0.5)
		(connect_pads
			(clearance 0)
		)
		(min_thickness 0.25)
		(keepout
			(tracks not_allowed)
			(vias allowed)
			(pads allowed)
			(copperpour not_allowed)
			(footprints allowed)
		)
		(placement
			(enabled no)
			(sheetname "")
		)
		(fill yes
			(thermal_gap 0.5)
			(thermal_bridge_width 0.5)
			(island_removal_mode 0)
		)
		(polygon
			(pts
				(arc
					(start 403.27072 -403.883876)
					(mid 402.56714 -403.883876)
					(end 403.27072 -403.883876)
				)
			)
		)
	)
	(zone
		(layers "B.Cu" "In13.Cu" "In15.Cu")
		(hatch none 0.5)
		(connect_pads
			(clearance 0)
		)
		(min_thickness 0.25)
		(keepout
			(tracks not_allowed)
			(vias allowed)
			(pads allowed)
			(copperpour not_allowed)
			(footprints allowed)
		)
		(placement
			(enabled no)
			(sheetname "")
		)
		(fill yes
			(thermal_gap 0.5)
			(thermal_bridge_width 0.5)
			(island_removal_mode 0)
		)
		(polygon
			(pts
				(arc
					(start 344.509852 -282.405836)
					(mid 343.857072 -282.405836)
					(end 344.509852 -282.405836)
				)
			)
		)
	)
	(zone
		(layers "B.Cu" "In13.Cu" "In15.Cu")
		(hatch none 0.5)
		(connect_pads
			(clearance 0)
		)
		(min_thickness 0.25)
		(keepout
			(tracks not_allowed)
			(vias allowed)
			(pads allowed)
			(copperpour not_allowed)
			(footprints allowed)
		)
		(placement
			(enabled no)
			(sheetname "")
		)
		(fill yes
			(thermal_gap 0.5)
			(thermal_bridge_width 0.5)
			(island_removal_mode 0)
		)
		(polygon
			(pts
				(arc
					(start 138.154918 -426.089826)
					(mid 137.345166 -426.089826)
					(end 138.154918 -426.089826)
				)
			)
		)
	)
	(zone
		(layers "B.Cu" "In13.Cu" "In15.Cu")
		(hatch none 0.5)
		(connect_pads
			(clearance 0)
		)
		(min_thickness 0.25)
		(keepout
			(tracks not_allowed)
			(vias allowed)
			(pads allowed)
			(copperpour not_allowed)
			(footprints allowed)
		)
		(placement
			(enabled no)
			(sheetname "")
		)
		(fill yes
			(thermal_gap 0.5)
			(thermal_bridge_width 0.5)
			(island_removal_mode 0)
		)
		(polygon
			(pts
				(arc
					(start 348.269052 -259.616956)
					(mid 347.616272 -259.616956)
					(end 348.269052 -259.616956)
				)
			)
		)
	)
	(zone
		(layers "B.Cu" "In13.Cu" "In15.Cu")
		(hatch none 0.5)
		(connect_pads
			(clearance 0)
		)
		(min_thickness 0.25)
		(keepout
			(tracks not_allowed)
			(vias allowed)
			(pads allowed)
			(copperpour not_allowed)
			(footprints allowed)
		)
		(placement
			(enabled no)
			(sheetname "")
		)
		(fill yes
			(thermal_gap 0.5)
			(thermal_bridge_width 0.5)
			(island_removal_mode 0)
		)
		(polygon
			(pts
				(arc
					(start 451.237604 -280.61666)
					(mid 450.584824 -280.61666)
					(end 451.237604 -280.61666)
				)
			)
		)
	)
	(zone
		(layers "B.Cu" "In13.Cu" "In15.Cu")
		(hatch none 0.5)
		(connect_pads
			(clearance 0)
		)
		(min_thickness 0.25)
		(keepout
			(tracks not_allowed)
			(vias allowed)
			(pads allowed)
			(copperpour not_allowed)
			(footprints allowed)
		)
		(placement
			(enabled no)
			(sheetname "")
		)
		(fill yes
			(thermal_gap 0.5)
			(thermal_bridge_width 0.5)
			(island_removal_mode 0)
		)
		(polygon
			(pts
				(arc
					(start 360.846624 -221.133924)
					(mid 360.193844 -221.133924)
					(end 360.846624 -221.133924)
				)
			)
		)
	)
	(zone
		(layers "B.Cu" "In13.Cu" "In15.Cu")
		(hatch none 0.5)
		(connect_pads
			(clearance 0)
		)
		(min_thickness 0.25)
		(keepout
			(tracks not_allowed)
			(vias allowed)
			(pads allowed)
			(copperpour not_allowed)
			(footprints allowed)
		)
		(placement
			(enabled no)
			(sheetname "")
		)
		(fill yes
			(thermal_gap 0.5)
			(thermal_bridge_width 0.5)
			(island_removal_mode 0)
		)
		(polygon
			(pts
				(arc
					(start 265.055604 -226.216718)
					(mid 264.402824 -226.216718)
					(end 265.055604 -226.216718)
				)
			)
		)
	)
	(zone
		(layers "B.Cu" "In13.Cu" "In15.Cu")
		(hatch none 0.5)
		(connect_pads
			(clearance 0)
		)
		(min_thickness 0.25)
		(keepout
			(tracks not_allowed)
			(vias allowed)
			(pads allowed)
			(copperpour not_allowed)
			(footprints allowed)
		)
		(placement
			(enabled no)
			(sheetname "")
		)
		(fill yes
			(thermal_gap 0.5)
			(thermal_bridge_width 0.5)
			(island_removal_mode 0)
		)
		(polygon
			(pts
				(arc
					(start 99.389184 -259.616956)
					(mid 98.736404 -259.616956)
					(end 99.389184 -259.616956)
				)
			)
		)
	)
	(zone
		(layers "B.Cu" "In13.Cu" "In15.Cu")
		(hatch none 0.5)
		(connect_pads
			(clearance 0)
		)
		(min_thickness 0.25)
		(keepout
			(tracks not_allowed)
			(vias allowed)
			(pads allowed)
			(copperpour not_allowed)
			(footprints allowed)
		)
		(placement
			(enabled no)
			(sheetname "")
		)
		(fill yes
			(thermal_gap 0.5)
			(thermal_bridge_width 0.5)
			(island_removal_mode 0)
		)
		(polygon
			(pts
				(arc
					(start 402.40712 -403.883876)
					(mid 401.70354 -403.883876)
					(end 402.40712 -403.883876)
				)
			)
		)
	)
	(zone
		(layers "B.Cu" "In13.Cu" "In15.Cu")
		(hatch none 0.5)
		(connect_pads
			(clearance 0)
		)
		(min_thickness 0.25)
		(keepout
			(tracks not_allowed)
			(vias allowed)
			(pads allowed)
			(copperpour not_allowed)
			(footprints allowed)
		)
		(placement
			(enabled no)
			(sheetname "")
		)
		(fill yes
			(thermal_gap 0.5)
			(thermal_bridge_width 0.5)
			(island_removal_mode 0)
		)
		(polygon
			(pts
				(arc
					(start 207.397604 -227.066602)
					(mid 206.744824 -227.066602)
					(end 207.397604 -227.066602)
				)
			)
		)
	)
	(zone
		(layers "B.Cu" "In13.Cu" "In15.Cu")
		(hatch none 0.5)
		(connect_pads
			(clearance 0)
		)
		(min_thickness 0.25)
		(keepout
			(tracks not_allowed)
			(vias allowed)
			(pads allowed)
			(copperpour not_allowed)
			(footprints allowed)
		)
		(placement
			(enabled no)
			(sheetname "")
		)
		(fill yes
			(thermal_gap 0.5)
			(thermal_bridge_width 0.5)
			(island_removal_mode 0)
		)
		(polygon
			(pts
				(arc
					(start 99.279456 -247.992138)
					(mid 98.626676 -247.992138)
					(end 99.279456 -247.992138)
				)
			)
		)
	)
	(zone
		(layers "B.Cu" "In13.Cu" "In15.Cu")
		(hatch none 0.5)
		(connect_pads
			(clearance 0)
		)
		(min_thickness 0.25)
		(keepout
			(tracks not_allowed)
			(vias allowed)
			(pads allowed)
			(copperpour not_allowed)
			(footprints allowed)
		)
		(placement
			(enabled no)
			(sheetname "")
		)
		(fill yes
			(thermal_gap 0.5)
			(thermal_bridge_width 0.5)
			(island_removal_mode 0)
		)
		(polygon
			(pts
				(arc
					(start 126.063756 -247.178322)
					(mid 125.410976 -247.178322)
					(end 126.063756 -247.178322)
				)
			)
		)
	)
	(zone
		(layers "B.Cu" "In13.Cu" "In15.Cu")
		(hatch none 0.5)
		(connect_pads
			(clearance 0)
		)
		(min_thickness 0.25)
		(keepout
			(tracks not_allowed)
			(vias allowed)
			(pads allowed)
			(copperpour not_allowed)
			(footprints allowed)
		)
		(placement
			(enabled no)
			(sheetname "")
		)
		(fill yes
			(thermal_gap 0.5)
			(thermal_bridge_width 0.5)
			(island_removal_mode 0)
		)
		(polygon
			(pts
				(arc
					(start 451.237604 -230.466646)
					(mid 450.584824 -230.466646)
					(end 451.237604 -230.466646)
				)
			)
		)
	)
	(zone
		(layers "B.Cu" "In13.Cu" "In15.Cu")
		(hatch none 0.5)
		(connect_pads
			(clearance 0)
		)
		(min_thickness 0.25)
		(keepout
			(tracks not_allowed)
			(vias allowed)
			(pads allowed)
			(copperpour not_allowed)
			(footprints allowed)
		)
		(placement
			(enabled no)
			(sheetname "")
		)
		(fill yes
			(thermal_gap 0.5)
			(thermal_bridge_width 0.5)
			(island_removal_mode 0)
		)
		(polygon
			(pts
				(arc
					(start 269.155672 -234.716574)
					(mid 268.502892 -234.716574)
					(end 269.155672 -234.716574)
				)
			)
		)
	)
	(zone
		(layers "B.Cu" "In13.Cu" "In15.Cu")
		(hatch none 0.5)
		(connect_pads
			(clearance 0)
		)
		(min_thickness 0.25)
		(keepout
			(tracks not_allowed)
			(vias allowed)
			(pads allowed)
			(copperpour not_allowed)
			(footprints allowed)
		)
		(placement
			(enabled no)
			(sheetname "")
		)
		(fill yes
			(thermal_gap 0.5)
			(thermal_bridge_width 0.5)
			(island_removal_mode 0)
		)
		(polygon
			(pts
				(arc
					(start 344.870024 -248.806208)
					(mid 344.217244 -248.806208)
					(end 344.870024 -248.806208)
				)
			)
		)
	)
	(zone
		(layers "B.Cu" "In13.Cu" "In15.Cu")
		(hatch none 0.5)
		(connect_pads
			(clearance 0)
		)
		(min_thickness 0.25)
		(keepout
			(tracks not_allowed)
			(vias allowed)
			(pads allowed)
			(copperpour not_allowed)
			(footprints allowed)
		)
		(placement
			(enabled no)
			(sheetname "")
		)
		(fill yes
			(thermal_gap 0.5)
			(thermal_bridge_width 0.5)
			(island_removal_mode 0)
		)
		(polygon
			(pts
				(arc
					(start 373.064024 -235.783882)
					(mid 372.411244 -235.783882)
					(end 373.064024 -235.783882)
				)
			)
		)
	)
	(zone
		(layers "B.Cu" "In13.Cu" "In15.Cu")
		(hatch none 0.5)
		(connect_pads
			(clearance 0)
		)
		(min_thickness 0.25)
		(keepout
			(tracks not_allowed)
			(vias allowed)
			(pads allowed)
			(copperpour not_allowed)
			(footprints allowed)
		)
		(placement
			(enabled no)
			(sheetname "")
		)
		(fill yes
			(thermal_gap 0.5)
			(thermal_bridge_width 0.5)
			(island_removal_mode 0)
		)
		(polygon
			(pts
				(arc
					(start 105.967784 -280.778204)
					(mid 105.315004 -280.778204)
					(end 105.967784 -280.778204)
				)
			)
		)
	)
	(zone
		(layers "B.Cu" "In13.Cu" "In15.Cu")
		(hatch none 0.5)
		(connect_pads
			(clearance 0)
		)
		(min_thickness 0.25)
		(keepout
			(tracks not_allowed)
			(vias allowed)
			(pads allowed)
			(copperpour not_allowed)
			(footprints allowed)
		)
		(placement
			(enabled no)
			(sheetname "")
		)
		(fill yes
			(thermal_gap 0.5)
			(thermal_bridge_width 0.5)
			(island_removal_mode 0)
		)
		(polygon
			(pts
				(arc
					(start 207.397604 -304.416714)
					(mid 206.744824 -304.416714)
					(end 207.397604 -304.416714)
				)
			)
		)
	)
	(zone
		(layers "B.Cu" "In13.Cu" "In15.Cu")
		(hatch none 0.5)
		(connect_pads
			(clearance 0)
		)
		(min_thickness 0.25)
		(keepout
			(tracks not_allowed)
			(vias allowed)
			(pads allowed)
			(copperpour not_allowed)
			(footprints allowed)
		)
		(placement
			(enabled no)
			(sheetname "")
		)
		(fill yes
			(thermal_gap 0.5)
			(thermal_bridge_width 0.5)
			(island_removal_mode 0)
		)
		(polygon
			(pts
				(arc
					(start 21.215604 -298.466764)
					(mid 20.562824 -298.466764)
					(end 21.215604 -298.466764)
				)
			)
		)
	)
	(zone
		(layers "B.Cu" "In13.Cu" "In15.Cu")
		(hatch none 0.5)
		(connect_pads
			(clearance 0)
		)
		(min_thickness 0.25)
		(keepout
			(tracks not_allowed)
			(vias allowed)
			(pads allowed)
			(copperpour not_allowed)
			(footprints allowed)
		)
		(placement
			(enabled no)
			(sheetname "")
		)
		(fill yes
			(thermal_gap 0.5)
			(thermal_bridge_width 0.5)
			(island_removal_mode 0)
		)
		(polygon
			(pts
				(arc
					(start 373.064024 -242.294918)
					(mid 372.411244 -242.294918)
					(end 373.064024 -242.294918)
				)
			)
		)
	)
	(zone
		(layers "B.Cu" "In13.Cu" "In15.Cu")
		(hatch none 0.5)
		(connect_pads
			(clearance 0)
		)
		(min_thickness 0.25)
		(keepout
			(tracks not_allowed)
			(vias allowed)
			(pads allowed)
			(copperpour not_allowed)
			(footprints allowed)
		)
		(placement
			(enabled no)
			(sheetname "")
		)
		(fill yes
			(thermal_gap 0.5)
			(thermal_bridge_width 0.5)
			(island_removal_mode 0)
		)
		(polygon
			(pts
				(arc
					(start 207.397604 -302.716692)
					(mid 206.744824 -302.716692)
					(end 207.397604 -302.716692)
				)
			)
		)
	)
	(zone
		(layers "B.Cu" "In13.Cu" "In15.Cu")
		(hatch none 0.5)
		(connect_pads
			(clearance 0)
		)
		(min_thickness 0.25)
		(keepout
			(tracks not_allowed)
			(vias allowed)
			(pads allowed)
			(copperpour not_allowed)
			(footprints allowed)
		)
		(placement
			(enabled no)
			(sheetname "")
		)
		(fill yes
			(thermal_gap 0.5)
			(thermal_bridge_width 0.5)
			(island_removal_mode 0)
		)
		(polygon
			(pts
				(arc
					(start 129.352802 -244.73662)
					(mid 128.700022 -244.73662)
					(end 129.352802 -244.73662)
				)
			)
		)
	)
	(zone
		(layers "B.Cu" "In13.Cu" "In15.Cu")
		(hatch none 0.5)
		(connect_pads
			(clearance 0)
		)
		(min_thickness 0.25)
		(keepout
			(tracks not_allowed)
			(vias allowed)
			(pads allowed)
			(copperpour not_allowed)
			(footprints allowed)
		)
		(placement
			(enabled no)
			(sheetname "")
		)
		(fill yes
			(thermal_gap 0.5)
			(thermal_bridge_width 0.5)
			(island_removal_mode 0)
		)
		(polygon
			(pts
				(arc
					(start 100.328984 -277.522432)
					(mid 99.676204 -277.522432)
					(end 100.328984 -277.522432)
				)
			)
		)
	)
	(zone
		(layers "B.Cu" "In13.Cu" "In15.Cu")
		(hatch none 0.5)
		(connect_pads
			(clearance 0)
		)
		(min_thickness 0.25)
		(keepout
			(tracks not_allowed)
			(vias allowed)
			(pads allowed)
			(copperpour not_allowed)
			(footprints allowed)
		)
		(placement
			(enabled no)
			(sheetname "")
		)
		(fill yes
			(thermal_gap 0.5)
			(thermal_bridge_width 0.5)
			(island_removal_mode 0)
		)
		(polygon
			(pts
				(arc
					(start 373.174006 -276.708616)
					(mid 372.521226 -276.708616)
					(end 373.174006 -276.708616)
				)
			)
		)
	)
	(zone
		(layers "B.Cu" "In13.Cu" "In15.Cu")
		(hatch none 0.5)
		(connect_pads
			(clearance 0)
		)
		(min_thickness 0.25)
		(keepout
			(tracks not_allowed)
			(vias allowed)
			(pads allowed)
			(copperpour not_allowed)
			(footprints allowed)
		)
		(placement
			(enabled no)
			(sheetname "")
		)
		(fill yes
			(thermal_gap 0.5)
			(thermal_bridge_width 0.5)
			(island_removal_mode 0)
		)
		(polygon
			(pts
				(arc
					(start 346.749624 -245.55069)
					(mid 346.096844 -245.55069)
					(end 346.749624 -245.55069)
				)
			)
		)
	)
	(zone
		(layers "B.Cu" "In13.Cu" "In15.Cu")
		(hatch none 0.5)
		(connect_pads
			(clearance 0)
		)
		(min_thickness 0.25)
		(keepout
			(tracks not_allowed)
			(vias allowed)
			(pads allowed)
			(copperpour not_allowed)
			(footprints allowed)
		)
		(placement
			(enabled no)
			(sheetname "")
		)
		(fill yes
			(thermal_gap 0.5)
			(thermal_bridge_width 0.5)
			(island_removal_mode 0)
		)
		(polygon
			(pts
				(arc
					(start 455.337672 -272.11655)
					(mid 454.684892 -272.11655)
					(end 455.337672 -272.11655)
				)
			)
		)
	)
	(zone
		(layers "B.Cu" "In13.Cu" "In15.Cu")
		(hatch none 0.5)
		(connect_pads
			(clearance 0)
		)
		(min_thickness 0.25)
		(keepout
			(tracks not_allowed)
			(vias allowed)
			(pads allowed)
			(copperpour not_allowed)
			(footprints allowed)
		)
		(placement
			(enabled no)
			(sheetname "")
		)
		(fill yes
			(thermal_gap 0.5)
			(thermal_bridge_width 0.5)
			(island_removal_mode 0)
		)
		(polygon
			(pts
				(arc
					(start 21.215604 -261.916672)
					(mid 20.562824 -261.916672)
					(end 21.215604 -261.916672)
				)
			)
		)
	)
	(zone
		(layers "B.Cu" "In13.Cu" "In15.Cu")
		(hatch none 0.5)
		(connect_pads
			(clearance 0)
		)
		(min_thickness 0.25)
		(keepout
			(tracks not_allowed)
			(vias allowed)
			(pads allowed)
			(copperpour not_allowed)
			(footprints allowed)
		)
		(placement
			(enabled no)
			(sheetname "")
		)
		(fill yes
			(thermal_gap 0.5)
			(thermal_bridge_width 0.5)
			(island_removal_mode 0)
		)
		(polygon
			(pts
				(arc
					(start 455.337672 -234.716574)
					(mid 454.684892 -234.716574)
					(end 455.337672 -234.716574)
				)
			)
		)
	)
	(zone
		(layers "B.Cu" "In13.Cu" "In15.Cu")
		(hatch none 0.5)
		(connect_pads
			(clearance 0)
		)
		(min_thickness 0.25)
		(keepout
			(tracks not_allowed)
			(vias allowed)
			(pads allowed)
			(copperpour not_allowed)
			(footprints allowed)
		)
		(placement
			(enabled no)
			(sheetname "")
		)
		(fill yes
			(thermal_gap 0.5)
			(thermal_bridge_width 0.5)
			(island_removal_mode 0)
		)
		(polygon
			(pts
				(arc
					(start 451.237604 -233.86669)
					(mid 450.584824 -233.86669)
					(end 451.237604 -233.86669)
				)
			)
		)
	)
	(zone
		(layers "B.Cu" "In13.Cu" "In15.Cu")
		(hatch none 0.5)
		(connect_pads
			(clearance 0)
		)
		(min_thickness 0.25)
		(keepout
			(tracks not_allowed)
			(vias allowed)
			(pads allowed)
			(copperpour not_allowed)
			(footprints allowed)
		)
		(placement
			(enabled no)
			(sheetname "")
		)
		(fill yes
			(thermal_gap 0.5)
			(thermal_bridge_width 0.5)
			(island_removal_mode 0)
		)
		(polygon
			(pts
				(arc
					(start 393.876022 -6.713474)
					(mid 393.172442 -6.713474)
					(end 393.876022 -6.713474)
				)
			)
		)
	)
	(zone
		(layers "B.Cu" "In13.Cu" "In15.Cu")
		(hatch none 0.5)
		(connect_pads
			(clearance 0)
		)
		(min_thickness 0.25)
		(keepout
			(tracks not_allowed)
			(vias allowed)
			(pads allowed)
			(copperpour not_allowed)
			(footprints allowed)
		)
		(placement
			(enabled no)
			(sheetname "")
		)
		(fill yes
			(thermal_gap 0.5)
			(thermal_bridge_width 0.5)
			(island_removal_mode 0)
		)
		(polygon
			(pts
				(arc
					(start 125.123956 -240.667286)
					(mid 124.471176 -240.667286)
					(end 125.123956 -240.667286)
				)
			)
		)
	)
	(zone
		(layers "B.Cu" "In13.Cu" "In15.Cu")
		(hatch none 0.5)
		(connect_pads
			(clearance 0)
		)
		(min_thickness 0.25)
		(keepout
			(tracks not_allowed)
			(vias allowed)
			(pads allowed)
			(copperpour not_allowed)
			(footprints allowed)
		)
		(placement
			(enabled no)
			(sheetname "")
		)
		(fill yes
			(thermal_gap 0.5)
			(thermal_bridge_width 0.5)
			(island_removal_mode 0)
		)
		(polygon
			(pts
				(arc
					(start 265.055604 -239.81664)
					(mid 264.402824 -239.81664)
					(end 265.055604 -239.81664)
				)
			)
		)
	)
	(zone
		(layers "B.Cu" "In13.Cu" "In15.Cu")
		(hatch none 0.5)
		(connect_pads
			(clearance 0)
		)
		(min_thickness 0.25)
		(keepout
			(tracks not_allowed)
			(vias allowed)
			(pads allowed)
			(copperpour not_allowed)
			(footprints allowed)
		)
		(placement
			(enabled no)
			(sheetname "")
		)
		(fill yes
			(thermal_gap 0.5)
			(thermal_bridge_width 0.5)
			(island_removal_mode 0)
		)
		(polygon
			(pts
				(arc
					(start 373.174006 -253.919736)
					(mid 372.521226 -253.919736)
					(end 373.174006 -253.919736)
				)
			)
		)
	)
	(zone
		(layers "B.Cu" "In13.Cu" "In15.Cu")
		(hatch none 0.5)
		(connect_pads
			(clearance 0)
		)
		(min_thickness 0.25)
		(keepout
			(tracks not_allowed)
			(vias allowed)
			(pads allowed)
			(copperpour not_allowed)
			(footprints allowed)
		)
		(placement
			(enabled no)
			(sheetname "")
		)
		(fill yes
			(thermal_gap 0.5)
			(thermal_bridge_width 0.5)
			(island_removal_mode 0)
		)
		(polygon
			(pts
				(arc
					(start 347.329252 -267.755878)
					(mid 346.676472 -267.755878)
					(end 347.329252 -267.755878)
				)
			)
		)
	)
	(zone
		(layers "B.Cu" "In13.Cu" "In15.Cu")
		(hatch none 0.5)
		(connect_pads
			(clearance 0)
		)
		(min_thickness 0.25)
		(keepout
			(tracks not_allowed)
			(vias allowed)
			(pads allowed)
			(copperpour not_allowed)
			(footprints allowed)
		)
		(placement
			(enabled no)
			(sheetname "")
		)
		(fill yes
			(thermal_gap 0.5)
			(thermal_bridge_width 0.5)
			(island_removal_mode 0)
		)
		(polygon
			(pts
				(arc
					(start 346.749624 -240.667286)
					(mid 346.096844 -240.667286)
					(end 346.749624 -240.667286)
				)
			)
		)
	)
	(zone
		(layers "B.Cu" "In13.Cu" "In15.Cu")
		(hatch none 0.5)
		(connect_pads
			(clearance 0)
		)
		(min_thickness 0.25)
		(keepout
			(tracks not_allowed)
			(vias allowed)
			(pads allowed)
			(copperpour not_allowed)
			(footprints allowed)
		)
		(placement
			(enabled no)
			(sheetname "")
		)
		(fill yes
			(thermal_gap 0.5)
			(thermal_bridge_width 0.5)
			(island_removal_mode 0)
		)
		(polygon
			(pts
				(arc
					(start 17.115536 -230.466646)
					(mid 16.462756 -230.466646)
					(end 17.115536 -230.466646)
				)
			)
		)
	)
	(zone
		(layers "B.Cu" "In13.Cu" "In15.Cu")
		(hatch none 0.5)
		(connect_pads
			(clearance 0)
		)
		(min_thickness 0.25)
		(keepout
			(tracks not_allowed)
			(vias allowed)
			(pads allowed)
			(copperpour not_allowed)
			(footprints allowed)
		)
		(placement
			(enabled no)
			(sheetname "")
		)
		(fill yes
			(thermal_gap 0.5)
			(thermal_bridge_width 0.5)
			(island_removal_mode 0)
		)
		(polygon
			(pts
				(arc
					(start 102.208584 -279.150318)
					(mid 101.555804 -279.150318)
					(end 102.208584 -279.150318)
				)
			)
		)
	)
	(zone
		(layers "B.Cu" "In13.Cu" "In15.Cu")
		(hatch none 0.5)
		(connect_pads
			(clearance 0)
		)
		(min_thickness 0.25)
		(keepout
			(tracks not_allowed)
			(vias allowed)
			(pads allowed)
			(copperpour not_allowed)
			(footprints allowed)
		)
		(placement
			(enabled no)
			(sheetname "")
		)
		(fill yes
			(thermal_gap 0.5)
			(thermal_bridge_width 0.5)
			(island_removal_mode 0)
		)
		(polygon
			(pts
				(arc
					(start 373.53367 -246.364506)
					(mid 372.88089 -246.364506)
					(end 373.53367 -246.364506)
				)
			)
		)
	)
	(zone
		(layers "B.Cu" "In13.Cu" "In15.Cu")
		(hatch none 0.5)
		(connect_pads
			(clearance 0)
		)
		(min_thickness 0.25)
		(keepout
			(tracks not_allowed)
			(vias allowed)
			(pads allowed)
			(copperpour not_allowed)
			(footprints allowed)
		)
		(placement
			(enabled no)
			(sheetname "")
		)
		(fill yes
			(thermal_gap 0.5)
			(thermal_bridge_width 0.5)
			(island_removal_mode 0)
		)
		(polygon
			(pts
				(arc
					(start 101.268784 -277.522432)
					(mid 100.616004 -277.522432)
					(end 101.268784 -277.522432)
				)
			)
		)
	)
	(zone
		(layers "B.Cu" "In13.Cu" "In15.Cu")
		(hatch none 0.5)
		(connect_pads
			(clearance 0)
		)
		(min_thickness 0.25)
		(keepout
			(tracks not_allowed)
			(vias allowed)
			(pads allowed)
			(copperpour not_allowed)
			(footprints allowed)
		)
		(placement
			(enabled no)
			(sheetname "")
		)
		(fill yes
			(thermal_gap 0.5)
			(thermal_bridge_width 0.5)
			(island_removal_mode 0)
		)
		(polygon
			(pts
				(arc
					(start 374.113806 -255.547622)
					(mid 373.461026 -255.547622)
					(end 374.113806 -255.547622)
				)
			)
		)
	)
	(zone
		(layers "B.Cu" "In13.Cu" "In15.Cu")
		(hatch none 0.5)
		(connect_pads
			(clearance 0)
		)
		(min_thickness 0.25)
		(keepout
			(tracks not_allowed)
			(vias allowed)
			(pads allowed)
			(copperpour not_allowed)
			(footprints allowed)
		)
		(placement
			(enabled no)
			(sheetname "")
		)
		(fill yes
			(thermal_gap 0.5)
			(thermal_bridge_width 0.5)
			(island_removal_mode 0)
		)
		(polygon
			(pts
				(arc
					(start 9.571736 -267.866622)
					(mid 8.918956 -267.866622)
					(end 9.571736 -267.866622)
				)
			)
		)
	)
	(zone
		(layers "B.Cu" "In13.Cu" "In15.Cu")
		(hatch none 0.5)
		(connect_pads
			(clearance 0)
		)
		(min_thickness 0.25)
		(keepout
			(tracks not_allowed)
			(vias allowed)
			(pads allowed)
			(copperpour not_allowed)
			(footprints allowed)
		)
		(placement
			(enabled no)
			(sheetname "")
		)
		(fill yes
			(thermal_gap 0.5)
			(thermal_bridge_width 0.5)
			(island_removal_mode 0)
		)
		(polygon
			(pts
				(arc
					(start 126.533402 -244.73662)
					(mid 125.880622 -244.73662)
					(end 126.533402 -244.73662)
				)
			)
		)
	)
	(zone
		(layers "B.Cu" "In13.Cu" "In15.Cu")
		(hatch none 0.5)
		(connect_pads
			(clearance 0)
		)
		(min_thickness 0.25)
		(keepout
			(tracks not_allowed)
			(vias allowed)
			(pads allowed)
			(copperpour not_allowed)
			(footprints allowed)
		)
		(placement
			(enabled no)
			(sheetname "")
		)
		(fill yes
			(thermal_gap 0.5)
			(thermal_bridge_width 0.5)
			(island_removal_mode 0)
		)
		(polygon
			(pts
				(arc
					(start 203.297536 -247.466612)
					(mid 202.644756 -247.466612)
					(end 203.297536 -247.466612)
				)
			)
		)
	)
	(zone
		(layers "B.Cu" "In13.Cu" "In15.Cu")
		(hatch none 0.5)
		(connect_pads
			(clearance 0)
		)
		(min_thickness 0.25)
		(keepout
			(tracks not_allowed)
			(vias allowed)
			(pads allowed)
			(copperpour not_allowed)
			(footprints allowed)
		)
		(placement
			(enabled no)
			(sheetname "")
		)
		(fill yes
			(thermal_gap 0.5)
			(thermal_bridge_width 0.5)
			(island_removal_mode 0)
		)
		(polygon
			(pts
				(arc
					(start 21.215604 -203.266802)
					(mid 20.562824 -203.266802)
					(end 21.215604 -203.266802)
				)
			)
		)
	)
	(zone
		(layers "B.Cu" "In13.Cu" "In15.Cu")
		(hatch none 0.5)
		(connect_pads
			(clearance 0)
		)
		(min_thickness 0.25)
		(keepout
			(tracks not_allowed)
			(vias allowed)
			(pads allowed)
			(copperpour not_allowed)
			(footprints allowed)
		)
		(placement
			(enabled no)
			(sheetname "")
		)
		(fill yes
			(thermal_gap 0.5)
			(thermal_bridge_width 0.5)
			(island_removal_mode 0)
		)
		(polygon
			(pts
				(arc
					(start 17.115536 -202.416664)
					(mid 16.462756 -202.416664)
					(end 17.115536 -202.416664)
				)
			)
		)
	)
	(zone
		(layers "B.Cu" "In13.Cu" "In15.Cu")
		(hatch none 0.5)
		(connect_pads
			(clearance 0)
		)
		(min_thickness 0.25)
		(keepout
			(tracks not_allowed)
			(vias allowed)
			(pads allowed)
			(copperpour not_allowed)
			(footprints allowed)
		)
		(placement
			(enabled no)
			(sheetname "")
		)
		(fill yes
			(thermal_gap 0.5)
			(thermal_bridge_width 0.5)
			(island_removal_mode 0)
		)
		(polygon
			(pts
				(arc
					(start 451.237604 -277.216616)
					(mid 450.584824 -277.216616)
					(end 451.237604 -277.216616)
				)
			)
		)
	)
	(zone
		(layers "B.Cu" "In13.Cu" "In15.Cu")
		(hatch none 0.5)
		(connect_pads
			(clearance 0)
		)
		(min_thickness 0.25)
		(keepout
			(tracks not_allowed)
			(vias allowed)
			(pads allowed)
			(copperpour not_allowed)
			(footprints allowed)
		)
		(placement
			(enabled no)
			(sheetname "")
		)
		(fill yes
			(thermal_gap 0.5)
			(thermal_bridge_width 0.5)
			(island_removal_mode 0)
		)
		(polygon
			(pts
				(arc
					(start 324.921118 -410.030168)
					(mid 324.217538 -410.030168)
					(end 324.921118 -410.030168)
				)
			)
		)
	)
	(zone
		(layers "B.Cu" "In13.Cu" "In15.Cu")
		(hatch none 0.5)
		(connect_pads
			(clearance 0)
		)
		(min_thickness 0.25)
		(keepout
			(tracks not_allowed)
			(vias allowed)
			(pads allowed)
			(copperpour not_allowed)
			(footprints allowed)
		)
		(placement
			(enabled no)
			(sheetname "")
		)
		(fill yes
			(thermal_gap 0.5)
			(thermal_bridge_width 0.5)
			(island_removal_mode 0)
		)
		(polygon
			(pts
				(arc
					(start 265.055604 -216.866724)
					(mid 264.402824 -216.866724)
					(end 265.055604 -216.866724)
				)
			)
		)
	)
	(zone
		(layers "B.Cu" "In13.Cu" "In15.Cu")
		(hatch none 0.5)
		(connect_pads
			(clearance 0)
		)
		(min_thickness 0.25)
		(keepout
			(tracks not_allowed)
			(vias allowed)
			(pads allowed)
			(copperpour not_allowed)
			(footprints allowed)
		)
		(placement
			(enabled no)
			(sheetname "")
		)
		(fill yes
			(thermal_gap 0.5)
			(thermal_bridge_width 0.5)
			(island_removal_mode 0)
		)
		(polygon
			(pts
				(arc
					(start 105.027984 -280.778204)
					(mid 104.375204 -280.778204)
					(end 105.027984 -280.778204)
				)
			)
		)
	)
	(zone
		(layers "B.Cu" "In13.Cu" "In15.Cu")
		(hatch none 0.5)
		(connect_pads
			(clearance 0)
		)
		(min_thickness 0.25)
		(keepout
			(tracks not_allowed)
			(vias allowed)
			(pads allowed)
			(copperpour not_allowed)
			(footprints allowed)
		)
		(placement
			(enabled no)
			(sheetname "")
		)
		(fill yes
			(thermal_gap 0.5)
			(thermal_bridge_width 0.5)
			(island_removal_mode 0)
		)
		(polygon
			(pts
				(arc
					(start 360.37647 -221.94774)
					(mid 359.72369 -221.94774)
					(end 360.37647 -221.94774)
				)
			)
		)
	)
	(zone
		(layers "B.Cu" "In13.Cu" "In15.Cu")
		(hatch none 0.5)
		(connect_pads
			(clearance 0)
		)
		(min_thickness 0.25)
		(keepout
			(tracks not_allowed)
			(vias allowed)
			(pads allowed)
			(copperpour not_allowed)
			(footprints allowed)
		)
		(placement
			(enabled no)
			(sheetname "")
		)
		(fill yes
			(thermal_gap 0.5)
			(thermal_bridge_width 0.5)
			(island_removal_mode 0)
		)
		(polygon
			(pts
				(arc
					(start 455.337672 -265.316716)
					(mid 454.684892 -265.316716)
					(end 455.337672 -265.316716)
				)
			)
		)
	)
	(zone
		(layers "B.Cu" "In13.Cu" "In15.Cu")
		(hatch none 0.5)
		(connect_pads
			(clearance 0)
		)
		(min_thickness 0.25)
		(keepout
			(tracks not_allowed)
			(vias allowed)
			(pads allowed)
			(copperpour not_allowed)
			(footprints allowed)
		)
		(placement
			(enabled no)
			(sheetname "")
		)
		(fill yes
			(thermal_gap 0.5)
			(thermal_bridge_width 0.5)
			(island_removal_mode 0)
		)
		(polygon
			(pts
				(arc
					(start 269.155672 -261.916672)
					(mid 268.502892 -261.916672)
					(end 269.155672 -261.916672)
				)
			)
		)
	)
	(zone
		(layers "B.Cu" "In13.Cu" "In15.Cu")
		(hatch none 0.5)
		(connect_pads
			(clearance 0)
		)
		(min_thickness 0.25)
		(keepout
			(tracks not_allowed)
			(vias allowed)
			(pads allowed)
			(copperpour not_allowed)
			(footprints allowed)
		)
		(placement
			(enabled no)
			(sheetname "")
		)
		(fill yes
			(thermal_gap 0.5)
			(thermal_bridge_width 0.5)
			(island_removal_mode 0)
		)
		(polygon
			(pts
				(arc
					(start 126.154942 -426.089826)
					(mid 125.34519 -426.089826)
					(end 126.154942 -426.089826)
				)
			)
		)
	)
	(zone
		(layers "B.Cu" "In13.Cu" "In15.Cu")
		(hatch none 0.5)
		(connect_pads
			(clearance 0)
		)
		(min_thickness 0.25)
		(keepout
			(tracks not_allowed)
			(vias allowed)
			(pads allowed)
			(copperpour not_allowed)
			(footprints allowed)
		)
		(placement
			(enabled no)
			(sheetname "")
		)
		(fill yes
			(thermal_gap 0.5)
			(thermal_bridge_width 0.5)
			(island_removal_mode 0)
		)
		(polygon
			(pts
				(arc
					(start 325.054976 -430.689766)
					(mid 324.245224 -430.689766)
					(end 325.054976 -430.689766)
				)
			)
		)
	)
	(zone
		(layers "B.Cu" "In13.Cu" "In15.Cu")
		(hatch none 0.5)
		(connect_pads
			(clearance 0)
		)
		(min_thickness 0.25)
		(keepout
			(tracks not_allowed)
			(vias allowed)
			(pads allowed)
			(copperpour not_allowed)
			(footprints allowed)
		)
		(placement
			(enabled no)
			(sheetname "")
		)
		(fill yes
			(thermal_gap 0.5)
			(thermal_bridge_width 0.5)
			(island_removal_mode 0)
		)
		(polygon
			(pts
				(arc
					(start 145.876264 -403.883876)
					(mid 145.172684 -403.883876)
					(end 145.876264 -403.883876)
				)
			)
		)
	)
	(zone
		(layers "B.Cu" "In13.Cu" "In15.Cu")
		(hatch none 0.5)
		(connect_pads
			(clearance 0)
		)
		(min_thickness 0.25)
		(keepout
			(tracks not_allowed)
			(vias allowed)
			(pads allowed)
			(copperpour not_allowed)
			(footprints allowed)
		)
		(placement
			(enabled no)
			(sheetname "")
		)
		(fill yes
			(thermal_gap 0.5)
			(thermal_bridge_width 0.5)
			(island_removal_mode 0)
		)
		(polygon
			(pts
				(arc
					(start 374.003824 -242.294918)
					(mid 373.351044 -242.294918)
					(end 374.003824 -242.294918)
				)
			)
		)
	)
	(zone
		(layers "B.Cu" "In13.Cu" "In15.Cu")
		(hatch none 0.5)
		(connect_pads
			(clearance 0)
		)
		(min_thickness 0.25)
		(keepout
			(tracks not_allowed)
			(vias allowed)
			(pads allowed)
			(copperpour not_allowed)
			(footprints allowed)
		)
		(placement
			(enabled no)
			(sheetname "")
		)
		(fill yes
			(thermal_gap 0.5)
			(thermal_bridge_width 0.5)
			(island_removal_mode 0)
		)
		(polygon
			(pts
				(arc
					(start 17.115536 -293.366698)
					(mid 16.462756 -293.366698)
					(end 17.115536 -293.366698)
				)
			)
		)
	)
	(zone
		(layers "B.Cu" "In13.Cu" "In15.Cu")
		(hatch none 0.5)
		(connect_pads
			(clearance 0)
		)
		(min_thickness 0.25)
		(keepout
			(tracks not_allowed)
			(vias allowed)
			(pads allowed)
			(copperpour not_allowed)
			(footprints allowed)
		)
		(placement
			(enabled no)
			(sheetname "")
		)
		(fill yes
			(thermal_gap 0.5)
			(thermal_bridge_width 0.5)
			(island_removal_mode 0)
		)
		(polygon
			(pts
				(arc
					(start 100.689156 -245.55069)
					(mid 100.036376 -245.55069)
					(end 100.689156 -245.55069)
				)
			)
		)
	)
	(zone
		(layers "B.Cu" "In13.Cu" "In15.Cu")
		(hatch none 0.5)
		(connect_pads
			(clearance 0)
		)
		(min_thickness 0.25)
		(keepout
			(tracks not_allowed)
			(vias allowed)
			(pads allowed)
			(copperpour not_allowed)
			(footprints allowed)
		)
		(placement
			(enabled no)
			(sheetname "")
		)
		(fill yes
			(thermal_gap 0.5)
			(thermal_bridge_width 0.5)
			(island_removal_mode 0)
		)
		(polygon
			(pts
				(arc
					(start 110.087156 -221.133924)
					(mid 109.434376 -221.133924)
					(end 110.087156 -221.133924)
				)
			)
		)
	)
	(zone
		(layers "B.Cu" "In13.Cu" "In15.Cu")
		(hatch none 0.5)
		(connect_pads
			(clearance 0)
		)
		(min_thickness 0.25)
		(keepout
			(tracks not_allowed)
			(vias allowed)
			(pads allowed)
			(copperpour not_allowed)
			(footprints allowed)
		)
		(placement
			(enabled no)
			(sheetname "")
		)
		(fill yes
			(thermal_gap 0.5)
			(thermal_bridge_width 0.5)
			(island_removal_mode 0)
		)
		(polygon
			(pts
				(arc
					(start 21.215604 -300.166786)
					(mid 20.562824 -300.166786)
					(end 21.215604 -300.166786)
				)
			)
		)
	)
	(zone
		(layers "B.Cu" "In13.Cu" "In15.Cu")
		(hatch none 0.5)
		(connect_pads
			(clearance 0)
		)
		(min_thickness 0.25)
		(keepout
			(tracks not_allowed)
			(vias allowed)
			(pads allowed)
			(copperpour not_allowed)
			(footprints allowed)
		)
		(placement
			(enabled no)
			(sheetname "")
		)
		(fill yes
			(thermal_gap 0.5)
			(thermal_bridge_width 0.5)
			(island_removal_mode 0)
		)
		(polygon
			(pts
				(arc
					(start 374.83796 -403.883876)
					(mid 374.13438 -403.883876)
					(end 374.83796 -403.883876)
				)
			)
		)
	)
	(zone
		(layers "B.Cu" "In13.Cu" "In15.Cu")
		(hatch none 0.5)
		(connect_pads
			(clearance 0)
		)
		(min_thickness 0.25)
		(keepout
			(tracks not_allowed)
			(vias allowed)
			(pads allowed)
			(copperpour not_allowed)
			(footprints allowed)
		)
		(placement
			(enabled no)
			(sheetname "")
		)
		(fill yes
			(thermal_gap 0.5)
			(thermal_bridge_width 0.5)
			(island_removal_mode 0)
		)
		(polygon
			(pts
				(arc
					(start 455.261472 -267.016738)
					(mid 454.608692 -267.016738)
					(end 455.261472 -267.016738)
				)
			)
		)
	)
	(zone
		(layers "B.Cu" "In13.Cu" "In15.Cu")
		(hatch none 0.5)
		(connect_pads
			(clearance 0)
		)
		(min_thickness 0.25)
		(keepout
			(tracks not_allowed)
			(vias allowed)
			(pads allowed)
			(copperpour not_allowed)
			(footprints allowed)
		)
		(placement
			(enabled no)
			(sheetname "")
		)
		(fill yes
			(thermal_gap 0.5)
			(thermal_bridge_width 0.5)
			(island_removal_mode 0)
		)
		(polygon
			(pts
				(arc
					(start 371.294406 -265.314176)
					(mid 370.641626 -265.314176)
					(end 371.294406 -265.314176)
				)
			)
		)
	)
	(zone
		(layers "B.Cu" "In13.Cu" "In15.Cu")
		(hatch none 0.5)
		(connect_pads
			(clearance 0)
		)
		(min_thickness 0.25)
		(keepout
			(tracks not_allowed)
			(vias allowed)
			(pads allowed)
			(copperpour not_allowed)
			(footprints allowed)
		)
		(placement
			(enabled no)
			(sheetname "")
		)
		(fill yes
			(thermal_gap 0.5)
			(thermal_bridge_width 0.5)
			(island_removal_mode 0)
		)
		(polygon
			(pts
				(arc
					(start 98.809556 -239.0394)
					(mid 98.156776 -239.0394)
					(end 98.809556 -239.0394)
				)
			)
		)
	)
	(zone
		(layers "B.Cu" "In13.Cu" "In15.Cu")
		(hatch none 0.5)
		(connect_pads
			(clearance 0)
		)
		(min_thickness 0.25)
		(keepout
			(tracks not_allowed)
			(vias allowed)
			(pads allowed)
			(copperpour not_allowed)
			(footprints allowed)
		)
		(placement
			(enabled no)
			(sheetname "")
		)
		(fill yes
			(thermal_gap 0.5)
			(thermal_bridge_width 0.5)
			(island_removal_mode 0)
		)
		(polygon
			(pts
				(arc
					(start 124.294138 -275.08073)
					(mid 123.641358 -275.08073)
					(end 124.294138 -275.08073)
				)
			)
		)
	)
	(zone
		(layers "B.Cu" "In13.Cu" "In15.Cu")
		(hatch none 0.5)
		(connect_pads
			(clearance 0)
		)
		(min_thickness 0.25)
		(keepout
			(tracks not_allowed)
			(vias allowed)
			(pads allowed)
			(copperpour not_allowed)
			(footprints allowed)
		)
		(placement
			(enabled no)
			(sheetname "")
		)
		(fill yes
			(thermal_gap 0.5)
			(thermal_bridge_width 0.5)
			(island_removal_mode 0)
		)
		(polygon
			(pts
				(arc
					(start 458.781404 -267.866622)
					(mid 458.128624 -267.866622)
					(end 458.781404 -267.866622)
				)
			)
		)
	)
	(zone
		(layers "B.Cu" "In13.Cu" "In15.Cu")
		(hatch none 0.5)
		(connect_pads
			(clearance 0)
		)
		(min_thickness 0.25)
		(keepout
			(tracks not_allowed)
			(vias allowed)
			(pads allowed)
			(copperpour not_allowed)
			(footprints allowed)
		)
		(placement
			(enabled no)
			(sheetname "")
		)
		(fill yes
			(thermal_gap 0.5)
			(thermal_bridge_width 0.5)
			(island_removal_mode 0)
		)
		(polygon
			(pts
				(arc
					(start 372.124224 -247.178322)
					(mid 371.471444 -247.178322)
					(end 372.124224 -247.178322)
				)
			)
		)
	)
	(zone
		(layers "B.Cu" "In13.Cu" "In15.Cu")
		(hatch none 0.5)
		(connect_pads
			(clearance 0)
		)
		(min_thickness 0.25)
		(keepout
			(tracks not_allowed)
			(vias allowed)
			(pads allowed)
			(copperpour not_allowed)
			(footprints allowed)
		)
		(placement
			(enabled no)
			(sheetname "")
		)
		(fill yes
			(thermal_gap 0.5)
			(thermal_bridge_width 0.5)
			(island_removal_mode 0)
		)
		(polygon
			(pts
				(arc
					(start 21.215604 -250.016772)
					(mid 20.562824 -250.016772)
					(end 21.215604 -250.016772)
				)
			)
		)
	)
	(zone
		(layers "B.Cu" "In13.Cu" "In15.Cu")
		(hatch none 0.5)
		(connect_pads
			(clearance 0)
		)
		(min_thickness 0.25)
		(keepout
			(tracks not_allowed)
			(vias allowed)
			(pads allowed)
			(copperpour not_allowed)
			(footprints allowed)
		)
		(placement
			(enabled no)
			(sheetname "")
		)
		(fill yes
			(thermal_gap 0.5)
			(thermal_bridge_width 0.5)
			(island_removal_mode 0)
		)
		(polygon
			(pts
				(arc
					(start 17.115536 -301.01667)
					(mid 16.462756 -301.01667)
					(end 17.115536 -301.01667)
				)
			)
		)
	)
	(zone
		(layers "B.Cu" "In13.Cu" "In15.Cu")
		(hatch none 0.5)
		(connect_pads
			(clearance 0)
		)
		(min_thickness 0.25)
		(keepout
			(tracks not_allowed)
			(vias allowed)
			(pads allowed)
			(copperpour not_allowed)
			(footprints allowed)
		)
		(placement
			(enabled no)
			(sheetname "")
		)
		(fill yes
			(thermal_gap 0.5)
			(thermal_bridge_width 0.5)
			(island_removal_mode 0)
		)
		(polygon
			(pts
				(arc
					(start 84.05495 -430.889918)
					(mid 83.245198 -430.889918)
					(end 84.05495 -430.889918)
				)
			)
		)
	)
	(zone
		(layers "B.Cu" "In13.Cu" "In15.Cu")
		(hatch none 0.5)
		(connect_pads
			(clearance 0)
		)
		(min_thickness 0.25)
		(keepout
			(tracks not_allowed)
			(vias allowed)
			(pads allowed)
			(copperpour not_allowed)
			(footprints allowed)
		)
		(placement
			(enabled no)
			(sheetname "")
		)
		(fill yes
			(thermal_gap 0.5)
			(thermal_bridge_width 0.5)
			(island_removal_mode 0)
		)
		(polygon
			(pts
				(arc
					(start 317.054992 -430.689766)
					(mid 316.24524 -430.689766)
					(end 317.054992 -430.689766)
				)
			)
		)
	)
	(zone
		(layers "B.Cu" "In13.Cu" "In15.Cu")
		(hatch none 0.5)
		(connect_pads
			(clearance 0)
		)
		(min_thickness 0.25)
		(keepout
			(tracks not_allowed)
			(vias allowed)
			(pads allowed)
			(copperpour not_allowed)
			(footprints allowed)
		)
		(placement
			(enabled no)
			(sheetname "")
		)
		(fill yes
			(thermal_gap 0.5)
			(thermal_bridge_width 0.5)
			(island_removal_mode 0)
		)
		(polygon
			(pts
				(arc
					(start 345.33967 -247.992138)
					(mid 344.68689 -247.992138)
					(end 345.33967 -247.992138)
				)
			)
		)
	)
	(zone
		(layers "B.Cu" "In13.Cu" "In15.Cu")
		(hatch none 0.5)
		(connect_pads
			(clearance 0)
		)
		(min_thickness 0.25)
		(keepout
			(tracks not_allowed)
			(vias allowed)
			(pads allowed)
			(copperpour not_allowed)
			(footprints allowed)
		)
		(placement
			(enabled no)
			(sheetname "")
		)
		(fill yes
			(thermal_gap 0.5)
			(thermal_bridge_width 0.5)
			(island_removal_mode 0)
		)
		(polygon
			(pts
				(arc
					(start 126.063756 -242.294918)
					(mid 125.410976 -242.294918)
					(end 126.063756 -242.294918)
				)
			)
		)
	)
	(zone
		(layers "B.Cu" "In13.Cu" "In15.Cu")
		(hatch none 0.5)
		(connect_pads
			(clearance 0)
		)
		(min_thickness 0.25)
		(keepout
			(tracks not_allowed)
			(vias allowed)
			(pads allowed)
			(copperpour not_allowed)
			(footprints allowed)
		)
		(placement
			(enabled no)
			(sheetname "")
		)
		(fill yes
			(thermal_gap 0.5)
			(thermal_bridge_width 0.5)
			(island_removal_mode 0)
		)
		(polygon
			(pts
				(arc
					(start 203.297536 -216.866724)
					(mid 202.644756 -216.866724)
					(end 203.297536 -216.866724)
				)
			)
		)
	)
	(zone
		(layers "B.Cu" "In13.Cu" "In15.Cu")
		(hatch none 0.5)
		(connect_pads
			(clearance 0)
		)
		(min_thickness 0.25)
		(keepout
			(tracks not_allowed)
			(vias allowed)
			(pads allowed)
			(copperpour not_allowed)
			(footprints allowed)
		)
		(placement
			(enabled no)
			(sheetname "")
		)
		(fill yes
			(thermal_gap 0.5)
			(thermal_bridge_width 0.5)
			(island_removal_mode 0)
		)
		(polygon
			(pts
				(arc
					(start 426.800772 -4.95173)
					(mid 426.097192 -4.95173)
					(end 426.800772 -4.95173)
				)
			)
		)
	)
	(zone
		(layers "B.Cu" "In13.Cu" "In15.Cu")
		(hatch none 0.5)
		(connect_pads
			(clearance 0)
		)
		(min_thickness 0.25)
		(keepout
			(tracks not_allowed)
			(vias allowed)
			(pads allowed)
			(copperpour not_allowed)
			(footprints allowed)
		)
		(placement
			(enabled no)
			(sheetname "")
		)
		(fill yes
			(thermal_gap 0.5)
			(thermal_bridge_width 0.5)
			(island_removal_mode 0)
		)
		(polygon
			(pts
				(arc
					(start 373.174006 -268.569694)
					(mid 372.521226 -268.569694)
					(end 373.174006 -268.569694)
				)
			)
		)
	)
	(zone
		(layers "B.Cu" "In13.Cu" "In15.Cu")
		(hatch none 0.5)
		(connect_pads
			(clearance 0)
		)
		(min_thickness 0.25)
		(keepout
			(tracks not_allowed)
			(vias allowed)
			(pads allowed)
			(copperpour not_allowed)
			(footprints allowed)
		)
		(placement
			(enabled no)
			(sheetname "")
		)
		(fill yes
			(thermal_gap 0.5)
			(thermal_bridge_width 0.5)
			(island_removal_mode 0)
		)
		(polygon
			(pts
				(arc
					(start 207.397604 -214.316564)
					(mid 206.744824 -214.316564)
					(end 207.397604 -214.316564)
				)
			)
		)
	)
	(zone
		(layers "B.Cu" "In13.Cu" "In15.Cu")
		(hatch none 0.5)
		(connect_pads
			(clearance 0)
		)
		(min_thickness 0.25)
		(keepout
			(tracks not_allowed)
			(vias allowed)
			(pads allowed)
			(copperpour not_allowed)
			(footprints allowed)
		)
		(placement
			(enabled no)
			(sheetname "")
		)
		(fill yes
			(thermal_gap 0.5)
			(thermal_bridge_width 0.5)
			(island_removal_mode 0)
		)
		(polygon
			(pts
				(arc
					(start 391.01776 -403.883876)
					(mid 390.31418 -403.883876)
					(end 391.01776 -403.883876)
				)
			)
		)
	)
	(zone
		(layers "B.Cu" "In13.Cu" "In15.Cu")
		(hatch none 0.5)
		(connect_pads
			(clearance 0)
		)
		(min_thickness 0.25)
		(keepout
			(tracks not_allowed)
			(vias allowed)
			(pads allowed)
			(copperpour not_allowed)
			(footprints allowed)
		)
		(placement
			(enabled no)
			(sheetname "")
		)
		(fill yes
			(thermal_gap 0.5)
			(thermal_bridge_width 0.5)
			(island_removal_mode 0)
		)
		(polygon
			(pts
				(arc
					(start 358.967024 -221.133924)
					(mid 358.314244 -221.133924)
					(end 358.967024 -221.133924)
				)
			)
		)
	)
	(zone
		(layers "B.Cu" "In13.Cu" "In15.Cu")
		(hatch none 0.5)
		(connect_pads
			(clearance 0)
		)
		(min_thickness 0.25)
		(keepout
			(tracks not_allowed)
			(vias allowed)
			(pads allowed)
			(copperpour not_allowed)
			(footprints allowed)
		)
		(placement
			(enabled no)
			(sheetname "")
		)
		(fill yes
			(thermal_gap 0.5)
			(thermal_bridge_width 0.5)
			(island_removal_mode 0)
		)
		(polygon
			(pts
				(arc
					(start 17.115536 -249.166634)
					(mid 16.462756 -249.166634)
					(end 17.115536 -249.166634)
				)
			)
		)
	)
	(zone
		(layers "B.Cu" "In13.Cu" "In15.Cu")
		(hatch none 0.5)
		(connect_pads
			(clearance 0)
		)
		(min_thickness 0.25)
		(keepout
			(tracks not_allowed)
			(vias allowed)
			(pads allowed)
			(copperpour not_allowed)
			(footprints allowed)
		)
		(placement
			(enabled no)
			(sheetname "")
		)
		(fill yes
			(thermal_gap 0.5)
			(thermal_bridge_width 0.5)
			(island_removal_mode 0)
		)
		(polygon
			(pts
				(arc
					(start 451.237604 -274.66671)
					(mid 450.584824 -274.66671)
					(end 451.237604 -274.66671)
				)
			)
		)
	)
	(zone
		(layers "B.Cu" "In13.Cu" "In15.Cu")
		(hatch none 0.5)
		(connect_pads
			(clearance 0)
		)
		(min_thickness 0.25)
		(keepout
			(tracks not_allowed)
			(vias allowed)
			(pads allowed)
			(copperpour not_allowed)
			(footprints allowed)
		)
		(placement
			(enabled no)
			(sheetname "")
		)
		(fill yes
			(thermal_gap 0.5)
			(thermal_bridge_width 0.5)
			(island_removal_mode 0)
		)
		(polygon
			(pts
				(arc
					(start 455.337672 -229.616762)
					(mid 454.684892 -229.616762)
					(end 455.337672 -229.616762)
				)
			)
		)
	)
	(zone
		(layers "B.Cu" "In13.Cu" "In15.Cu")
		(hatch none 0.5)
		(connect_pads
			(clearance 0)
		)
		(min_thickness 0.25)
		(keepout
			(tracks not_allowed)
			(vias allowed)
			(pads allowed)
			(copperpour not_allowed)
			(footprints allowed)
		)
		(placement
			(enabled no)
			(sheetname "")
		)
		(fill yes
			(thermal_gap 0.5)
			(thermal_bridge_width 0.5)
			(island_removal_mode 0)
		)
		(polygon
			(pts
				(arc
					(start 269.155672 -201.56678)
					(mid 268.502892 -201.56678)
					(end 269.155672 -201.56678)
				)
			)
		)
	)
	(zone
		(layers "B.Cu" "In13.Cu" "In15.Cu")
		(hatch none 0.5)
		(connect_pads
			(clearance 0)
		)
		(min_thickness 0.25)
		(keepout
			(tracks not_allowed)
			(vias allowed)
			(pads allowed)
			(copperpour not_allowed)
			(footprints allowed)
		)
		(placement
			(enabled no)
			(sheetname "")
		)
		(fill yes
			(thermal_gap 0.5)
			(thermal_bridge_width 0.5)
			(island_removal_mode 0)
		)
		(polygon
			(pts
				(arc
					(start 203.297536 -303.566576)
					(mid 202.644756 -303.566576)
					(end 203.297536 -303.566576)
				)
			)
		)
	)
	(zone
		(layers "B.Cu" "In13.Cu" "In15.Cu")
		(hatch none 0.5)
		(connect_pads
			(clearance 0)
		)
		(min_thickness 0.25)
		(keepout
			(tracks not_allowed)
			(vias allowed)
			(pads allowed)
			(copperpour not_allowed)
			(footprints allowed)
		)
		(placement
			(enabled no)
			(sheetname "")
		)
		(fill yes
			(thermal_gap 0.5)
			(thermal_bridge_width 0.5)
			(island_removal_mode 0)
		)
		(polygon
			(pts
				(arc
					(start 125.703584 -259.616956)
					(mid 125.050804 -259.616956)
					(end 125.703584 -259.616956)
				)
			)
		)
	)
	(zone
		(layers "B.Cu" "In13.Cu" "In15.Cu")
		(hatch none 0.5)
		(connect_pads
			(clearance 0)
		)
		(min_thickness 0.25)
		(keepout
			(tracks not_allowed)
			(vias allowed)
			(pads allowed)
			(copperpour not_allowed)
			(footprints allowed)
		)
		(placement
			(enabled no)
			(sheetname "")
		)
		(fill yes
			(thermal_gap 0.5)
			(thermal_bridge_width 0.5)
			(island_removal_mode 0)
		)
		(polygon
			(pts
				(arc
					(start 17.115536 -272.966688)
					(mid 16.462756 -272.966688)
					(end 17.115536 -272.966688)
				)
			)
		)
	)
	(zone
		(layers "B.Cu" "In13.Cu" "In15.Cu")
		(hatch none 0.5)
		(connect_pads
			(clearance 0)
		)
		(min_thickness 0.25)
		(keepout
			(tracks not_allowed)
			(vias allowed)
			(pads allowed)
			(copperpour not_allowed)
			(footprints allowed)
		)
		(placement
			(enabled no)
			(sheetname "")
		)
		(fill yes
			(thermal_gap 0.5)
			(thermal_bridge_width 0.5)
			(island_removal_mode 0)
		)
		(polygon
			(pts
				(arc
					(start 203.297536 -218.566746)
					(mid 202.644756 -218.566746)
					(end 203.297536 -218.566746)
				)
			)
		)
	)
	(zone
		(layers "B.Cu" "In13.Cu" "In15.Cu")
		(hatch none 0.5)
		(connect_pads
			(clearance 0)
		)
		(min_thickness 0.25)
		(keepout
			(tracks not_allowed)
			(vias allowed)
			(pads allowed)
			(copperpour not_allowed)
			(footprints allowed)
		)
		(placement
			(enabled no)
			(sheetname "")
		)
		(fill yes
			(thermal_gap 0.5)
			(thermal_bridge_width 0.5)
			(island_removal_mode 0)
		)
		(polygon
			(pts
				(arc
					(start 152.002744 -403.883876)
					(mid 151.299164 -403.883876)
					(end 152.002744 -403.883876)
				)
			)
		)
	)
	(zone
		(layers "B.Cu" "In13.Cu" "In15.Cu")
		(hatch none 0.5)
		(connect_pads
			(clearance 0)
		)
		(min_thickness 0.25)
		(keepout
			(tracks not_allowed)
			(vias allowed)
			(pads allowed)
			(copperpour not_allowed)
			(footprints allowed)
		)
		(placement
			(enabled no)
			(sheetname "")
		)
		(fill yes
			(thermal_gap 0.5)
			(thermal_bridge_width 0.5)
			(island_removal_mode 0)
		)
		(polygon
			(pts
				(arc
					(start 347.21927 -249.620024)
					(mid 346.56649 -249.620024)
					(end 347.21927 -249.620024)
				)
			)
		)
	)
	(zone
		(layers "B.Cu" "In13.Cu" "In15.Cu")
		(hatch none 0.5)
		(connect_pads
			(clearance 0)
		)
		(min_thickness 0.25)
		(keepout
			(tracks not_allowed)
			(vias allowed)
			(pads allowed)
			(copperpour not_allowed)
			(footprints allowed)
		)
		(placement
			(enabled no)
			(sheetname "")
		)
		(fill yes
			(thermal_gap 0.5)
			(thermal_bridge_width 0.5)
			(island_removal_mode 0)
		)
		(polygon
			(pts
				(arc
					(start 361.786424 -221.133924)
					(mid 361.133644 -221.133924)
					(end 361.786424 -221.133924)
				)
			)
		)
	)
	(zone
		(layers "B.Cu" "In13.Cu" "In15.Cu")
		(hatch none 0.5)
		(connect_pads
			(clearance 0)
		)
		(min_thickness 0.25)
		(keepout
			(tracks not_allowed)
			(vias allowed)
			(pads allowed)
			(copperpour not_allowed)
			(footprints allowed)
		)
		(placement
			(enabled no)
			(sheetname "")
		)
		(fill yes
			(thermal_gap 0.5)
			(thermal_bridge_width 0.5)
			(island_removal_mode 0)
		)
		(polygon
			(pts
				(arc
					(start 100.328984 -264.50036)
					(mid 99.676204 -264.50036)
					(end 100.328984 -264.50036)
				)
			)
		)
	)
	(zone
		(layers "B.Cu" "In13.Cu" "In15.Cu")
		(hatch none 0.5)
		(connect_pads
			(clearance 0)
		)
		(min_thickness 0.25)
		(keepout
			(tracks not_allowed)
			(vias allowed)
			(pads allowed)
			(copperpour not_allowed)
			(footprints allowed)
		)
		(placement
			(enabled no)
			(sheetname "")
		)
		(fill yes
			(thermal_gap 0.5)
			(thermal_bridge_width 0.5)
			(island_removal_mode 0)
		)
		(polygon
			(pts
				(arc
					(start 348.739206 -276.708616)
					(mid 348.086426 -276.708616)
					(end 348.739206 -276.708616)
				)
			)
		)
	)
	(zone
		(layers "B.Cu" "In13.Cu" "In15.Cu")
		(hatch none 0.5)
		(connect_pads
			(clearance 0)
		)
		(min_thickness 0.25)
		(keepout
			(tracks not_allowed)
			(vias allowed)
			(pads allowed)
			(copperpour not_allowed)
			(footprints allowed)
		)
		(placement
			(enabled no)
			(sheetname "")
		)
		(fill yes
			(thermal_gap 0.5)
			(thermal_bridge_width 0.5)
			(island_removal_mode 0)
		)
		(polygon
			(pts
				(arc
					(start 123.714002 -228.45903)
					(mid 123.061222 -228.45903)
					(end 123.714002 -228.45903)
				)
			)
		)
	)
	(zone
		(layers "B.Cu" "In13.Cu" "In15.Cu")
		(hatch none 0.5)
		(connect_pads
			(clearance 0)
		)
		(min_thickness 0.25)
		(keepout
			(tracks not_allowed)
			(vias allowed)
			(pads allowed)
			(copperpour not_allowed)
			(footprints allowed)
		)
		(placement
			(enabled no)
			(sheetname "")
		)
		(fill yes
			(thermal_gap 0.5)
			(thermal_bridge_width 0.5)
			(island_removal_mode 0)
		)
		(polygon
			(pts
				(arc
					(start 335.582006 -281.59202)
					(mid 334.929226 -281.59202)
					(end 335.582006 -281.59202)
				)
			)
		)
	)
	(zone
		(layers "B.Cu" "In13.Cu" "In15.Cu")
		(hatch none 0.5)
		(connect_pads
			(clearance 0)
		)
		(min_thickness 0.25)
		(keepout
			(tracks not_allowed)
			(vias allowed)
			(pads allowed)
			(copperpour not_allowed)
			(footprints allowed)
		)
		(placement
			(enabled no)
			(sheetname "")
		)
		(fill yes
			(thermal_gap 0.5)
			(thermal_bridge_width 0.5)
			(island_removal_mode 0)
		)
		(polygon
			(pts
				(arc
					(start 413.786066 -6.713474)
					(mid 413.082486 -6.713474)
					(end 413.786066 -6.713474)
				)
			)
		)
	)
	(zone
		(layers "B.Cu" "In13.Cu" "In15.Cu")
		(hatch none 0.5)
		(connect_pads
			(clearance 0)
		)
		(min_thickness 0.25)
		(keepout
			(tracks not_allowed)
			(vias allowed)
			(pads allowed)
			(copperpour not_allowed)
			(footprints allowed)
		)
		(placement
			(enabled no)
			(sheetname "")
		)
		(fill yes
			(thermal_gap 0.5)
			(thermal_bridge_width 0.5)
			(island_removal_mode 0)
		)
		(polygon
			(pts
				(arc
					(start 114.316256 -221.94774)
					(mid 113.663476 -221.94774)
					(end 114.316256 -221.94774)
				)
			)
		)
	)
	(zone
		(layers "B.Cu" "In13.Cu" "In15.Cu")
		(hatch none 0.5)
		(connect_pads
			(clearance 0)
		)
		(min_thickness 0.25)
		(keepout
			(tracks not_allowed)
			(vias allowed)
			(pads allowed)
			(copperpour not_allowed)
			(footprints allowed)
		)
		(placement
			(enabled no)
			(sheetname "")
		)
		(fill yes
			(thermal_gap 0.5)
			(thermal_bridge_width 0.5)
			(island_removal_mode 0)
		)
		(polygon
			(pts
				(arc
					(start 125.123956 -230.900478)
					(mid 124.471176 -230.900478)
					(end 125.123956 -230.900478)
				)
			)
		)
	)
	(zone
		(layers "B.Cu" "In13.Cu" "In15.Cu")
		(hatch none 0.5)
		(connect_pads
			(clearance 0)
		)
		(min_thickness 0.25)
		(keepout
			(tracks not_allowed)
			(vias allowed)
			(pads allowed)
			(copperpour not_allowed)
			(footprints allowed)
		)
		(placement
			(enabled no)
			(sheetname "")
		)
		(fill yes
			(thermal_gap 0.5)
			(thermal_bridge_width 0.5)
			(island_removal_mode 0)
		)
		(polygon
			(pts
				(arc
					(start 455.337672 -201.56678)
					(mid 454.684892 -201.56678)
					(end 455.337672 -201.56678)
				)
			)
		)
	)
	(zone
		(layers "B.Cu" "In13.Cu" "In15.Cu")
		(hatch none 0.5)
		(connect_pads
			(clearance 0)
		)
		(min_thickness 0.25)
		(keepout
			(tracks not_allowed)
			(vias allowed)
			(pads allowed)
			(copperpour not_allowed)
			(footprints allowed)
		)
		(placement
			(enabled no)
			(sheetname "")
		)
		(fill yes
			(thermal_gap 0.5)
			(thermal_bridge_width 0.5)
			(island_removal_mode 0)
		)
		(polygon
			(pts
				(arc
					(start 21.173186 -4.962652)
					(mid 20.469606 -4.962652)
					(end 21.173186 -4.962652)
				)
			)
		)
	)
	(zone
		(layers "B.Cu" "In13.Cu" "In15.Cu")
		(hatch none 0.5)
		(connect_pads
			(clearance 0)
		)
		(min_thickness 0.25)
		(keepout
			(tracks not_allowed)
			(vias allowed)
			(pads allowed)
			(copperpour not_allowed)
			(footprints allowed)
		)
		(placement
			(enabled no)
			(sheetname "")
		)
		(fill yes
			(thermal_gap 0.5)
			(thermal_bridge_width 0.5)
			(island_removal_mode 0)
		)
		(polygon
			(pts
				(arc
					(start 99.279202 -236.597952)
					(mid 98.626422 -236.597952)
					(end 99.279202 -236.597952)
				)
			)
		)
	)
	(zone
		(layers "B.Cu" "In13.Cu" "In15.Cu")
		(hatch none 0.5)
		(connect_pads
			(clearance 0)
		)
		(min_thickness 0.25)
		(keepout
			(tracks not_allowed)
			(vias allowed)
			(pads allowed)
			(copperpour not_allowed)
			(footprints allowed)
		)
		(placement
			(enabled no)
			(sheetname "")
		)
		(fill yes
			(thermal_gap 0.5)
			(thermal_bridge_width 0.5)
			(island_removal_mode 0)
		)
		(polygon
			(pts
				(arc
					(start 73.701148 -403.883876)
					(mid 72.997568 -403.883876)
					(end 73.701148 -403.883876)
				)
			)
		)
	)
	(zone
		(layers "B.Cu" "In13.Cu" "In15.Cu")
		(hatch none 0.5)
		(connect_pads
			(clearance 0)
		)
		(min_thickness 0.25)
		(keepout
			(tracks not_allowed)
			(vias allowed)
			(pads allowed)
			(copperpour not_allowed)
			(footprints allowed)
		)
		(placement
			(enabled no)
			(sheetname "")
		)
		(fill yes
			(thermal_gap 0.5)
			(thermal_bridge_width 0.5)
			(island_removal_mode 0)
		)
		(polygon
			(pts
				(arc
					(start 21.215604 -279.766776)
					(mid 20.562824 -279.766776)
					(end 21.215604 -279.766776)
				)
			)
		)
	)
	(zone
		(layers "B.Cu" "In13.Cu" "In15.Cu")
		(hatch none 0.5)
		(connect_pads
			(clearance 0)
		)
		(min_thickness 0.25)
		(keepout
			(tracks not_allowed)
			(vias allowed)
			(pads allowed)
			(copperpour not_allowed)
			(footprints allowed)
		)
		(placement
			(enabled no)
			(sheetname "")
		)
		(fill yes
			(thermal_gap 0.5)
			(thermal_bridge_width 0.5)
			(island_removal_mode 0)
		)
		(polygon
			(pts
				(arc
					(start 337.931252 -280.778204)
					(mid 337.278472 -280.778204)
					(end 337.931252 -280.778204)
				)
			)
		)
	)
	(zone
		(layers "B.Cu" "In13.Cu" "In15.Cu")
		(hatch none 0.5)
		(connect_pads
			(clearance 0)
		)
		(min_thickness 0.25)
		(keepout
			(tracks not_allowed)
			(vias allowed)
			(pads allowed)
			(copperpour not_allowed)
			(footprints allowed)
		)
		(placement
			(enabled no)
			(sheetname "")
		)
		(fill yes
			(thermal_gap 0.5)
			(thermal_bridge_width 0.5)
			(island_removal_mode 0)
		)
		(polygon
			(pts
				(arc
					(start 327.054972 -430.889918)
					(mid 326.24522 -430.889918)
					(end 327.054972 -430.889918)
				)
			)
		)
	)
	(zone
		(layers "B.Cu" "In13.Cu" "In15.Cu")
		(hatch none 0.5)
		(connect_pads
			(clearance 0)
		)
		(min_thickness 0.25)
		(keepout
			(tracks not_allowed)
			(vias allowed)
			(pads allowed)
			(copperpour not_allowed)
			(footprints allowed)
		)
		(placement
			(enabled no)
			(sheetname "")
		)
		(fill yes
			(thermal_gap 0.5)
			(thermal_bridge_width 0.5)
			(island_removal_mode 0)
		)
		(polygon
			(pts
				(arc
					(start 91.871038 -282.405836)
					(mid 91.218258 -282.405836)
					(end 91.871038 -282.405836)
				)
			)
		)
	)
	(zone
		(layers "B.Cu" "In13.Cu" "In15.Cu")
		(hatch none 0.5)
		(connect_pads
			(clearance 0)
		)
		(min_thickness 0.25)
		(keepout
			(tracks not_allowed)
			(vias allowed)
			(pads allowed)
			(copperpour not_allowed)
			(footprints allowed)
		)
		(placement
			(enabled no)
			(sheetname "")
		)
		(fill yes
			(thermal_gap 0.5)
			(thermal_bridge_width 0.5)
			(island_removal_mode 0)
		)
		(polygon
			(pts
				(arc
					(start 125.233684 -257.175254)
					(mid 124.580904 -257.175254)
					(end 125.233684 -257.175254)
				)
			)
		)
	)
	(zone
		(layers "B.Cu" "In13.Cu" "In15.Cu")
		(hatch none 0.5)
		(connect_pads
			(clearance 0)
		)
		(min_thickness 0.25)
		(keepout
			(tracks not_allowed)
			(vias allowed)
			(pads allowed)
			(copperpour not_allowed)
			(footprints allowed)
		)
		(placement
			(enabled no)
			(sheetname "")
		)
		(fill yes
			(thermal_gap 0.5)
			(thermal_bridge_width 0.5)
			(island_removal_mode 0)
		)
		(polygon
			(pts
				(arc
					(start 350.618552 -276.708616)
					(mid 349.965772 -276.708616)
					(end 350.618552 -276.708616)
				)
			)
		)
	)
	(zone
		(layers "B.Cu" "In13.Cu" "In15.Cu")
		(hatch none 0.5)
		(connect_pads
			(clearance 0)
		)
		(min_thickness 0.25)
		(keepout
			(tracks not_allowed)
			(vias allowed)
			(pads allowed)
			(copperpour not_allowed)
			(footprints allowed)
		)
		(placement
			(enabled no)
			(sheetname "")
		)
		(fill yes
			(thermal_gap 0.5)
			(thermal_bridge_width 0.5)
			(island_removal_mode 0)
		)
		(polygon
			(pts
				(arc
					(start 54.952138 -6.724396)
					(mid 54.248558 -6.724396)
					(end 54.952138 -6.724396)
				)
			)
		)
	)
	(zone
		(layers "B.Cu" "In13.Cu" "In15.Cu")
		(hatch none 0.5)
		(connect_pads
			(clearance 0)
		)
		(min_thickness 0.25)
		(keepout
			(tracks not_allowed)
			(vias allowed)
			(pads allowed)
			(copperpour not_allowed)
			(footprints allowed)
		)
		(placement
			(enabled no)
			(sheetname "")
		)
		(fill yes
			(thermal_gap 0.5)
			(thermal_bridge_width 0.5)
			(island_removal_mode 0)
		)
		(polygon
			(pts
				(arc
					(start 98.449384 -277.522432)
					(mid 97.796604 -277.522432)
					(end 98.449384 -277.522432)
				)
			)
		)
	)
	(zone
		(layers "B.Cu" "In13.Cu" "In15.Cu")
		(hatch none 0.5)
		(connect_pads
			(clearance 0)
		)
		(min_thickness 0.25)
		(keepout
			(tracks not_allowed)
			(vias allowed)
			(pads allowed)
			(copperpour not_allowed)
			(footprints allowed)
		)
		(placement
			(enabled no)
			(sheetname "")
		)
		(fill yes
			(thermal_gap 0.5)
			(thermal_bridge_width 0.5)
			(island_removal_mode 0)
		)
		(polygon
			(pts
				(arc
					(start 21.215604 -267.016738)
					(mid 20.562824 -267.016738)
					(end 21.215604 -267.016738)
				)
			)
		)
	)
	(zone
		(layers "B.Cu" "In13.Cu" "In15.Cu")
		(hatch none 0.5)
		(connect_pads
			(clearance 0)
		)
		(min_thickness 0.25)
		(keepout
			(tracks not_allowed)
			(vias allowed)
			(pads allowed)
			(copperpour not_allowed)
			(footprints allowed)
		)
		(placement
			(enabled no)
			(sheetname "")
		)
		(fill yes
			(thermal_gap 0.5)
			(thermal_bridge_width 0.5)
			(island_removal_mode 0)
		)
		(polygon
			(pts
				(arc
					(start 348.629224 -248.806208)
					(mid 347.976444 -248.806208)
					(end 348.629224 -248.806208)
				)
			)
		)
	)
	(zone
		(layers "B.Cu" "In13.Cu" "In15.Cu")
		(hatch none 0.5)
		(connect_pads
			(clearance 0)
		)
		(min_thickness 0.25)
		(keepout
			(tracks not_allowed)
			(vias allowed)
			(pads allowed)
			(copperpour not_allowed)
			(footprints allowed)
		)
		(placement
			(enabled no)
			(sheetname "")
		)
		(fill yes
			(thermal_gap 0.5)
			(thermal_bridge_width 0.5)
			(island_removal_mode 0)
		)
		(polygon
			(pts
				(arc
					(start 386.15493 -426.089826)
					(mid 385.345178 -426.089826)
					(end 386.15493 -426.089826)
				)
			)
		)
	)
	(zone
		(layers "B.Cu" "In13.Cu" "In15.Cu")
		(hatch none 0.5)
		(connect_pads
			(clearance 0)
		)
		(min_thickness 0.25)
		(keepout
			(tracks not_allowed)
			(vias allowed)
			(pads allowed)
			(copperpour not_allowed)
			(footprints allowed)
		)
		(placement
			(enabled no)
			(sheetname "")
		)
		(fill yes
			(thermal_gap 0.5)
			(thermal_bridge_width 0.5)
			(island_removal_mode 0)
		)
		(polygon
			(pts
				(arc
					(start 28.37307 -4.962652)
					(mid 27.66949 -4.962652)
					(end 28.37307 -4.962652)
				)
			)
		)
	)
	(zone
		(layers "B.Cu" "In13.Cu" "In15.Cu")
		(hatch none 0.5)
		(connect_pads
			(clearance 0)
		)
		(min_thickness 0.25)
		(keepout
			(tracks not_allowed)
			(vias allowed)
			(pads allowed)
			(copperpour not_allowed)
			(footprints allowed)
		)
		(placement
			(enabled no)
			(sheetname "")
		)
		(fill yes
			(thermal_gap 0.5)
			(thermal_bridge_width 0.5)
			(island_removal_mode 0)
		)
		(polygon
			(pts
				(arc
					(start 203.297536 -200.716642)
					(mid 202.644756 -200.716642)
					(end 203.297536 -200.716642)
				)
			)
		)
	)
	(zone
		(layers "B.Cu" "In13.Cu" "In15.Cu")
		(hatch none 0.5)
		(connect_pads
			(clearance 0)
		)
		(min_thickness 0.25)
		(keepout
			(tracks not_allowed)
			(vias allowed)
			(pads allowed)
			(copperpour not_allowed)
			(footprints allowed)
		)
		(placement
			(enabled no)
			(sheetname "")
		)
		(fill yes
			(thermal_gap 0.5)
			(thermal_bridge_width 0.5)
			(island_removal_mode 0)
		)
		(polygon
			(pts
				(arc
					(start 366.01527 -221.94774)
					(mid 365.36249 -221.94774)
					(end 366.01527 -221.94774)
				)
			)
		)
	)
	(zone
		(layers "B.Cu" "In13.Cu" "In15.Cu")
		(hatch none 0.5)
		(connect_pads
			(clearance 0)
		)
		(min_thickness 0.25)
		(keepout
			(tracks not_allowed)
			(vias allowed)
			(pads allowed)
			(copperpour not_allowed)
			(footprints allowed)
		)
		(placement
			(enabled no)
			(sheetname "")
		)
		(fill yes
			(thermal_gap 0.5)
			(thermal_bridge_width 0.5)
			(island_removal_mode 0)
		)
		(polygon
			(pts
				(arc
					(start 106.437938 -281.59202)
					(mid 105.785158 -281.59202)
					(end 106.437938 -281.59202)
				)
			)
		)
	)
	(zone
		(layers "B.Cu" "In13.Cu" "In15.Cu")
		(hatch none 0.5)
		(connect_pads
			(clearance 0)
		)
		(min_thickness 0.25)
		(keepout
			(tracks not_allowed)
			(vias allowed)
			(pads allowed)
			(copperpour not_allowed)
			(footprints allowed)
		)
		(placement
			(enabled no)
			(sheetname "")
		)
		(fill yes
			(thermal_gap 0.5)
			(thermal_bridge_width 0.5)
			(island_removal_mode 0)
		)
		(polygon
			(pts
				(arc
					(start 269.155672 -240.666778)
					(mid 268.502892 -240.666778)
					(end 269.155672 -240.666778)
				)
			)
		)
	)
	(zone
		(layers "B.Cu" "In13.Cu" "In15.Cu")
		(hatch none 0.5)
		(connect_pads
			(clearance 0)
		)
		(min_thickness 0.25)
		(keepout
			(tracks not_allowed)
			(vias allowed)
			(pads allowed)
			(copperpour not_allowed)
			(footprints allowed)
		)
		(placement
			(enabled no)
			(sheetname "")
		)
		(fill yes
			(thermal_gap 0.5)
			(thermal_bridge_width 0.5)
			(island_removal_mode 0)
		)
		(polygon
			(pts
				(arc
					(start 99.279202 -241.481102)
					(mid 98.626422 -241.481102)
					(end 99.279202 -241.481102)
				)
			)
		)
	)
	(zone
		(layers "B.Cu" "In13.Cu" "In15.Cu")
		(hatch none 0.5)
		(connect_pads
			(clearance 0)
		)
		(min_thickness 0.25)
		(keepout
			(tracks not_allowed)
			(vias allowed)
			(pads allowed)
			(copperpour not_allowed)
			(footprints allowed)
		)
		(placement
			(enabled no)
			(sheetname "")
		)
		(fill yes
			(thermal_gap 0.5)
			(thermal_bridge_width 0.5)
			(island_removal_mode 0)
		)
		(polygon
			(pts
				(arc
					(start 123.354338 -260.430772)
					(mid 122.701558 -260.430772)
					(end 123.354338 -260.430772)
				)
			)
		)
	)
	(zone
		(layers "B.Cu" "In13.Cu" "In15.Cu")
		(hatch none 0.5)
		(connect_pads
			(clearance 0)
		)
		(min_thickness 0.25)
		(keepout
			(tracks not_allowed)
			(vias allowed)
			(pads allowed)
			(copperpour not_allowed)
			(footprints allowed)
		)
		(placement
			(enabled no)
			(sheetname "")
		)
		(fill yes
			(thermal_gap 0.5)
			(thermal_bridge_width 0.5)
			(island_removal_mode 0)
		)
		(polygon
			(pts
				(arc
					(start 158.129224 -403.883876)
					(mid 157.425644 -403.883876)
					(end 158.129224 -403.883876)
				)
			)
		)
	)
	(zone
		(layers "B.Cu" "In13.Cu" "In15.Cu")
		(hatch none 0.5)
		(connect_pads
			(clearance 0)
		)
		(min_thickness 0.25)
		(keepout
			(tracks not_allowed)
			(vias allowed)
			(pads allowed)
			(copperpour not_allowed)
			(footprints allowed)
		)
		(placement
			(enabled no)
			(sheetname "")
		)
		(fill yes
			(thermal_gap 0.5)
			(thermal_bridge_width 0.5)
			(island_removal_mode 0)
		)
		(polygon
			(pts
				(arc
					(start 73.054972 -431.889916)
					(mid 72.24522 -431.889916)
					(end 73.054972 -431.889916)
				)
			)
		)
	)
	(zone
		(layers "B.Cu" "In13.Cu" "In15.Cu")
		(hatch none 0.5)
		(connect_pads
			(clearance 0)
		)
		(min_thickness 0.25)
		(keepout
			(tracks not_allowed)
			(vias allowed)
			(pads allowed)
			(copperpour not_allowed)
			(footprints allowed)
		)
		(placement
			(enabled no)
			(sheetname "")
		)
		(fill yes
			(thermal_gap 0.5)
			(thermal_bridge_width 0.5)
			(island_removal_mode 0)
		)
		(polygon
			(pts
				(arc
					(start 90.054938 -430.689766)
					(mid 89.245186 -430.689766)
					(end 90.054938 -430.689766)
				)
			)
		)
	)
	(zone
		(layers "B.Cu" "In13.Cu" "In15.Cu")
		(hatch none 0.5)
		(connect_pads
			(clearance 0)
		)
		(min_thickness 0.25)
		(keepout
			(tracks not_allowed)
			(vias allowed)
			(pads allowed)
			(copperpour not_allowed)
			(footprints allowed)
		)
		(placement
			(enabled no)
			(sheetname "")
		)
		(fill yes
			(thermal_gap 0.5)
			(thermal_bridge_width 0.5)
			(island_removal_mode 0)
		)
		(polygon
			(pts
				(arc
					(start 17.115536 -288.266632)
					(mid 16.462756 -288.266632)
					(end 17.115536 -288.266632)
				)
			)
		)
	)
	(zone
		(layers "B.Cu" "In13.Cu" "In15.Cu")
		(hatch none 0.5)
		(connect_pads
			(clearance 0)
		)
		(min_thickness 0.25)
		(keepout
			(tracks not_allowed)
			(vias allowed)
			(pads allowed)
			(copperpour not_allowed)
			(footprints allowed)
		)
		(placement
			(enabled no)
			(sheetname "")
		)
		(fill yes
			(thermal_gap 0.5)
			(thermal_bridge_width 0.5)
			(island_removal_mode 0)
		)
		(polygon
			(pts
				(arc
					(start 382.154938 -427.289976)
					(mid 381.345186 -427.289976)
					(end 382.154938 -427.289976)
				)
			)
		)
	)
	(zone
		(layers "B.Cu" "In13.Cu" "In15.Cu")
		(hatch none 0.5)
		(connect_pads
			(clearance 0)
		)
		(min_thickness 0.25)
		(keepout
			(tracks not_allowed)
			(vias allowed)
			(pads allowed)
			(copperpour not_allowed)
			(footprints allowed)
		)
		(placement
			(enabled no)
			(sheetname "")
		)
		(fill yes
			(thermal_gap 0.5)
			(thermal_bridge_width 0.5)
			(island_removal_mode 0)
		)
		(polygon
			(pts
				(arc
					(start 203.297536 -204.116686)
					(mid 202.644756 -204.116686)
					(end 203.297536 -204.116686)
				)
			)
		)
	)
	(zone
		(layers "B.Cu" "In13.Cu" "In15.Cu")
		(hatch none 0.5)
		(connect_pads
			(clearance 0)
		)
		(min_thickness 0.25)
		(keepout
			(tracks not_allowed)
			(vias allowed)
			(pads allowed)
			(copperpour not_allowed)
			(footprints allowed)
		)
		(placement
			(enabled no)
			(sheetname "")
		)
		(fill yes
			(thermal_gap 0.5)
			(thermal_bridge_width 0.5)
			(island_removal_mode 0)
		)
		(polygon
			(pts
				(arc
					(start 102.678738 -279.964134)
					(mid 102.025958 -279.964134)
					(end 102.678738 -279.964134)
				)
			)
		)
	)
	(zone
		(layers "B.Cu" "In13.Cu" "In15.Cu")
		(hatch none 0.5)
		(connect_pads
			(clearance 0)
		)
		(min_thickness 0.25)
		(keepout
			(tracks not_allowed)
			(vias allowed)
			(pads allowed)
			(copperpour not_allowed)
			(footprints allowed)
		)
		(placement
			(enabled no)
			(sheetname "")
		)
		(fill yes
			(thermal_gap 0.5)
			(thermal_bridge_width 0.5)
			(island_removal_mode 0)
		)
		(polygon
			(pts
				(arc
					(start 348.15907 -246.364506)
					(mid 347.50629 -246.364506)
					(end 348.15907 -246.364506)
				)
			)
		)
	)
	(zone
		(layers "B.Cu" "In13.Cu" "In15.Cu")
		(hatch none 0.5)
		(connect_pads
			(clearance 0)
		)
		(min_thickness 0.25)
		(keepout
			(tracks not_allowed)
			(vias allowed)
			(pads allowed)
			(copperpour not_allowed)
			(footprints allowed)
		)
		(placement
			(enabled no)
			(sheetname "")
		)
		(fill yes
			(thermal_gap 0.5)
			(thermal_bridge_width 0.5)
			(island_removal_mode 0)
		)
		(polygon
			(pts
				(arc
					(start 125.593602 -246.364506)
					(mid 124.940822 -246.364506)
					(end 125.593602 -246.364506)
				)
			)
		)
	)
	(zone
		(layers "B.Cu" "In13.Cu" "In15.Cu")
		(hatch none 0.5)
		(connect_pads
			(clearance 0)
		)
		(min_thickness 0.25)
		(keepout
			(tracks not_allowed)
			(vias allowed)
			(pads allowed)
			(copperpour not_allowed)
			(footprints allowed)
		)
		(placement
			(enabled no)
			(sheetname "")
		)
		(fill yes
			(thermal_gap 0.5)
			(thermal_bridge_width 0.5)
			(island_removal_mode 0)
		)
		(polygon
			(pts
				(arc
					(start 348.269052 -266.128246)
					(mid 347.616272 -266.128246)
					(end 348.269052 -266.128246)
				)
			)
		)
	)
	(zone
		(layers "B.Cu" "In13.Cu" "In15.Cu")
		(hatch none 0.5)
		(connect_pads
			(clearance 0)
		)
		(min_thickness 0.25)
		(keepout
			(tracks not_allowed)
			(vias allowed)
			(pads allowed)
			(copperpour not_allowed)
			(footprints allowed)
		)
		(placement
			(enabled no)
			(sheetname "")
		)
		(fill yes
			(thermal_gap 0.5)
			(thermal_bridge_width 0.5)
			(island_removal_mode 0)
		)
		(polygon
			(pts
				(arc
					(start 203.297536 -262.76681)
					(mid 202.644756 -262.76681)
					(end 203.297536 -262.76681)
				)
			)
		)
	)
	(zone
		(layers "B.Cu" "In13.Cu" "In15.Cu")
		(hatch none 0.5)
		(connect_pads
			(clearance 0)
		)
		(min_thickness 0.25)
		(keepout
			(tracks not_allowed)
			(vias allowed)
			(pads allowed)
			(copperpour not_allowed)
			(footprints allowed)
		)
		(placement
			(enabled no)
			(sheetname "")
		)
		(fill yes
			(thermal_gap 0.5)
			(thermal_bridge_width 0.5)
			(island_removal_mode 0)
		)
		(polygon
			(pts
				(arc
					(start 85.762084 -284.847538)
					(mid 85.109304 -284.847538)
					(end 85.762084 -284.847538)
				)
			)
		)
	)
	(zone
		(layers "B.Cu" "In13.Cu" "In15.Cu")
		(hatch none 0.5)
		(connect_pads
			(clearance 0)
		)
		(min_thickness 0.25)
		(keepout
			(tracks not_allowed)
			(vias allowed)
			(pads allowed)
			(copperpour not_allowed)
			(footprints allowed)
		)
		(placement
			(enabled no)
			(sheetname "")
		)
		(fill yes
			(thermal_gap 0.5)
			(thermal_bridge_width 0.5)
			(island_removal_mode 0)
		)
		(polygon
			(pts
				(arc
					(start 451.237604 -261.066788)
					(mid 450.584824 -261.066788)
					(end 451.237604 -261.066788)
				)
			)
		)
	)
	(zone
		(layers "B.Cu" "In13.Cu" "In15.Cu")
		(hatch none 0.5)
		(connect_pads
			(clearance 0)
		)
		(min_thickness 0.25)
		(keepout
			(tracks not_allowed)
			(vias allowed)
			(pads allowed)
			(copperpour not_allowed)
			(footprints allowed)
		)
		(placement
			(enabled no)
			(sheetname "")
		)
		(fill yes
			(thermal_gap 0.5)
			(thermal_bridge_width 0.5)
			(island_removal_mode 0)
		)
		(polygon
			(pts
				(arc
					(start 207.397604 -221.96679)
					(mid 206.744824 -221.96679)
					(end 207.397604 -221.96679)
				)
			)
		)
	)
	(zone
		(layers "B.Cu" "In13.Cu" "In15.Cu")
		(hatch none 0.5)
		(connect_pads
			(clearance 0)
		)
		(min_thickness 0.25)
		(keepout
			(tracks not_allowed)
			(vias allowed)
			(pads allowed)
			(copperpour not_allowed)
			(footprints allowed)
		)
		(placement
			(enabled no)
			(sheetname "")
		)
		(fill yes
			(thermal_gap 0.5)
			(thermal_bridge_width 0.5)
			(island_removal_mode 0)
		)
		(polygon
			(pts
				(arc
					(start 265.055604 -291.666676)
					(mid 264.402824 -291.666676)
					(end 265.055604 -291.666676)
				)
			)
		)
	)
	(zone
		(layers "B.Cu" "In13.Cu" "In15.Cu")
		(hatch none 0.5)
		(connect_pads
			(clearance 0)
		)
		(min_thickness 0.25)
		(keepout
			(tracks not_allowed)
			(vias allowed)
			(pads allowed)
			(copperpour not_allowed)
			(footprints allowed)
		)
		(placement
			(enabled no)
			(sheetname "")
		)
		(fill yes
			(thermal_gap 0.5)
			(thermal_bridge_width 0.5)
			(island_removal_mode 0)
		)
		(polygon
			(pts
				(arc
					(start 373.174006 -275.08073)
					(mid 372.521226 -275.08073)
					(end 373.174006 -275.08073)
				)
			)
		)
	)
	(zone
		(layers "B.Cu" "In13.Cu" "In15.Cu")
		(hatch none 0.5)
		(connect_pads
			(clearance 0)
		)
		(min_thickness 0.25)
		(keepout
			(tracks not_allowed)
			(vias allowed)
			(pads allowed)
			(copperpour not_allowed)
			(footprints allowed)
		)
		(placement
			(enabled no)
			(sheetname "")
		)
		(fill yes
			(thermal_gap 0.5)
			(thermal_bridge_width 0.5)
			(island_removal_mode 0)
		)
		(polygon
			(pts
				(arc
					(start 269.155672 -199.01662)
					(mid 268.502892 -199.01662)
					(end 269.155672 -199.01662)
				)
			)
		)
	)
	(zone
		(layers "B.Cu" "In13.Cu" "In15.Cu")
		(hatch none 0.5)
		(connect_pads
			(clearance 0)
		)
		(min_thickness 0.25)
		(keepout
			(tracks not_allowed)
			(vias allowed)
			(pads allowed)
			(copperpour not_allowed)
			(footprints allowed)
		)
		(placement
			(enabled no)
			(sheetname "")
		)
		(fill yes
			(thermal_gap 0.5)
			(thermal_bridge_width 0.5)
			(island_removal_mode 0)
		)
		(polygon
			(pts
				(arc
					(start 462.881472 -267.016738)
					(mid 462.228692 -267.016738)
					(end 462.881472 -267.016738)
				)
			)
		)
	)
	(zone
		(layers "B.Cu" "In13.Cu" "In15.Cu")
		(hatch none 0.5)
		(connect_pads
			(clearance 0)
		)
		(min_thickness 0.25)
		(keepout
			(tracks not_allowed)
			(vias allowed)
			(pads allowed)
			(copperpour not_allowed)
			(footprints allowed)
		)
		(placement
			(enabled no)
			(sheetname "")
		)
		(fill yes
			(thermal_gap 0.5)
			(thermal_bridge_width 0.5)
			(island_removal_mode 0)
		)
		(polygon
			(pts
				(arc
					(start 91.216988 -403.883876)
					(mid 90.513408 -403.883876)
					(end 91.216988 -403.883876)
				)
			)
		)
	)
	(zone
		(layers "B.Cu" "In13.Cu" "In15.Cu")
		(hatch none 0.5)
		(connect_pads
			(clearance 0)
		)
		(min_thickness 0.25)
		(keepout
			(tracks not_allowed)
			(vias allowed)
			(pads allowed)
			(copperpour not_allowed)
			(footprints allowed)
		)
		(placement
			(enabled no)
			(sheetname "")
		)
		(fill yes
			(thermal_gap 0.5)
			(thermal_bridge_width 0.5)
			(island_removal_mode 0)
		)
		(polygon
			(pts
				(arc
					(start 207.397604 -246.616728)
					(mid 206.744824 -246.616728)
					(end 207.397604 -246.616728)
				)
			)
		)
	)
	(zone
		(layers "B.Cu" "In13.Cu" "In15.Cu")
		(hatch none 0.5)
		(connect_pads
			(clearance 0)
		)
		(min_thickness 0.25)
		(keepout
			(tracks not_allowed)
			(vias allowed)
			(pads allowed)
			(copperpour not_allowed)
			(footprints allowed)
		)
		(placement
			(enabled no)
			(sheetname "")
		)
		(fill yes
			(thermal_gap 0.5)
			(thermal_bridge_width 0.5)
			(island_removal_mode 0)
		)
		(polygon
			(pts
				(arc
					(start 203.297536 -267.866622)
					(mid 202.644756 -267.866622)
					(end 203.297536 -267.866622)
				)
			)
		)
	)
	(zone
		(layers "B.Cu" "In13.Cu" "In15.Cu")
		(hatch none 0.5)
		(connect_pads
			(clearance 0)
		)
		(min_thickness 0.25)
		(keepout
			(tracks not_allowed)
			(vias allowed)
			(pads allowed)
			(copperpour not_allowed)
			(footprints allowed)
		)
		(placement
			(enabled no)
			(sheetname "")
		)
		(fill yes
			(thermal_gap 0.5)
			(thermal_bridge_width 0.5)
			(island_removal_mode 0)
		)
		(polygon
			(pts
				(arc
					(start 203.297536 -215.166702)
					(mid 202.644756 -215.166702)
					(end 203.297536 -215.166702)
				)
			)
		)
	)
	(zone
		(layers "B.Cu" "In13.Cu" "In15.Cu")
		(hatch none 0.5)
		(connect_pads
			(clearance 0)
		)
		(min_thickness 0.25)
		(keepout
			(tracks not_allowed)
			(vias allowed)
			(pads allowed)
			(copperpour not_allowed)
			(footprints allowed)
		)
		(placement
			(enabled no)
			(sheetname "")
		)
		(fill yes
			(thermal_gap 0.5)
			(thermal_bridge_width 0.5)
			(island_removal_mode 0)
		)
		(polygon
			(pts
				(arc
					(start 265.055604 -198.166736)
					(mid 264.402824 -198.166736)
					(end 265.055604 -198.166736)
				)
			)
		)
	)
	(zone
		(layers "B.Cu" "In13.Cu" "In15.Cu")
		(hatch none 0.5)
		(connect_pads
			(clearance 0)
		)
		(min_thickness 0.25)
		(keepout
			(tracks not_allowed)
			(vias allowed)
			(pads allowed)
			(copperpour not_allowed)
			(footprints allowed)
		)
		(placement
			(enabled no)
			(sheetname "")
		)
		(fill yes
			(thermal_gap 0.5)
			(thermal_bridge_width 0.5)
			(island_removal_mode 0)
		)
		(polygon
			(pts
				(arc
					(start 409.154884 -427.089824)
					(mid 408.345132 -427.089824)
					(end 409.154884 -427.089824)
				)
			)
		)
	)
	(zone
		(layers "B.Cu" "In13.Cu" "In15.Cu")
		(hatch none 0.5)
		(connect_pads
			(clearance 0)
		)
		(min_thickness 0.25)
		(keepout
			(tracks not_allowed)
			(vias allowed)
			(pads allowed)
			(copperpour not_allowed)
			(footprints allowed)
		)
		(placement
			(enabled no)
			(sheetname "")
		)
		(fill yes
			(thermal_gap 0.5)
			(thermal_bridge_width 0.5)
			(island_removal_mode 0)
		)
		(polygon
			(pts
				(arc
					(start 203.297536 -301.01667)
					(mid 202.644756 -301.01667)
					(end 203.297536 -301.01667)
				)
			)
		)
	)
	(zone
		(layers "B.Cu" "In13.Cu" "In15.Cu")
		(hatch none 0.5)
		(connect_pads
			(clearance 0)
		)
		(min_thickness 0.25)
		(keepout
			(tracks not_allowed)
			(vias allowed)
			(pads allowed)
			(copperpour not_allowed)
			(footprints allowed)
		)
		(placement
			(enabled no)
			(sheetname "")
		)
		(fill yes
			(thermal_gap 0.5)
			(thermal_bridge_width 0.5)
			(island_removal_mode 0)
		)
		(polygon
			(pts
				(arc
					(start 125.123956 -243.922804)
					(mid 124.471176 -243.922804)
					(end 125.123956 -243.922804)
				)
			)
		)
	)
	(zone
		(layers "B.Cu" "In13.Cu" "In15.Cu")
		(hatch none 0.5)
		(connect_pads
			(clearance 0)
		)
		(min_thickness 0.25)
		(keepout
			(tracks not_allowed)
			(vias allowed)
			(pads allowed)
			(copperpour not_allowed)
			(footprints allowed)
		)
		(placement
			(enabled no)
			(sheetname "")
		)
		(fill yes
			(thermal_gap 0.5)
			(thermal_bridge_width 0.5)
			(island_removal_mode 0)
		)
		(polygon
			(pts
				(arc
					(start 321.054984 -430.689766)
					(mid 320.245232 -430.689766)
					(end 321.054984 -430.689766)
				)
			)
		)
	)
	(zone
		(layers "B.Cu" "In13.Cu" "In15.Cu")
		(hatch none 0.5)
		(connect_pads
			(clearance 0)
		)
		(min_thickness 0.25)
		(keepout
			(tracks not_allowed)
			(vias allowed)
			(pads allowed)
			(copperpour not_allowed)
			(footprints allowed)
		)
		(placement
			(enabled no)
			(sheetname "")
		)
		(fill yes
			(thermal_gap 0.5)
			(thermal_bridge_width 0.5)
			(island_removal_mode 0)
		)
		(polygon
			(pts
				(arc
					(start 125.593602 -226.831144)
					(mid 124.940822 -226.831144)
					(end 125.593602 -226.831144)
				)
			)
		)
	)
	(zone
		(layers "B.Cu" "In13.Cu" "In15.Cu")
		(hatch none 0.5)
		(connect_pads
			(clearance 0)
		)
		(min_thickness 0.25)
		(keepout
			(tracks not_allowed)
			(vias allowed)
			(pads allowed)
			(copperpour not_allowed)
			(footprints allowed)
		)
		(placement
			(enabled no)
			(sheetname "")
		)
		(fill yes
			(thermal_gap 0.5)
			(thermal_bridge_width 0.5)
			(island_removal_mode 0)
		)
		(polygon
			(pts
				(arc
					(start 451.237604 -301.01667)
					(mid 450.584824 -301.01667)
					(end 451.237604 -301.01667)
				)
			)
		)
	)
	(zone
		(layers "B.Cu" "In13.Cu" "In15.Cu")
		(hatch none 0.5)
		(connect_pads
			(clearance 0)
		)
		(min_thickness 0.25)
		(keepout
			(tracks not_allowed)
			(vias allowed)
			(pads allowed)
			(copperpour not_allowed)
			(footprints allowed)
		)
		(placement
			(enabled no)
			(sheetname "")
		)
		(fill yes
			(thermal_gap 0.5)
			(thermal_bridge_width 0.5)
			(island_removal_mode 0)
		)
		(polygon
			(pts
				(arc
					(start 327.054972 -429.689768)
					(mid 326.24522 -429.689768)
					(end 327.054972 -429.689768)
				)
			)
		)
	)
	(zone
		(layers "B.Cu" "In13.Cu" "In15.Cu")
		(hatch none 0.5)
		(connect_pads
			(clearance 0)
		)
		(min_thickness 0.25)
		(keepout
			(tracks not_allowed)
			(vias allowed)
			(pads allowed)
			(copperpour not_allowed)
			(footprints allowed)
		)
		(placement
			(enabled no)
			(sheetname "")
		)
		(fill yes
			(thermal_gap 0.5)
			(thermal_bridge_width 0.5)
			(island_removal_mode 0)
		)
		(polygon
			(pts
				(arc
					(start 119.015002 -220.319854)
					(mid 118.362222 -220.319854)
					(end 119.015002 -220.319854)
				)
			)
		)
	)
	(zone
		(layers "B.Cu" "In13.Cu" "In15.Cu")
		(hatch none 0.5)
		(connect_pads
			(clearance 0)
		)
		(min_thickness 0.25)
		(keepout
			(tracks not_allowed)
			(vias allowed)
			(pads allowed)
			(copperpour not_allowed)
			(footprints allowed)
		)
		(placement
			(enabled no)
			(sheetname "")
		)
		(fill yes
			(thermal_gap 0.5)
			(thermal_bridge_width 0.5)
			(island_removal_mode 0)
		)
		(polygon
			(pts
				(arc
					(start 124.184156 -227.64496)
					(mid 123.531376 -227.64496)
					(end 124.184156 -227.64496)
				)
			)
		)
	)
	(zone
		(layers "B.Cu" "In13.Cu" "In15.Cu")
		(hatch none 0.5)
		(connect_pads
			(clearance 0)
		)
		(min_thickness 0.25)
		(keepout
			(tracks not_allowed)
			(vias allowed)
			(pads allowed)
			(copperpour not_allowed)
			(footprints allowed)
		)
		(placement
			(enabled no)
			(sheetname "")
		)
		(fill yes
			(thermal_gap 0.5)
			(thermal_bridge_width 0.5)
			(island_removal_mode 0)
		)
		(polygon
			(pts
				(arc
					(start 418.249608 -6.713474)
					(mid 417.546028 -6.713474)
					(end 418.249608 -6.713474)
				)
			)
		)
	)
	(zone
		(layers "B.Cu" "In13.Cu" "In15.Cu")
		(hatch none 0.5)
		(connect_pads
			(clearance 0)
		)
		(min_thickness 0.25)
		(keepout
			(tracks not_allowed)
			(vias allowed)
			(pads allowed)
			(copperpour not_allowed)
			(footprints allowed)
		)
		(placement
			(enabled no)
			(sheetname "")
		)
		(fill yes
			(thermal_gap 0.5)
			(thermal_bridge_width 0.5)
			(island_removal_mode 0)
		)
		(polygon
			(pts
				(arc
					(start 357.087424 -221.133924)
					(mid 356.434644 -221.133924)
					(end 357.087424 -221.133924)
				)
			)
		)
	)
	(zone
		(layers "B.Cu" "In13.Cu" "In15.Cu")
		(hatch none 0.5)
		(connect_pads
			(clearance 0)
		)
		(min_thickness 0.25)
		(keepout
			(tracks not_allowed)
			(vias allowed)
			(pads allowed)
			(copperpour not_allowed)
			(footprints allowed)
		)
		(placement
			(enabled no)
			(sheetname "")
		)
		(fill yes
			(thermal_gap 0.5)
			(thermal_bridge_width 0.5)
			(island_removal_mode 0)
		)
		(polygon
			(pts
				(arc
					(start 269.155672 -218.566746)
					(mid 268.502892 -218.566746)
					(end 269.155672 -218.566746)
				)
			)
		)
	)
	(zone
		(layers "B.Cu" "In13.Cu" "In15.Cu")
		(hatch none 0.5)
		(connect_pads
			(clearance 0)
		)
		(min_thickness 0.25)
		(keepout
			(tracks not_allowed)
			(vias allowed)
			(pads allowed)
			(copperpour not_allowed)
			(footprints allowed)
		)
		(placement
			(enabled no)
			(sheetname "")
		)
		(fill yes
			(thermal_gap 0.5)
			(thermal_bridge_width 0.5)
			(island_removal_mode 0)
		)
		(polygon
			(pts
				(arc
					(start 54.458108 -403.883876)
					(mid 53.754528 -403.883876)
					(end 54.458108 -403.883876)
				)
			)
		)
	)
	(zone
		(layers "B.Cu" "In13.Cu" "In15.Cu")
		(hatch none 0.5)
		(connect_pads
			(clearance 0)
		)
		(min_thickness 0.25)
		(keepout
			(tracks not_allowed)
			(vias allowed)
			(pads allowed)
			(copperpour not_allowed)
			(footprints allowed)
		)
		(placement
			(enabled no)
			(sheetname "")
		)
		(fill yes
			(thermal_gap 0.5)
			(thermal_bridge_width 0.5)
			(island_removal_mode 0)
		)
		(polygon
			(pts
				(arc
					(start 265.055604 -221.116652)
					(mid 264.402824 -221.116652)
					(end 265.055604 -221.116652)
				)
			)
		)
	)
	(zone
		(layers "B.Cu" "In13.Cu" "In15.Cu")
		(hatch none 0.5)
		(connect_pads
			(clearance 0)
		)
		(min_thickness 0.25)
		(keepout
			(tracks not_allowed)
			(vias allowed)
			(pads allowed)
			(copperpour not_allowed)
			(footprints allowed)
		)
		(placement
			(enabled no)
			(sheetname "")
		)
		(fill yes
			(thermal_gap 0.5)
			(thermal_bridge_width 0.5)
			(island_removal_mode 0)
		)
		(polygon
			(pts
				(arc
					(start 374.113806 -260.430772)
					(mid 373.461026 -260.430772)
					(end 374.113806 -260.430772)
				)
			)
		)
	)
	(zone
		(layers "B.Cu" "In13.Cu" "In15.Cu")
		(hatch none 0.5)
		(connect_pads
			(clearance 0)
		)
		(min_thickness 0.25)
		(keepout
			(tracks not_allowed)
			(vias allowed)
			(pads allowed)
			(copperpour not_allowed)
			(footprints allowed)
		)
		(placement
			(enabled no)
			(sheetname "")
		)
		(fill yes
			(thermal_gap 0.5)
			(thermal_bridge_width 0.5)
			(island_removal_mode 0)
		)
		(polygon
			(pts
				(arc
					(start 338.05495 -430.689766)
					(mid 337.245198 -430.689766)
					(end 338.05495 -430.689766)
				)
			)
		)
	)
	(zone
		(layers "B.Cu" "In13.Cu" "In15.Cu")
		(hatch none 0.5)
		(connect_pads
			(clearance 0)
		)
		(min_thickness 0.25)
		(keepout
			(tracks not_allowed)
			(vias allowed)
			(pads allowed)
			(copperpour not_allowed)
			(footprints allowed)
		)
		(placement
			(enabled no)
			(sheetname "")
		)
		(fill yes
			(thermal_gap 0.5)
			(thermal_bridge_width 0.5)
			(island_removal_mode 0)
		)
		(polygon
			(pts
				(arc
					(start 427.664372 -4.95173)
					(mid 426.960792 -4.95173)
					(end 427.664372 -4.95173)
				)
			)
		)
	)
	(zone
		(layers "B.Cu" "In13.Cu" "In15.Cu")
		(hatch none 0.5)
		(connect_pads
			(clearance 0)
		)
		(min_thickness 0.25)
		(keepout
			(tracks not_allowed)
			(vias allowed)
			(pads allowed)
			(copperpour not_allowed)
			(footprints allowed)
		)
		(placement
			(enabled no)
			(sheetname "")
		)
		(fill yes
			(thermal_gap 0.5)
			(thermal_bridge_width 0.5)
			(island_removal_mode 0)
		)
		(polygon
			(pts
				(arc
					(start 87.172038 -284.033722)
					(mid 86.519258 -284.033722)
					(end 87.172038 -284.033722)
				)
			)
		)
	)
	(zone
		(layers "B.Cu" "In13.Cu" "In15.Cu")
		(hatch none 0.5)
		(connect_pads
			(clearance 0)
		)
		(min_thickness 0.25)
		(keepout
			(tracks not_allowed)
			(vias allowed)
			(pads allowed)
			(copperpour not_allowed)
			(footprints allowed)
		)
		(placement
			(enabled no)
			(sheetname "")
		)
		(fill yes
			(thermal_gap 0.5)
			(thermal_bridge_width 0.5)
			(island_removal_mode 0)
		)
		(polygon
			(pts
				(arc
					(start 400.144234 -4.95173)
					(mid 399.440654 -4.95173)
					(end 400.144234 -4.95173)
				)
			)
		)
	)
	(zone
		(layers "B.Cu" "In13.Cu" "In15.Cu")
		(hatch none 0.5)
		(connect_pads
			(clearance 0)
		)
		(min_thickness 0.25)
		(keepout
			(tracks not_allowed)
			(vias allowed)
			(pads allowed)
			(copperpour not_allowed)
			(footprints allowed)
		)
		(placement
			(enabled no)
			(sheetname "")
		)
		(fill yes
			(thermal_gap 0.5)
			(thermal_bridge_width 0.5)
			(island_removal_mode 0)
		)
		(polygon
			(pts
				(arc
					(start 374.47347 -226.831144)
					(mid 373.82069 -226.831144)
					(end 374.47347 -226.831144)
				)
			)
		)
	)
	(zone
		(layers "B.Cu" "In13.Cu" "In15.Cu")
		(hatch none 0.5)
		(connect_pads
			(clearance 0)
		)
		(min_thickness 0.25)
		(keepout
			(tracks not_allowed)
			(vias allowed)
			(pads allowed)
			(copperpour not_allowed)
			(footprints allowed)
		)
		(placement
			(enabled no)
			(sheetname "")
		)
		(fill yes
			(thermal_gap 0.5)
			(thermal_bridge_width 0.5)
			(island_removal_mode 0)
		)
		(polygon
			(pts
				(arc
					(start 71.054976 -430.889918)
					(mid 70.245224 -430.889918)
					(end 71.054976 -430.889918)
				)
			)
		)
	)
	(zone
		(layers "B.Cu" "In13.Cu" "In15.Cu")
		(hatch none 0.5)
		(connect_pads
			(clearance 0)
		)
		(min_thickness 0.25)
		(keepout
			(tracks not_allowed)
			(vias allowed)
			(pads allowed)
			(copperpour not_allowed)
			(footprints allowed)
		)
		(placement
			(enabled no)
			(sheetname "")
		)
		(fill yes
			(thermal_gap 0.5)
			(thermal_bridge_width 0.5)
			(island_removal_mode 0)
		)
		(polygon
			(pts
				(arc
					(start 375.70156 -403.883876)
					(mid 374.99798 -403.883876)
					(end 375.70156 -403.883876)
				)
			)
		)
	)
	(zone
		(layers "B.Cu" "In13.Cu" "In15.Cu")
		(hatch none 0.5)
		(connect_pads
			(clearance 0)
		)
		(min_thickness 0.25)
		(keepout
			(tracks not_allowed)
			(vias allowed)
			(pads allowed)
			(copperpour not_allowed)
			(footprints allowed)
		)
		(placement
			(enabled no)
			(sheetname "")
		)
		(fill yes
			(thermal_gap 0.5)
			(thermal_bridge_width 0.5)
			(island_removal_mode 0)
		)
		(polygon
			(pts
				(arc
					(start 17.115536 -252.566678)
					(mid 16.462756 -252.566678)
					(end 17.115536 -252.566678)
				)
			)
		)
	)
	(zone
		(layers "B.Cu" "In13.Cu" "In15.Cu")
		(hatch none 0.5)
		(connect_pads
			(clearance 0)
		)
		(min_thickness 0.25)
		(keepout
			(tracks not_allowed)
			(vias allowed)
			(pads allowed)
			(copperpour not_allowed)
			(footprints allowed)
		)
		(placement
			(enabled no)
			(sheetname "")
		)
		(fill yes
			(thermal_gap 0.5)
			(thermal_bridge_width 0.5)
			(island_removal_mode 0)
		)
		(polygon
			(pts
				(arc
					(start 210.841336 -267.866622)
					(mid 210.188556 -267.866622)
					(end 210.841336 -267.866622)
				)
			)
		)
	)
	(zone
		(layers "B.Cu" "In13.Cu" "In15.Cu")
		(hatch none 0.5)
		(connect_pads
			(clearance 0)
		)
		(min_thickness 0.25)
		(keepout
			(tracks not_allowed)
			(vias allowed)
			(pads allowed)
			(copperpour not_allowed)
			(footprints allowed)
		)
		(placement
			(enabled no)
			(sheetname "")
		)
		(fill yes
			(thermal_gap 0.5)
			(thermal_bridge_width 0.5)
			(island_removal_mode 0)
		)
		(polygon
			(pts
				(arc
					(start 85.954108 -403.883876)
					(mid 85.250528 -403.883876)
					(end 85.954108 -403.883876)
				)
			)
		)
	)
	(zone
		(layers "B.Cu" "In13.Cu" "In15.Cu")
		(hatch none 0.5)
		(connect_pads
			(clearance 0)
		)
		(min_thickness 0.25)
		(keepout
			(tracks not_allowed)
			(vias allowed)
			(pads allowed)
			(copperpour not_allowed)
			(footprints allowed)
		)
		(placement
			(enabled no)
			(sheetname "")
		)
		(fill yes
			(thermal_gap 0.5)
			(thermal_bridge_width 0.5)
			(island_removal_mode 0)
		)
		(polygon
			(pts
				(arc
					(start 451.237604 -294.216582)
					(mid 450.584824 -294.216582)
					(end 451.237604 -294.216582)
				)
			)
		)
	)
	(zone
		(layers "B.Cu" "In13.Cu" "In15.Cu")
		(hatch none 0.5)
		(connect_pads
			(clearance 0)
		)
		(min_thickness 0.25)
		(keepout
			(tracks not_allowed)
			(vias allowed)
			(pads allowed)
			(copperpour not_allowed)
			(footprints allowed)
		)
		(placement
			(enabled no)
			(sheetname "")
		)
		(fill yes
			(thermal_gap 0.5)
			(thermal_bridge_width 0.5)
			(island_removal_mode 0)
		)
		(polygon
			(pts
				(arc
					(start 405.47036 -403.883876)
					(mid 404.76678 -403.883876)
					(end 405.47036 -403.883876)
				)
			)
		)
	)
	(zone
		(layers "B.Cu" "In13.Cu" "In15.Cu")
		(hatch none 0.5)
		(connect_pads
			(clearance 0)
		)
		(min_thickness 0.25)
		(keepout
			(tracks not_allowed)
			(vias allowed)
			(pads allowed)
			(copperpour not_allowed)
			(footprints allowed)
		)
		(placement
			(enabled no)
			(sheetname "")
		)
		(fill yes
			(thermal_gap 0.5)
			(thermal_bridge_width 0.5)
			(island_removal_mode 0)
		)
		(polygon
			(pts
				(arc
					(start 399.154904 -427.289976)
					(mid 398.345152 -427.289976)
					(end 399.154904 -427.289976)
				)
			)
		)
	)
	(zone
		(layers "B.Cu" "In13.Cu" "In15.Cu")
		(hatch none 0.5)
		(connect_pads
			(clearance 0)
		)
		(min_thickness 0.25)
		(keepout
			(tracks not_allowed)
			(vias allowed)
			(pads allowed)
			(copperpour not_allowed)
			(footprints allowed)
		)
		(placement
			(enabled no)
			(sheetname "")
		)
		(fill yes
			(thermal_gap 0.5)
			(thermal_bridge_width 0.5)
			(island_removal_mode 0)
		)
		(polygon
			(pts
				(arc
					(start 343.300558 -410.030168)
					(mid 342.596978 -410.030168)
					(end 343.300558 -410.030168)
				)
			)
		)
	)
	(zone
		(layers "B.Cu" "In13.Cu" "In15.Cu")
		(hatch none 0.5)
		(connect_pads
			(clearance 0)
		)
		(min_thickness 0.25)
		(keepout
			(tracks not_allowed)
			(vias allowed)
			(pads allowed)
			(copperpour not_allowed)
			(footprints allowed)
		)
		(placement
			(enabled no)
			(sheetname "")
		)
		(fill yes
			(thermal_gap 0.5)
			(thermal_bridge_width 0.5)
			(island_removal_mode 0)
		)
		(polygon
			(pts
				(arc
					(start 372.124224 -240.667286)
					(mid 371.471444 -240.667286)
					(end 372.124224 -240.667286)
				)
			)
		)
	)
	(zone
		(layers "B.Cu" "In13.Cu" "In15.Cu")
		(hatch none 0.5)
		(connect_pads
			(clearance 0)
		)
		(min_thickness 0.25)
		(keepout
			(tracks not_allowed)
			(vias allowed)
			(pads allowed)
			(copperpour not_allowed)
			(footprints allowed)
		)
		(placement
			(enabled no)
			(sheetname "")
		)
		(fill yes
			(thermal_gap 0.5)
			(thermal_bridge_width 0.5)
			(island_removal_mode 0)
		)
		(polygon
			(pts
				(arc
					(start 269.155672 -216.016586)
					(mid 268.502892 -216.016586)
					(end 269.155672 -216.016586)
				)
			)
		)
	)
	(zone
		(layers "B.Cu" "In13.Cu" "In15.Cu")
		(hatch none 0.5)
		(connect_pads
			(clearance 0)
		)
		(min_thickness 0.25)
		(keepout
			(tracks not_allowed)
			(vias allowed)
			(pads allowed)
			(copperpour not_allowed)
			(footprints allowed)
		)
		(placement
			(enabled no)
			(sheetname "")
		)
		(fill yes
			(thermal_gap 0.5)
			(thermal_bridge_width 0.5)
			(island_removal_mode 0)
		)
		(polygon
			(pts
				(arc
					(start 163.392104 -403.883876)
					(mid 162.688524 -403.883876)
					(end 163.392104 -403.883876)
				)
			)
		)
	)
	(zone
		(layers "B.Cu" "In13.Cu" "In15.Cu")
		(hatch none 0.5)
		(connect_pads
			(clearance 0)
		)
		(min_thickness 0.25)
		(keepout
			(tracks not_allowed)
			(vias allowed)
			(pads allowed)
			(copperpour not_allowed)
			(footprints allowed)
		)
		(placement
			(enabled no)
			(sheetname "")
		)
		(fill yes
			(thermal_gap 0.5)
			(thermal_bridge_width 0.5)
			(island_removal_mode 0)
		)
		(polygon
			(pts
				(arc
					(start 125.123956 -242.294918)
					(mid 124.471176 -242.294918)
					(end 125.123956 -242.294918)
				)
			)
		)
	)
	(zone
		(layers "B.Cu" "In13.Cu" "In15.Cu")
		(hatch none 0.5)
		(connect_pads
			(clearance 0)
		)
		(min_thickness 0.25)
		(keepout
			(tracks not_allowed)
			(vias allowed)
			(pads allowed)
			(copperpour not_allowed)
			(footprints allowed)
		)
		(placement
			(enabled no)
			(sheetname "")
		)
		(fill yes
			(thermal_gap 0.5)
			(thermal_bridge_width 0.5)
			(island_removal_mode 0)
		)
		(polygon
			(pts
				(arc
					(start 65.054988 -430.689766)
					(mid 64.245236 -430.689766)
					(end 65.054988 -430.689766)
				)
			)
		)
	)
	(zone
		(layers "B.Cu" "In13.Cu" "In15.Cu")
		(hatch none 0.5)
		(connect_pads
			(clearance 0)
		)
		(min_thickness 0.25)
		(keepout
			(tracks not_allowed)
			(vias allowed)
			(pads allowed)
			(copperpour not_allowed)
			(footprints allowed)
		)
		(placement
			(enabled no)
			(sheetname "")
		)
		(fill yes
			(thermal_gap 0.5)
			(thermal_bridge_width 0.5)
			(island_removal_mode 0)
		)
		(polygon
			(pts
				(arc
					(start 269.155672 -272.116804)
					(mid 268.502892 -272.116804)
					(end 269.155672 -272.116804)
				)
			)
		)
	)
	(zone
		(layers "B.Cu" "In13.Cu" "In15.Cu")
		(hatch none 0.5)
		(connect_pads
			(clearance 0)
		)
		(min_thickness 0.25)
		(keepout
			(tracks not_allowed)
			(vias allowed)
			(pads allowed)
			(copperpour not_allowed)
			(footprints allowed)
		)
		(placement
			(enabled no)
			(sheetname "")
		)
		(fill yes
			(thermal_gap 0.5)
			(thermal_bridge_width 0.5)
			(island_removal_mode 0)
		)
		(polygon
			(pts
				(arc
					(start 349.208852 -257.98907)
					(mid 348.556072 -257.98907)
					(end 349.208852 -257.98907)
				)
			)
		)
	)
	(zone
		(layers "B.Cu" "In13.Cu" "In15.Cu")
		(hatch none 0.5)
		(connect_pads
			(clearance 0)
		)
		(min_thickness 0.25)
		(keepout
			(tracks not_allowed)
			(vias allowed)
			(pads allowed)
			(copperpour not_allowed)
			(footprints allowed)
		)
		(placement
			(enabled no)
			(sheetname "")
		)
		(fill yes
			(thermal_gap 0.5)
			(thermal_bridge_width 0.5)
			(island_removal_mode 0)
		)
		(polygon
			(pts
				(arc
					(start 17.115536 -286.56661)
					(mid 16.462756 -286.56661)
					(end 17.115536 -286.56661)
				)
			)
		)
	)
	(zone
		(layers "B.Cu" "In13.Cu" "In15.Cu")
		(hatch none 0.5)
		(connect_pads
			(clearance 0)
		)
		(min_thickness 0.25)
		(keepout
			(tracks not_allowed)
			(vias allowed)
			(pads allowed)
			(copperpour not_allowed)
			(footprints allowed)
		)
		(placement
			(enabled no)
			(sheetname "")
		)
		(fill yes
			(thermal_gap 0.5)
			(thermal_bridge_width 0.5)
			(island_removal_mode 0)
		)
		(polygon
			(pts
				(arc
					(start 124.294138 -260.430772)
					(mid 123.641358 -260.430772)
					(end 124.294138 -260.430772)
				)
			)
		)
	)
	(zone
		(layers "B.Cu" "In13.Cu" "In15.Cu")
		(hatch none 0.5)
		(connect_pads
			(clearance 0)
		)
		(min_thickness 0.25)
		(keepout
			(tracks not_allowed)
			(vias allowed)
			(pads allowed)
			(copperpour not_allowed)
			(footprints allowed)
		)
		(placement
			(enabled no)
			(sheetname "")
		)
		(fill yes
			(thermal_gap 0.5)
			(thermal_bridge_width 0.5)
			(island_removal_mode 0)
		)
		(polygon
			(pts
				(arc
					(start 344.040206 -281.59202)
					(mid 343.387426 -281.59202)
					(end 344.040206 -281.59202)
				)
			)
		)
	)
	(zone
		(layers "B.Cu" "In15.Cu")
		(hatch none 0.5)
		(connect_pads
			(clearance 0)
		)
		(min_thickness 0.25)
		(keepout
			(tracks not_allowed)
			(vias allowed)
			(pads allowed)
			(copperpour not_allowed)
			(footprints allowed)
		)
		(placement
			(enabled no)
			(sheetname "")
		)
		(fill yes
			(thermal_gap 0.5)
			(thermal_bridge_width 0.5)
			(island_removal_mode 0)
		)
		(polygon
			(pts
				(arc
					(start 67.054984 -438.089802)
					(mid 66.245232 -438.089802)
					(end 67.054984 -438.089802)
				)
			)
		)
	)
	(zone
		(layers "B.Cu" "In15.Cu")
		(hatch none 0.5)
		(connect_pads
			(clearance 0)
		)
		(min_thickness 0.25)
		(keepout
			(tracks not_allowed)
			(vias allowed)
			(pads allowed)
			(copperpour not_allowed)
			(footprints allowed)
		)
		(placement
			(enabled no)
			(sheetname "")
		)
		(fill yes
			(thermal_gap 0.5)
			(thermal_bridge_width 0.5)
			(island_removal_mode 0)
		)
		(polygon
			(pts
				(arc
					(start 350.508824 -221.133924)
					(mid 349.856044 -221.133924)
					(end 350.508824 -221.133924)
				)
			)
		)
	)
	(zone
		(layers "B.Cu" "In15.Cu")
		(hatch none 0.5)
		(connect_pads
			(clearance 0)
		)
		(min_thickness 0.25)
		(keepout
			(tracks not_allowed)
			(vias allowed)
			(pads allowed)
			(copperpour not_allowed)
			(footprints allowed)
		)
		(placement
			(enabled no)
			(sheetname "")
		)
		(fill yes
			(thermal_gap 0.5)
			(thermal_bridge_width 0.5)
			(island_removal_mode 0)
		)
		(polygon
			(pts
				(arc
					(start 409.154884 -434.289962)
					(mid 408.345132 -434.289962)
					(end 409.154884 -434.289962)
				)
			)
		)
	)
	(zone
		(layers "B.Cu" "In15.Cu")
		(hatch none 0.5)
		(connect_pads
			(clearance 0)
		)
		(min_thickness 0.25)
		(keepout
			(tracks not_allowed)
			(vias allowed)
			(pads allowed)
			(copperpour not_allowed)
			(footprints allowed)
		)
		(placement
			(enabled no)
			(sheetname "")
		)
		(fill yes
			(thermal_gap 0.5)
			(thermal_bridge_width 0.5)
			(island_removal_mode 0)
		)
		(polygon
			(pts
				(arc
					(start 132.15493 -434.289962)
					(mid 131.345178 -434.289962)
					(end 132.15493 -434.289962)
				)
			)
		)
	)
	(zone
		(layers "B.Cu" "In15.Cu")
		(hatch none 0.5)
		(connect_pads
			(clearance 0)
		)
		(min_thickness 0.25)
		(keepout
			(tracks not_allowed)
			(vias allowed)
			(pads allowed)
			(copperpour not_allowed)
			(footprints allowed)
		)
		(placement
			(enabled no)
			(sheetname "")
		)
		(fill yes
			(thermal_gap 0.5)
			(thermal_bridge_width 0.5)
			(island_removal_mode 0)
		)
		(polygon
			(pts
				(arc
					(start 342.990424 -221.133924)
					(mid 342.337644 -221.133924)
					(end 342.990424 -221.133924)
				)
			)
		)
	)
	(zone
		(layers "B.Cu" "In15.Cu")
		(hatch none 0.5)
		(connect_pads
			(clearance 0)
		)
		(min_thickness 0.25)
		(keepout
			(tracks not_allowed)
			(vias allowed)
			(pads allowed)
			(copperpour not_allowed)
			(footprints allowed)
		)
		(placement
			(enabled no)
			(sheetname "")
		)
		(fill yes
			(thermal_gap 0.5)
			(thermal_bridge_width 0.5)
			(island_removal_mode 0)
		)
		(polygon
			(pts
				(arc
					(start 372.59387 -220.319854)
					(mid 371.94109 -220.319854)
					(end 372.59387 -220.319854)
				)
			)
		)
	)
	(zone
		(layers "B.Cu" "In15.Cu")
		(hatch none 0.5)
		(connect_pads
			(clearance 0)
		)
		(min_thickness 0.25)
		(keepout
			(tracks not_allowed)
			(vias allowed)
			(pads allowed)
			(copperpour not_allowed)
			(footprints allowed)
		)
		(placement
			(enabled no)
			(sheetname "")
		)
		(fill yes
			(thermal_gap 0.5)
			(thermal_bridge_width 0.5)
			(island_removal_mode 0)
		)
		(polygon
			(pts
				(arc
					(start 133.582156 -221.133924)
					(mid 132.929376 -221.133924)
					(end 133.582156 -221.133924)
				)
			)
		)
	)
	(zone
		(layers "B.Cu" "In15.Cu")
		(hatch none 0.5)
		(connect_pads
			(clearance 0)
		)
		(min_thickness 0.25)
		(keepout
			(tracks not_allowed)
			(vias allowed)
			(pads allowed)
			(copperpour not_allowed)
			(footprints allowed)
		)
		(placement
			(enabled no)
			(sheetname "")
		)
		(fill yes
			(thermal_gap 0.5)
			(thermal_bridge_width 0.5)
			(island_removal_mode 0)
		)
		(polygon
			(pts
				(arc
					(start 133.112002 -221.94774)
					(mid 132.459222 -221.94774)
					(end 133.112002 -221.94774)
				)
			)
		)
	)
	(zone
		(layers "B.Cu" "In15.Cu")
		(hatch none 0.5)
		(connect_pads
			(clearance 0)
		)
		(min_thickness 0.25)
		(keepout
			(tracks not_allowed)
			(vias allowed)
			(pads allowed)
			(copperpour not_allowed)
			(footprints allowed)
		)
		(placement
			(enabled no)
			(sheetname "")
		)
		(fill yes
			(thermal_gap 0.5)
			(thermal_bridge_width 0.5)
			(island_removal_mode 0)
		)
		(polygon
			(pts
				(arc
					(start 102.098602 -220.319854)
					(mid 101.445822 -220.319854)
					(end 102.098602 -220.319854)
				)
			)
		)
	)
	(zone
		(layers "B.Cu" "In15.Cu")
		(hatch none 0.5)
		(connect_pads
			(clearance 0)
		)
		(min_thickness 0.25)
		(keepout
			(tracks not_allowed)
			(vias allowed)
			(pads allowed)
			(copperpour not_allowed)
			(footprints allowed)
		)
		(placement
			(enabled no)
			(sheetname "")
		)
		(fill yes
			(thermal_gap 0.5)
			(thermal_bridge_width 0.5)
			(island_removal_mode 0)
		)
		(polygon
			(pts
				(arc
					(start 340.171024 -221.133924)
					(mid 339.518244 -221.133924)
					(end 340.171024 -221.133924)
				)
			)
		)
	)
	(zone
		(layers "B.Cu" "In15.Cu")
		(hatch none 0.5)
		(connect_pads
			(clearance 0)
		)
		(min_thickness 0.25)
		(keepout
			(tracks not_allowed)
			(vias allowed)
			(pads allowed)
			(copperpour not_allowed)
			(footprints allowed)
		)
		(placement
			(enabled no)
			(sheetname "")
		)
		(fill yes
			(thermal_gap 0.5)
			(thermal_bridge_width 0.5)
			(island_removal_mode 0)
		)
		(polygon
			(pts
				(arc
					(start 344.054938 -436.889906)
					(mid 343.245186 -436.889906)
					(end 344.054938 -436.889906)
				)
			)
		)
	)
	(zone
		(layers "B.Cu" "In15.Cu")
		(hatch none 0.5)
		(connect_pads
			(clearance 0)
		)
		(min_thickness 0.25)
		(keepout
			(tracks not_allowed)
			(vias allowed)
			(pads allowed)
			(copperpour not_allowed)
			(footprints allowed)
		)
		(placement
			(enabled no)
			(sheetname "")
		)
		(fill yes
			(thermal_gap 0.5)
			(thermal_bridge_width 0.5)
			(island_removal_mode 0)
		)
		(polygon
			(pts
				(arc
					(start 80.054958 -436.889906)
					(mid 79.245206 -436.889906)
					(end 80.054958 -436.889906)
				)
			)
		)
	)
	(zone
		(layers "B.Cu" "In15.Cu")
		(hatch none 0.5)
		(connect_pads
			(clearance 0)
		)
		(min_thickness 0.25)
		(keepout
			(tracks not_allowed)
			(vias allowed)
			(pads allowed)
			(copperpour not_allowed)
			(footprints allowed)
		)
		(placement
			(enabled no)
			(sheetname "")
		)
		(fill yes
			(thermal_gap 0.5)
			(thermal_bridge_width 0.5)
			(island_removal_mode 0)
		)
		(polygon
			(pts
				(arc
					(start 405.154892 -435.489858)
					(mid 404.34514 -435.489858)
					(end 405.154892 -435.489858)
				)
			)
		)
	)
	(zone
		(layers "B.Cu" "In15.Cu")
		(hatch none 0.5)
		(connect_pads
			(clearance 0)
		)
		(min_thickness 0.25)
		(keepout
			(tracks not_allowed)
			(vias allowed)
			(pads allowed)
			(copperpour not_allowed)
			(footprints allowed)
		)
		(placement
			(enabled no)
			(sheetname "")
		)
		(fill yes
			(thermal_gap 0.5)
			(thermal_bridge_width 0.5)
			(island_removal_mode 0)
		)
		(polygon
			(pts
				(arc
					(start 369.304824 -221.133924)
					(mid 368.652044 -221.133924)
					(end 369.304824 -221.133924)
				)
			)
		)
	)
	(zone
		(layers "B.Cu" "In15.Cu")
		(hatch none 0.5)
		(connect_pads
			(clearance 0)
		)
		(min_thickness 0.25)
		(keepout
			(tracks not_allowed)
			(vias allowed)
			(pads allowed)
			(copperpour not_allowed)
			(footprints allowed)
		)
		(placement
			(enabled no)
			(sheetname "")
		)
		(fill yes
			(thermal_gap 0.5)
			(thermal_bridge_width 0.5)
			(island_removal_mode 0)
		)
		(polygon
			(pts
				(arc
					(start 370.71427 -220.319854)
					(mid 370.06149 -220.319854)
					(end 370.71427 -220.319854)
				)
			)
		)
	)
	(zone
		(layers "B.Cu" "In15.Cu")
		(hatch none 0.5)
		(connect_pads
			(clearance 0)
		)
		(min_thickness 0.25)
		(keepout
			(tracks not_allowed)
			(vias allowed)
			(pads allowed)
			(copperpour not_allowed)
			(footprints allowed)
		)
		(placement
			(enabled no)
			(sheetname "")
		)
		(fill yes
			(thermal_gap 0.5)
			(thermal_bridge_width 0.5)
			(island_removal_mode 0)
		)
		(polygon
			(pts
				(arc
					(start 124.184156 -221.133924)
					(mid 123.531376 -221.133924)
					(end 124.184156 -221.133924)
				)
			)
		)
	)
	(zone
		(layers "B.Cu" "In15.Cu")
		(hatch none 0.5)
		(connect_pads
			(clearance 0)
		)
		(min_thickness 0.25)
		(keepout
			(tracks not_allowed)
			(vias allowed)
			(pads allowed)
			(copperpour not_allowed)
			(footprints allowed)
		)
		(placement
			(enabled no)
			(sheetname "")
		)
		(fill yes
			(thermal_gap 0.5)
			(thermal_bridge_width 0.5)
			(island_removal_mode 0)
		)
		(polygon
			(pts
				(arc
					(start 78.054962 -439.0898)
					(mid 77.24521 -439.0898)
					(end 78.054962 -439.0898)
				)
			)
		)
	)
	(zone
		(layers "B.Cu" "In15.Cu")
		(hatch none 0.5)
		(connect_pads
			(clearance 0)
		)
		(min_thickness 0.25)
		(keepout
			(tracks not_allowed)
			(vias allowed)
			(pads allowed)
			(copperpour not_allowed)
			(footprints allowed)
		)
		(placement
			(enabled no)
			(sheetname "")
		)
		(fill yes
			(thermal_gap 0.5)
			(thermal_bridge_width 0.5)
			(island_removal_mode 0)
		)
		(polygon
			(pts
				(arc
					(start 131.232402 -221.94774)
					(mid 130.579622 -221.94774)
					(end 131.232402 -221.94774)
				)
			)
		)
	)
	(zone
		(layers "B.Cu" "In15.Cu")
		(hatch none 0.5)
		(connect_pads
			(clearance 0)
		)
		(min_thickness 0.25)
		(keepout
			(tracks not_allowed)
			(vias allowed)
			(pads allowed)
			(copperpour not_allowed)
			(footprints allowed)
		)
		(placement
			(enabled no)
			(sheetname "")
		)
		(fill yes
			(thermal_gap 0.5)
			(thermal_bridge_width 0.5)
			(island_removal_mode 0)
		)
		(polygon
			(pts
				(arc
					(start 182.393082 -53.091334)
					(mid 181.689502 -53.091334)
					(end 182.393082 -53.091334)
				)
			)
		)
	)
	(zone
		(layers "B.Cu" "In15.Cu")
		(hatch none 0.5)
		(connect_pads
			(clearance 0)
		)
		(min_thickness 0.25)
		(keepout
			(tracks not_allowed)
			(vias allowed)
			(pads allowed)
			(copperpour not_allowed)
			(footprints allowed)
		)
		(placement
			(enabled no)
			(sheetname "")
		)
		(fill yes
			(thermal_gap 0.5)
			(thermal_bridge_width 0.5)
			(island_removal_mode 0)
		)
		(polygon
			(pts
				(arc
					(start 374.943624 -221.133924)
					(mid 374.290844 -221.133924)
					(end 374.943624 -221.133924)
				)
			)
		)
	)
	(zone
		(layers "B.Cu" "In15.Cu")
		(hatch none 0.5)
		(connect_pads
			(clearance 0)
		)
		(min_thickness 0.25)
		(keepout
			(tracks not_allowed)
			(vias allowed)
			(pads allowed)
			(copperpour not_allowed)
			(footprints allowed)
		)
		(placement
			(enabled no)
			(sheetname "")
		)
		(fill yes
			(thermal_gap 0.5)
			(thermal_bridge_width 0.5)
			(island_removal_mode 0)
		)
		(polygon
			(pts
				(arc
					(start 349.09887 -221.94774)
					(mid 348.44609 -221.94774)
					(end 349.09887 -221.94774)
				)
			)
		)
	)
	(zone
		(layers "B.Cu" "In15.Cu")
		(hatch none 0.5)
		(connect_pads
			(clearance 0)
		)
		(min_thickness 0.25)
		(keepout
			(tracks not_allowed)
			(vias allowed)
			(pads allowed)
			(copperpour not_allowed)
			(footprints allowed)
		)
		(placement
			(enabled no)
			(sheetname "")
		)
		(fill yes
			(thermal_gap 0.5)
			(thermal_bridge_width 0.5)
			(island_removal_mode 0)
		)
		(polygon
			(pts
				(arc
					(start 381.992124 -220.319854)
					(mid 381.339344 -220.319854)
					(end 381.992124 -220.319854)
				)
			)
		)
	)
	(zone
		(layers "B.Cu" "In15.Cu")
		(hatch none 0.5)
		(connect_pads
			(clearance 0)
		)
		(min_thickness 0.25)
		(keepout
			(tracks not_allowed)
			(vias allowed)
			(pads allowed)
			(copperpour not_allowed)
			(footprints allowed)
		)
		(placement
			(enabled no)
			(sheetname "")
		)
		(fill yes
			(thermal_gap 0.5)
			(thermal_bridge_width 0.5)
			(island_removal_mode 0)
		)
		(polygon
			(pts
				(arc
					(start 379.17247 -221.94774)
					(mid 378.51969 -221.94774)
					(end 379.17247 -221.94774)
				)
			)
		)
	)
	(zone
		(layers "B.Cu" "In15.Cu")
		(hatch none 0.5)
		(connect_pads
			(clearance 0)
		)
		(min_thickness 0.25)
		(keepout
			(tracks not_allowed)
			(vias allowed)
			(pads allowed)
			(copperpour not_allowed)
			(footprints allowed)
		)
		(placement
			(enabled no)
			(sheetname "")
		)
		(fill yes
			(thermal_gap 0.5)
			(thermal_bridge_width 0.5)
			(island_removal_mode 0)
		)
		(polygon
			(pts
				(arc
					(start 350.97847 -221.94774)
					(mid 350.32569 -221.94774)
					(end 350.97847 -221.94774)
				)
			)
		)
	)
	(zone
		(layers "B.Cu" "In15.Cu")
		(hatch none 0.5)
		(connect_pads
			(clearance 0)
		)
		(min_thickness 0.25)
		(keepout
			(tracks not_allowed)
			(vias allowed)
			(pads allowed)
			(copperpour not_allowed)
			(footprints allowed)
		)
		(placement
			(enabled no)
			(sheetname "")
		)
		(fill yes
			(thermal_gap 0.5)
			(thermal_bridge_width 0.5)
			(island_removal_mode 0)
		)
		(polygon
			(pts
				(arc
					(start 321.054984 -437.889904)
					(mid 320.245232 -437.889904)
					(end 321.054984 -437.889904)
				)
			)
		)
	)
	(zone
		(layers "B.Cu" "In15.Cu")
		(hatch none 0.5)
		(connect_pads
			(clearance 0)
		)
		(min_thickness 0.25)
		(keepout
			(tracks not_allowed)
			(vias allowed)
			(pads allowed)
			(copperpour not_allowed)
			(footprints allowed)
		)
		(placement
			(enabled no)
			(sheetname "")
		)
		(fill yes
			(thermal_gap 0.5)
			(thermal_bridge_width 0.5)
			(island_removal_mode 0)
		)
		(polygon
			(pts
				(arc
					(start 71.054976 -436.889906)
					(mid 70.245224 -436.889906)
					(end 71.054976 -436.889906)
				)
			)
		)
	)
	(zone
		(layers "B.Cu" "In15.Cu")
		(hatch none 0.5)
		(connect_pads
			(clearance 0)
		)
		(min_thickness 0.25)
		(keepout
			(tracks not_allowed)
			(vias allowed)
			(pads allowed)
			(copperpour not_allowed)
			(footprints allowed)
		)
		(placement
			(enabled no)
			(sheetname "")
		)
		(fill yes
			(thermal_gap 0.5)
			(thermal_bridge_width 0.5)
			(island_removal_mode 0)
		)
		(polygon
			(pts
				(arc
					(start 91.291156 -221.133924)
					(mid 90.638376 -221.133924)
					(end 91.291156 -221.133924)
				)
			)
		)
	)
	(zone
		(layers "B.Cu" "In15.Cu")
		(hatch none 0.5)
		(connect_pads
			(clearance 0)
		)
		(min_thickness 0.25)
		(keepout
			(tracks not_allowed)
			(vias allowed)
			(pads allowed)
			(copperpour not_allowed)
			(footprints allowed)
		)
		(placement
			(enabled no)
			(sheetname "")
		)
		(fill yes
			(thermal_gap 0.5)
			(thermal_bridge_width 0.5)
			(island_removal_mode 0)
		)
		(polygon
			(pts
				(arc
					(start 102.568756 -221.133924)
					(mid 101.915976 -221.133924)
					(end 102.568756 -221.133924)
				)
			)
		)
	)
	(zone
		(layers "B.Cu" "In15.Cu")
		(hatch none 0.5)
		(connect_pads
			(clearance 0)
		)
		(min_thickness 0.25)
		(keepout
			(tracks not_allowed)
			(vias allowed)
			(pads allowed)
			(copperpour not_allowed)
			(footprints allowed)
		)
		(placement
			(enabled no)
			(sheetname "")
		)
		(fill yes
			(thermal_gap 0.5)
			(thermal_bridge_width 0.5)
			(island_removal_mode 0)
		)
		(polygon
			(pts
				(arc
					(start 129.822956 -221.133924)
					(mid 129.170176 -221.133924)
					(end 129.822956 -221.133924)
				)
			)
		)
	)
	(zone
		(layers "B.Cu" "In15.Cu")
		(hatch none 0.5)
		(connect_pads
			(clearance 0)
		)
		(min_thickness 0.25)
		(keepout
			(tracks not_allowed)
			(vias allowed)
			(pads allowed)
			(copperpour not_allowed)
			(footprints allowed)
		)
		(placement
			(enabled no)
			(sheetname "")
		)
		(fill yes
			(thermal_gap 0.5)
			(thermal_bridge_width 0.5)
			(island_removal_mode 0)
		)
		(polygon
			(pts
				(arc
					(start 340.054946 -436.889906)
					(mid 339.245194 -436.889906)
					(end 340.054946 -436.889906)
				)
			)
		)
	)
	(zone
		(layers "B.Cu" "In15.Cu")
		(hatch none 0.5)
		(connect_pads
			(clearance 0)
		)
		(min_thickness 0.25)
		(keepout
			(tracks not_allowed)
			(vias allowed)
			(pads allowed)
			(copperpour not_allowed)
			(footprints allowed)
		)
		(placement
			(enabled no)
			(sheetname "")
		)
		(fill yes
			(thermal_gap 0.5)
			(thermal_bridge_width 0.5)
			(island_removal_mode 0)
		)
		(polygon
			(pts
				(arc
					(start 377.29287 -221.94774)
					(mid 376.64009 -221.94774)
					(end 377.29287 -221.94774)
				)
			)
		)
	)
	(zone
		(layers "B.Cu" "In15.Cu")
		(hatch none 0.5)
		(connect_pads
			(clearance 0)
		)
		(min_thickness 0.25)
		(keepout
			(tracks not_allowed)
			(vias allowed)
			(pads allowed)
			(copperpour not_allowed)
			(footprints allowed)
		)
		(placement
			(enabled no)
			(sheetname "")
		)
		(fill yes
			(thermal_gap 0.5)
			(thermal_bridge_width 0.5)
			(island_removal_mode 0)
		)
		(polygon
			(pts
				(arc
					(start 147.1549 -434.48986)
					(mid 146.345148 -434.48986)
					(end 147.1549 -434.48986)
				)
			)
		)
	)
	(zone
		(layers "B.Cu" "In15.Cu")
		(hatch none 0.5)
		(connect_pads
			(clearance 0)
		)
		(min_thickness 0.25)
		(keepout
			(tracks not_allowed)
			(vias allowed)
			(pads allowed)
			(copperpour not_allowed)
			(footprints allowed)
		)
		(placement
			(enabled no)
			(sheetname "")
		)
		(fill yes
			(thermal_gap 0.5)
			(thermal_bridge_width 0.5)
			(island_removal_mode 0)
		)
		(polygon
			(pts
				(arc
					(start 336.054954 -438.089802)
					(mid 335.245202 -438.089802)
					(end 336.054954 -438.089802)
				)
			)
		)
	)
	(zone
		(layers "B.Cu" "In15.Cu")
		(hatch none 0.5)
		(connect_pads
			(clearance 0)
		)
		(min_thickness 0.25)
		(keepout
			(tracks not_allowed)
			(vias allowed)
			(pads allowed)
			(copperpour not_allowed)
			(footprints allowed)
		)
		(placement
			(enabled no)
			(sheetname "")
		)
		(fill yes
			(thermal_gap 0.5)
			(thermal_bridge_width 0.5)
			(island_removal_mode 0)
		)
		(polygon
			(pts
				(arc
					(start 371.65407 -221.94774)
					(mid 371.00129 -221.94774)
					(end 371.65407 -221.94774)
				)
			)
		)
	)
	(zone
		(layers "B.Cu" "In15.Cu")
		(hatch none 0.5)
		(connect_pads
			(clearance 0)
		)
		(min_thickness 0.25)
		(keepout
			(tracks not_allowed)
			(vias allowed)
			(pads allowed)
			(copperpour not_allowed)
			(footprints allowed)
		)
		(placement
			(enabled no)
			(sheetname "")
		)
		(fill yes
			(thermal_gap 0.5)
			(thermal_bridge_width 0.5)
			(island_removal_mode 0)
		)
		(polygon
			(pts
				(arc
					(start 93.640402 -221.94774)
					(mid 92.987622 -221.94774)
					(end 93.640402 -221.94774)
				)
			)
		)
	)
	(zone
		(layers "B.Cu" "In15.Cu")
		(hatch none 0.5)
		(connect_pads
			(clearance 0)
		)
		(min_thickness 0.25)
		(keepout
			(tracks not_allowed)
			(vias allowed)
			(pads allowed)
			(copperpour not_allowed)
			(footprints allowed)
		)
		(placement
			(enabled no)
			(sheetname "")
		)
		(fill yes
			(thermal_gap 0.5)
			(thermal_bridge_width 0.5)
			(island_removal_mode 0)
		)
		(polygon
			(pts
				(arc
					(start 126.533402 -220.319854)
					(mid 125.880622 -220.319854)
					(end 126.533402 -220.319854)
				)
			)
		)
	)
	(zone
		(layers "B.Cu" "In15.Cu")
		(hatch none 0.5)
		(connect_pads
			(clearance 0)
		)
		(min_thickness 0.25)
		(keepout
			(tracks not_allowed)
			(vias allowed)
			(pads allowed)
			(copperpour not_allowed)
			(footprints allowed)
		)
		(placement
			(enabled no)
			(sheetname "")
		)
		(fill yes
			(thermal_gap 0.5)
			(thermal_bridge_width 0.5)
			(island_removal_mode 0)
		)
		(polygon
			(pts
				(arc
					(start 76.054966 -438.089802)
					(mid 75.245214 -438.089802)
					(end 76.054966 -438.089802)
				)
			)
		)
	)
	(zone
		(layers "B.Cu" "In15.Cu")
		(hatch none 0.5)
		(connect_pads
			(clearance 0)
		)
		(min_thickness 0.25)
		(keepout
			(tracks not_allowed)
			(vias allowed)
			(pads allowed)
			(copperpour not_allowed)
			(footprints allowed)
		)
		(placement
			(enabled no)
			(sheetname "")
		)
		(fill yes
			(thermal_gap 0.5)
			(thermal_bridge_width 0.5)
			(island_removal_mode 0)
		)
		(polygon
			(pts
				(arc
					(start 345.33967 -221.94774)
					(mid 344.68689 -221.94774)
					(end 345.33967 -221.94774)
				)
			)
		)
	)
	(zone
		(layers "B.Cu" "In15.Cu")
		(hatch none 0.5)
		(connect_pads
			(clearance 0)
		)
		(min_thickness 0.25)
		(keepout
			(tracks not_allowed)
			(vias allowed)
			(pads allowed)
			(copperpour not_allowed)
			(footprints allowed)
		)
		(placement
			(enabled no)
			(sheetname "")
		)
		(fill yes
			(thermal_gap 0.5)
			(thermal_bridge_width 0.5)
			(island_removal_mode 0)
		)
		(polygon
			(pts
				(arc
					(start 405.154892 -434.289962)
					(mid 404.34514 -434.289962)
					(end 405.154892 -434.289962)
				)
			)
		)
	)
	(zone
		(layers "B.Cu" "In15.Cu")
		(hatch none 0.5)
		(connect_pads
			(clearance 0)
		)
		(min_thickness 0.25)
		(keepout
			(tracks not_allowed)
			(vias allowed)
			(pads allowed)
			(copperpour not_allowed)
			(footprints allowed)
		)
		(placement
			(enabled no)
			(sheetname "")
		)
		(fill yes
			(thermal_gap 0.5)
			(thermal_bridge_width 0.5)
			(island_removal_mode 0)
		)
		(polygon
			(pts
				(arc
					(start 91.760802 -221.94774)
					(mid 91.108022 -221.94774)
					(end 91.760802 -221.94774)
				)
			)
		)
	)
	(zone
		(layers "B.Cu" "In15.Cu")
		(hatch none 0.5)
		(connect_pads
			(clearance 0)
		)
		(min_thickness 0.25)
		(keepout
			(tracks not_allowed)
			(vias allowed)
			(pads allowed)
			(copperpour not_allowed)
			(footprints allowed)
		)
		(placement
			(enabled no)
			(sheetname "")
		)
		(fill yes
			(thermal_gap 0.5)
			(thermal_bridge_width 0.5)
			(island_removal_mode 0)
		)
		(polygon
			(pts
				(arc
					(start 95.050356 -221.133924)
					(mid 94.397576 -221.133924)
					(end 95.050356 -221.133924)
				)
			)
		)
	)
	(zone
		(layers "B.Cu" "In15.Cu")
		(hatch none 0.5)
		(connect_pads
			(clearance 0)
		)
		(min_thickness 0.25)
		(keepout
			(tracks not_allowed)
			(vias allowed)
			(pads allowed)
			(copperpour not_allowed)
			(footprints allowed)
		)
		(placement
			(enabled no)
			(sheetname "")
		)
		(fill yes
			(thermal_gap 0.5)
			(thermal_bridge_width 0.5)
			(island_removal_mode 0)
		)
		(polygon
			(pts
				(arc
					(start 182.393082 -48.028098)
					(mid 181.689502 -48.028098)
					(end 182.393082 -48.028098)
				)
			)
		)
	)
	(zone
		(layers "B.Cu" "In15.Cu")
		(hatch none 0.5)
		(connect_pads
			(clearance 0)
		)
		(min_thickness 0.25)
		(keepout
			(tracks not_allowed)
			(vias allowed)
			(pads allowed)
			(copperpour not_allowed)
			(footprints allowed)
		)
		(placement
			(enabled no)
			(sheetname "")
		)
		(fill yes
			(thermal_gap 0.5)
			(thermal_bridge_width 0.5)
			(island_removal_mode 0)
		)
		(polygon
			(pts
				(arc
					(start 127.473202 -221.94774)
					(mid 126.820422 -221.94774)
					(end 127.473202 -221.94774)
				)
			)
		)
	)
	(zone
		(layers "B.Cu" "In15.Cu")
		(hatch none 0.5)
		(connect_pads
			(clearance 0)
		)
		(min_thickness 0.25)
		(keepout
			(tracks not_allowed)
			(vias allowed)
			(pads allowed)
			(copperpour not_allowed)
			(footprints allowed)
		)
		(placement
			(enabled no)
			(sheetname "")
		)
		(fill yes
			(thermal_gap 0.5)
			(thermal_bridge_width 0.5)
			(island_removal_mode 0)
		)
		(polygon
			(pts
				(arc
					(start 373.064024 -221.133924)
					(mid 372.411244 -221.133924)
					(end 373.064024 -221.133924)
				)
			)
		)
	)
	(zone
		(layers "B.Cu" "In15.Cu")
		(hatch none 0.5)
		(connect_pads
			(clearance 0)
		)
		(min_thickness 0.25)
		(keepout
			(tracks not_allowed)
			(vias allowed)
			(pads allowed)
			(copperpour not_allowed)
			(footprints allowed)
		)
		(placement
			(enabled no)
			(sheetname "")
		)
		(fill yes
			(thermal_gap 0.5)
			(thermal_bridge_width 0.5)
			(island_removal_mode 0)
		)
		(polygon
			(pts
				(arc
					(start 382.931924 -221.94774)
					(mid 382.279144 -221.94774)
					(end 382.931924 -221.94774)
				)
			)
		)
	)
	(zone
		(layers "B.Cu" "In15.Cu")
		(hatch none 0.5)
		(connect_pads
			(clearance 0)
		)
		(min_thickness 0.25)
		(keepout
			(tracks not_allowed)
			(vias allowed)
			(pads allowed)
			(copperpour not_allowed)
			(footprints allowed)
		)
		(placement
			(enabled no)
			(sheetname "")
		)
		(fill yes
			(thermal_gap 0.5)
			(thermal_bridge_width 0.5)
			(island_removal_mode 0)
		)
		(polygon
			(pts
				(arc
					(start 376.35307 -220.319854)
					(mid 375.70029 -220.319854)
					(end 376.35307 -220.319854)
				)
			)
		)
	)
	(zone
		(layers "B.Cu" "In15.Cu")
		(hatch none 0.5)
		(connect_pads
			(clearance 0)
		)
		(min_thickness 0.25)
		(keepout
			(tracks not_allowed)
			(vias allowed)
			(pads allowed)
			(copperpour not_allowed)
			(footprints allowed)
		)
		(placement
			(enabled no)
			(sheetname "")
		)
		(fill yes
			(thermal_gap 0.5)
			(thermal_bridge_width 0.5)
			(island_removal_mode 0)
		)
		(polygon
			(pts
				(arc
					(start 346.054934 -439.0898)
					(mid 345.245182 -439.0898)
					(end 346.054934 -439.0898)
				)
			)
		)
	)
	(zone
		(layers "B.Cu" "In15.Cu")
		(hatch none 0.5)
		(connect_pads
			(clearance 0)
		)
		(min_thickness 0.25)
		(keepout
			(tracks not_allowed)
			(vias allowed)
			(pads allowed)
			(copperpour not_allowed)
			(footprints allowed)
		)
		(placement
			(enabled no)
			(sheetname "")
		)
		(fill yes
			(thermal_gap 0.5)
			(thermal_bridge_width 0.5)
			(island_removal_mode 0)
		)
		(polygon
			(pts
				(arc
					(start 342.245188 -44.691046)
					(mid 341.592408 -44.691046)
					(end 342.245188 -44.691046)
				)
			)
		)
	)
	(zone
		(layers "B.Cu" "In15.Cu")
		(hatch none 0.5)
		(connect_pads
			(clearance 0)
		)
		(min_thickness 0.25)
		(keepout
			(tracks not_allowed)
			(vias allowed)
			(pads allowed)
			(copperpour not_allowed)
			(footprints allowed)
		)
		(placement
			(enabled no)
			(sheetname "")
		)
		(fill yes
			(thermal_gap 0.5)
			(thermal_bridge_width 0.5)
			(island_removal_mode 0)
		)
		(polygon
			(pts
				(arc
					(start 338.05495 -437.889904)
					(mid 337.245198 -437.889904)
					(end 338.05495 -437.889904)
				)
			)
		)
	)
	(zone
		(layers "B.Cu" "In15.Cu")
		(hatch none 0.5)
		(connect_pads
			(clearance 0)
		)
		(min_thickness 0.25)
		(keepout
			(tracks not_allowed)
			(vias allowed)
			(pads allowed)
			(copperpour not_allowed)
			(footprints allowed)
		)
		(placement
			(enabled no)
			(sheetname "")
		)
		(fill yes
			(thermal_gap 0.5)
			(thermal_bridge_width 0.5)
			(island_removal_mode 0)
		)
		(polygon
			(pts
				(arc
					(start 392.154918 -435.489858)
					(mid 391.345166 -435.489858)
					(end 392.154918 -435.489858)
				)
			)
		)
	)
	(zone
		(layers "B.Cu" "In15.Cu")
		(hatch none 0.5)
		(connect_pads
			(clearance 0)
		)
		(min_thickness 0.25)
		(keepout
			(tracks not_allowed)
			(vias allowed)
			(pads allowed)
			(copperpour not_allowed)
			(footprints allowed)
		)
		(placement
			(enabled no)
			(sheetname "")
		)
		(fill yes
			(thermal_gap 0.5)
			(thermal_bridge_width 0.5)
			(island_removal_mode 0)
		)
		(polygon
			(pts
				(arc
					(start 140.154914 -435.489858)
					(mid 139.345162 -435.489858)
					(end 140.154914 -435.489858)
				)
			)
		)
	)
	(zone
		(layers "B.Cu" "In15.Cu")
		(hatch none 0.5)
		(connect_pads
			(clearance 0)
		)
		(min_thickness 0.25)
		(keepout
			(tracks not_allowed)
			(vias allowed)
			(pads allowed)
			(copperpour not_allowed)
			(footprints allowed)
		)
		(placement
			(enabled no)
			(sheetname "")
		)
		(fill yes
			(thermal_gap 0.5)
			(thermal_bridge_width 0.5)
			(island_removal_mode 0)
		)
		(polygon
			(pts
				(arc
					(start 69.05498 -437.889904)
					(mid 68.245228 -437.889904)
					(end 69.05498 -437.889904)
				)
			)
		)
	)
	(zone
		(layers "B.Cu" "In15.Cu")
		(hatch none 0.5)
		(connect_pads
			(clearance 0)
		)
		(min_thickness 0.25)
		(keepout
			(tracks not_allowed)
			(vias allowed)
			(pads allowed)
			(copperpour not_allowed)
			(footprints allowed)
		)
		(placement
			(enabled no)
			(sheetname "")
		)
		(fill yes
			(thermal_gap 0.5)
			(thermal_bridge_width 0.5)
			(island_removal_mode 0)
		)
		(polygon
			(pts
				(arc
					(start 125.593602 -221.94774)
					(mid 124.940822 -221.94774)
					(end 125.593602 -221.94774)
				)
			)
		)
	)
	(zone
		(layers "B.Cu" "In15.Cu")
		(hatch none 0.5)
		(connect_pads
			(clearance 0)
		)
		(min_thickness 0.25)
		(keepout
			(tracks not_allowed)
			(vias allowed)
			(pads allowed)
			(copperpour not_allowed)
			(footprints allowed)
		)
		(placement
			(enabled no)
			(sheetname "")
		)
		(fill yes
			(thermal_gap 0.5)
			(thermal_bridge_width 0.5)
			(island_removal_mode 0)
		)
		(polygon
			(pts
				(arc
					(start 134.154926 -434.48986)
					(mid 133.345174 -434.48986)
					(end 134.154926 -434.48986)
				)
			)
		)
	)
	(zone
		(layers "B.Cu" "In15.Cu")
		(hatch none 0.5)
		(connect_pads
			(clearance 0)
		)
		(min_thickness 0.25)
		(keepout
			(tracks not_allowed)
			(vias allowed)
			(pads allowed)
			(copperpour not_allowed)
			(footprints allowed)
		)
		(placement
			(enabled no)
			(sheetname "")
		)
		(fill yes
			(thermal_gap 0.5)
			(thermal_bridge_width 0.5)
			(island_removal_mode 0)
		)
		(polygon
			(pts
				(arc
					(start 378.702824 -221.133924)
					(mid 378.050044 -221.133924)
					(end 378.702824 -221.133924)
				)
			)
		)
	)
	(zone
		(layers "B.Cu" "In15.Cu")
		(hatch none 0.5)
		(connect_pads
			(clearance 0)
		)
		(min_thickness 0.25)
		(keepout
			(tracks not_allowed)
			(vias allowed)
			(pads allowed)
			(copperpour not_allowed)
			(footprints allowed)
		)
		(placement
			(enabled no)
			(sheetname "")
		)
		(fill yes
			(thermal_gap 0.5)
			(thermal_bridge_width 0.5)
			(island_removal_mode 0)
		)
		(polygon
			(pts
				(arc
					(start 143.154908 -433.289964)
					(mid 142.345156 -433.289964)
					(end 143.154908 -433.289964)
				)
			)
		)
	)
	(zone
		(layers "B.Cu" "In15.Cu")
		(hatch none 0.5)
		(connect_pads
			(clearance 0)
		)
		(min_thickness 0.25)
		(keepout
			(tracks not_allowed)
			(vias allowed)
			(pads allowed)
			(copperpour not_allowed)
			(footprints allowed)
		)
		(placement
			(enabled no)
			(sheetname "")
		)
		(fill yes
			(thermal_gap 0.5)
			(thermal_bridge_width 0.5)
			(island_removal_mode 0)
		)
		(polygon
			(pts
				(arc
					(start 90.054938 -437.889904)
					(mid 89.245186 -437.889904)
					(end 90.054938 -437.889904)
				)
			)
		)
	)
	(zone
		(layers "B.Cu" "In15.Cu")
		(hatch none 0.5)
		(connect_pads
			(clearance 0)
		)
		(min_thickness 0.25)
		(keepout
			(tracks not_allowed)
			(vias allowed)
			(pads allowed)
			(copperpour not_allowed)
			(footprints allowed)
		)
		(placement
			(enabled no)
			(sheetname "")
		)
		(fill yes
			(thermal_gap 0.5)
			(thermal_bridge_width 0.5)
			(island_removal_mode 0)
		)
		(polygon
			(pts
				(arc
					(start 90.821002 -220.319854)
					(mid 90.168222 -220.319854)
					(end 90.821002 -220.319854)
				)
			)
		)
	)
	(zone
		(layers "B.Cu" "In15.Cu")
		(hatch none 0.5)
		(connect_pads
			(clearance 0)
		)
		(min_thickness 0.25)
		(keepout
			(tracks not_allowed)
			(vias allowed)
			(pads allowed)
			(copperpour not_allowed)
			(footprints allowed)
		)
		(placement
			(enabled no)
			(sheetname "")
		)
		(fill yes
			(thermal_gap 0.5)
			(thermal_bridge_width 0.5)
			(island_removal_mode 0)
		)
		(polygon
			(pts
				(arc
					(start 341.432388 -45.160946)
					(mid 340.779608 -45.160946)
					(end 341.432388 -45.160946)
				)
			)
		)
	)
	(zone
		(layers "B.Cu" "In15.Cu")
		(hatch none 0.5)
		(connect_pads
			(clearance 0)
		)
		(min_thickness 0.25)
		(keepout
			(tracks not_allowed)
			(vias allowed)
			(pads allowed)
			(copperpour not_allowed)
			(footprints allowed)
		)
		(placement
			(enabled no)
			(sheetname "")
		)
		(fill yes
			(thermal_gap 0.5)
			(thermal_bridge_width 0.5)
			(island_removal_mode 0)
		)
		(polygon
			(pts
				(arc
					(start 134.052056 -220.319854)
					(mid 133.399276 -220.319854)
					(end 134.052056 -220.319854)
				)
			)
		)
	)
	(zone
		(layers "B.Cu" "In15.Cu")
		(hatch none 0.5)
		(connect_pads
			(clearance 0)
		)
		(min_thickness 0.25)
		(keepout
			(tracks not_allowed)
			(vias allowed)
			(pads allowed)
			(copperpour not_allowed)
			(footprints allowed)
		)
		(placement
			(enabled no)
			(sheetname "")
		)
		(fill yes
			(thermal_gap 0.5)
			(thermal_bridge_width 0.5)
			(island_removal_mode 0)
		)
		(polygon
			(pts
				(arc
					(start 149.154896 -434.289962)
					(mid 148.345144 -434.289962)
					(end 149.154896 -434.289962)
				)
			)
		)
	)
	(zone
		(layers "B.Cu" "In15.Cu")
		(hatch none 0.5)
		(connect_pads
			(clearance 0)
		)
		(min_thickness 0.25)
		(keepout
			(tracks not_allowed)
			(vias allowed)
			(pads allowed)
			(copperpour not_allowed)
			(footprints allowed)
		)
		(placement
			(enabled no)
			(sheetname "")
		)
		(fill yes
			(thermal_gap 0.5)
			(thermal_bridge_width 0.5)
			(island_removal_mode 0)
		)
		(polygon
			(pts
				(arc
					(start 382.154938 -433.289964)
					(mid 381.345186 -433.289964)
					(end 382.154938 -433.289964)
				)
			)
		)
	)
	(zone
		(layers "B.Cu" "In15.Cu")
		(hatch none 0.5)
		(connect_pads
			(clearance 0)
		)
		(min_thickness 0.25)
		(keepout
			(tracks not_allowed)
			(vias allowed)
			(pads allowed)
			(copperpour not_allowed)
			(footprints allowed)
		)
		(placement
			(enabled no)
			(sheetname "")
		)
		(fill yes
			(thermal_gap 0.5)
			(thermal_bridge_width 0.5)
			(island_removal_mode 0)
		)
		(polygon
			(pts
				(arc
					(start 134.991602 -221.94774)
					(mid 134.338822 -221.94774)
					(end 134.991602 -221.94774)
				)
			)
		)
	)
	(zone
		(layers "B.Cu" "In15.Cu")
		(hatch none 0.5)
		(connect_pads
			(clearance 0)
		)
		(min_thickness 0.25)
		(keepout
			(tracks not_allowed)
			(vias allowed)
			(pads allowed)
			(copperpour not_allowed)
			(footprints allowed)
		)
		(placement
			(enabled no)
			(sheetname "")
		)
		(fill yes
			(thermal_gap 0.5)
			(thermal_bridge_width 0.5)
			(island_removal_mode 0)
		)
		(polygon
			(pts
				(arc
					(start 143.154908 -434.48986)
					(mid 142.345156 -434.48986)
					(end 143.154908 -434.48986)
				)
			)
		)
	)
	(zone
		(layers "B.Cu" "In15.Cu")
		(hatch none 0.5)
		(connect_pads
			(clearance 0)
		)
		(min_thickness 0.25)
		(keepout
			(tracks not_allowed)
			(vias allowed)
			(pads allowed)
			(copperpour not_allowed)
			(footprints allowed)
		)
		(placement
			(enabled no)
			(sheetname "")
		)
		(fill yes
			(thermal_gap 0.5)
			(thermal_bridge_width 0.5)
			(island_removal_mode 0)
		)
		(polygon
			(pts
				(arc
					(start 151.154892 -434.48986)
					(mid 150.34514 -434.48986)
					(end 151.154892 -434.48986)
				)
			)
		)
	)
	(zone
		(layers "B.Cu" "In15.Cu")
		(hatch none 0.5)
		(connect_pads
			(clearance 0)
		)
		(min_thickness 0.25)
		(keepout
			(tracks not_allowed)
			(vias allowed)
			(pads allowed)
			(copperpour not_allowed)
			(footprints allowed)
		)
		(placement
			(enabled no)
			(sheetname "")
		)
		(fill yes
			(thermal_gap 0.5)
			(thermal_bridge_width 0.5)
			(island_removal_mode 0)
		)
		(polygon
			(pts
				(arc
					(start 413.154876 -434.289962)
					(mid 412.345124 -434.289962)
					(end 413.154876 -434.289962)
				)
			)
		)
	)
	(zone
		(layers "B.Cu" "In15.Cu")
		(hatch none 0.5)
		(connect_pads
			(clearance 0)
		)
		(min_thickness 0.25)
		(keepout
			(tracks not_allowed)
			(vias allowed)
			(pads allowed)
			(copperpour not_allowed)
			(footprints allowed)
		)
		(placement
			(enabled no)
			(sheetname "")
		)
		(fill yes
			(thermal_gap 0.5)
			(thermal_bridge_width 0.5)
			(island_removal_mode 0)
		)
		(polygon
			(pts
				(arc
					(start 342.050624 -221.133924)
					(mid 341.397844 -221.133924)
					(end 342.050624 -221.133924)
				)
			)
		)
	)
	(zone
		(layers "B.Cu" "In15.Cu")
		(hatch none 0.5)
		(connect_pads
			(clearance 0)
		)
		(min_thickness 0.25)
		(keepout
			(tracks not_allowed)
			(vias allowed)
			(pads allowed)
			(copperpour not_allowed)
			(footprints allowed)
		)
		(placement
			(enabled no)
			(sheetname "")
		)
		(fill yes
			(thermal_gap 0.5)
			(thermal_bridge_width 0.5)
			(island_removal_mode 0)
		)
		(polygon
			(pts
				(arc
					(start 90.351356 -221.133924)
					(mid 89.698576 -221.133924)
					(end 90.351356 -221.133924)
				)
			)
		)
	)
	(zone
		(layers "B.Cu" "In15.Cu")
		(hatch none 0.5)
		(connect_pads
			(clearance 0)
		)
		(min_thickness 0.25)
		(keepout
			(tracks not_allowed)
			(vias allowed)
			(pads allowed)
			(copperpour not_allowed)
			(footprints allowed)
		)
		(placement
			(enabled no)
			(sheetname "")
		)
		(fill yes
			(thermal_gap 0.5)
			(thermal_bridge_width 0.5)
			(island_removal_mode 0)
		)
		(polygon
			(pts
				(arc
					(start 343.930224 -221.133924)
					(mid 343.277444 -221.133924)
					(end 343.930224 -221.133924)
				)
			)
		)
	)
	(zone
		(layers "B.Cu" "In15.Cu")
		(hatch none 0.5)
		(connect_pads
			(clearance 0)
		)
		(min_thickness 0.25)
		(keepout
			(tracks not_allowed)
			(vias allowed)
			(pads allowed)
			(copperpour not_allowed)
			(footprints allowed)
		)
		(placement
			(enabled no)
			(sheetname "")
		)
		(fill yes
			(thermal_gap 0.5)
			(thermal_bridge_width 0.5)
			(island_removal_mode 0)
		)
		(polygon
			(pts
				(arc
					(start 403.154896 -434.48986)
					(mid 402.345144 -434.48986)
					(end 403.154896 -434.48986)
				)
			)
		)
	)
	(zone
		(layers "B.Cu" "In15.Cu")
		(hatch none 0.5)
		(connect_pads
			(clearance 0)
		)
		(min_thickness 0.25)
		(keepout
			(tracks not_allowed)
			(vias allowed)
			(pads allowed)
			(copperpour not_allowed)
			(footprints allowed)
		)
		(placement
			(enabled no)
			(sheetname "")
		)
		(fill yes
			(thermal_gap 0.5)
			(thermal_bridge_width 0.5)
			(island_removal_mode 0)
		)
		(polygon
			(pts
				(arc
					(start 130.292602 -220.319854)
					(mid 129.639822 -220.319854)
					(end 130.292602 -220.319854)
				)
			)
		)
	)
	(zone
		(layers "B.Cu" "In15.Cu")
		(hatch none 0.5)
		(connect_pads
			(clearance 0)
		)
		(min_thickness 0.25)
		(keepout
			(tracks not_allowed)
			(vias allowed)
			(pads allowed)
			(copperpour not_allowed)
			(footprints allowed)
		)
		(placement
			(enabled no)
			(sheetname "")
		)
		(fill yes
			(thermal_gap 0.5)
			(thermal_bridge_width 0.5)
			(island_removal_mode 0)
		)
		(polygon
			(pts
				(arc
					(start 337.82127 -221.94774)
					(mid 337.16849 -221.94774)
					(end 337.82127 -221.94774)
				)
			)
		)
	)
	(zone
		(layers "B.Cu" "In15.Cu")
		(hatch none 0.5)
		(connect_pads
			(clearance 0)
		)
		(min_thickness 0.25)
		(keepout
			(tracks not_allowed)
			(vias allowed)
			(pads allowed)
			(copperpour not_allowed)
			(footprints allowed)
		)
		(placement
			(enabled no)
			(sheetname "")
		)
		(fill yes
			(thermal_gap 0.5)
			(thermal_bridge_width 0.5)
			(island_removal_mode 0)
		)
		(polygon
			(pts
				(arc
					(start 374.003824 -221.133924)
					(mid 373.351044 -221.133924)
					(end 374.003824 -221.133924)
				)
			)
		)
	)
	(zone
		(layers "B.Cu" "In15.Cu")
		(hatch none 0.5)
		(connect_pads
			(clearance 0)
		)
		(min_thickness 0.25)
		(keepout
			(tracks not_allowed)
			(vias allowed)
			(pads allowed)
			(copperpour not_allowed)
			(footprints allowed)
		)
		(placement
			(enabled no)
			(sheetname "")
		)
		(fill yes
			(thermal_gap 0.5)
			(thermal_bridge_width 0.5)
			(island_removal_mode 0)
		)
		(polygon
			(pts
				(arc
					(start 403.154896 -433.289964)
					(mid 402.345144 -433.289964)
					(end 403.154896 -433.289964)
				)
			)
		)
	)
	(zone
		(layers "B.Cu" "In15.Cu")
		(hatch none 0.5)
		(connect_pads
			(clearance 0)
		)
		(min_thickness 0.25)
		(keepout
			(tracks not_allowed)
			(vias allowed)
			(pads allowed)
			(copperpour not_allowed)
			(footprints allowed)
		)
		(placement
			(enabled no)
			(sheetname "")
		)
		(fill yes
			(thermal_gap 0.5)
			(thermal_bridge_width 0.5)
			(island_removal_mode 0)
		)
		(polygon
			(pts
				(arc
					(start 101.158802 -221.94774)
					(mid 100.506022 -221.94774)
					(end 101.158802 -221.94774)
				)
			)
		)
	)
	(zone
		(layers "B.Cu" "In15.Cu")
		(hatch none 0.5)
		(connect_pads
			(clearance 0)
		)
		(min_thickness 0.25)
		(keepout
			(tracks not_allowed)
			(vias allowed)
			(pads allowed)
			(copperpour not_allowed)
			(footprints allowed)
		)
		(placement
			(enabled no)
			(sheetname "")
		)
		(fill yes
			(thermal_gap 0.5)
			(thermal_bridge_width 0.5)
			(island_removal_mode 0)
		)
		(polygon
			(pts
				(arc
					(start 132.172202 -220.319854)
					(mid 131.519422 -220.319854)
					(end 132.172202 -220.319854)
				)
			)
		)
	)
	(zone
		(layers "B.Cu" "In15.Cu")
		(hatch none 0.5)
		(connect_pads
			(clearance 0)
		)
		(min_thickness 0.25)
		(keepout
			(tracks not_allowed)
			(vias allowed)
			(pads allowed)
			(copperpour not_allowed)
			(footprints allowed)
		)
		(placement
			(enabled no)
			(sheetname "")
		)
		(fill yes
			(thermal_gap 0.5)
			(thermal_bridge_width 0.5)
			(island_removal_mode 0)
		)
		(polygon
			(pts
				(arc
					(start 329.054968 -437.889904)
					(mid 328.245216 -437.889904)
					(end 329.054968 -437.889904)
				)
			)
		)
	)
	(zone
		(layers "B.Cu" "In15.Cu")
		(hatch none 0.5)
		(connect_pads
			(clearance 0)
		)
		(min_thickness 0.25)
		(keepout
			(tracks not_allowed)
			(vias allowed)
			(pads allowed)
			(copperpour not_allowed)
			(footprints allowed)
		)
		(placement
			(enabled no)
			(sheetname "")
		)
		(fill yes
			(thermal_gap 0.5)
			(thermal_bridge_width 0.5)
			(island_removal_mode 0)
		)
		(polygon
			(pts
				(arc
					(start 103.038402 -221.94774)
					(mid 102.385622 -221.94774)
					(end 103.038402 -221.94774)
				)
			)
		)
	)
	(zone
		(layers "B.Cu" "In15.Cu")
		(hatch none 0.5)
		(connect_pads
			(clearance 0)
		)
		(min_thickness 0.25)
		(keepout
			(tracks not_allowed)
			(vias allowed)
			(pads allowed)
			(copperpour not_allowed)
			(footprints allowed)
		)
		(placement
			(enabled no)
			(sheetname "")
		)
		(fill yes
			(thermal_gap 0.5)
			(thermal_bridge_width 0.5)
			(island_removal_mode 0)
		)
		(polygon
			(pts
				(arc
					(start 128.883156 -221.133924)
					(mid 128.230376 -221.133924)
					(end 128.883156 -221.133924)
				)
			)
		)
	)
	(zone
		(layers "B.Cu" "In15.Cu")
		(hatch none 0.5)
		(connect_pads
			(clearance 0)
		)
		(min_thickness 0.25)
		(keepout
			(tracks not_allowed)
			(vias allowed)
			(pads allowed)
			(copperpour not_allowed)
			(footprints allowed)
		)
		(placement
			(enabled no)
			(sheetname "")
		)
		(fill yes
			(thermal_gap 0.5)
			(thermal_bridge_width 0.5)
			(island_removal_mode 0)
		)
		(polygon
			(pts
				(arc
					(start 346.054934 -437.889904)
					(mid 345.245182 -437.889904)
					(end 346.054934 -437.889904)
				)
			)
		)
	)
	(zone
		(layers "B.Cu" "In15.Cu")
		(hatch none 0.5)
		(connect_pads
			(clearance 0)
		)
		(min_thickness 0.25)
		(keepout
			(tracks not_allowed)
			(vias allowed)
			(pads allowed)
			(copperpour not_allowed)
			(footprints allowed)
		)
		(placement
			(enabled no)
			(sheetname "")
		)
		(fill yes
			(thermal_gap 0.5)
			(thermal_bridge_width 0.5)
			(island_removal_mode 0)
		)
		(polygon
			(pts
				(arc
					(start 61.054996 -439.0898)
					(mid 60.245244 -439.0898)
					(end 61.054996 -439.0898)
				)
			)
		)
	)
	(zone
		(layers "B.Cu" "In15.Cu")
		(hatch none 0.5)
		(connect_pads
			(clearance 0)
		)
		(min_thickness 0.25)
		(keepout
			(tracks not_allowed)
			(vias allowed)
			(pads allowed)
			(copperpour not_allowed)
			(footprints allowed)
		)
		(placement
			(enabled no)
			(sheetname "")
		)
		(fill yes
			(thermal_gap 0.5)
			(thermal_bridge_width 0.5)
			(island_removal_mode 0)
		)
		(polygon
			(pts
				(arc
					(start 121.364756 -221.133924)
					(mid 120.711976 -221.133924)
					(end 121.364756 -221.133924)
				)
			)
		)
	)
	(zone
		(layers "B.Cu" "In15.Cu")
		(hatch none 0.5)
		(connect_pads
			(clearance 0)
		)
		(min_thickness 0.25)
		(keepout
			(tracks not_allowed)
			(vias allowed)
			(pads allowed)
			(copperpour not_allowed)
			(footprints allowed)
		)
		(placement
			(enabled no)
			(sheetname "")
		)
		(fill yes
			(thermal_gap 0.5)
			(thermal_bridge_width 0.5)
			(island_removal_mode 0)
		)
		(polygon
			(pts
				(arc
					(start 96.929956 -221.133924)
					(mid 96.277176 -221.133924)
					(end 96.929956 -221.133924)
				)
			)
		)
	)
	(zone
		(layers "B.Cu" "In15.Cu")
		(hatch none 0.5)
		(connect_pads
			(clearance 0)
		)
		(min_thickness 0.25)
		(keepout
			(tracks not_allowed)
			(vias allowed)
			(pads allowed)
			(copperpour not_allowed)
			(footprints allowed)
		)
		(placement
			(enabled no)
			(sheetname "")
		)
		(fill yes
			(thermal_gap 0.5)
			(thermal_bridge_width 0.5)
			(island_removal_mode 0)
		)
		(polygon
			(pts
				(arc
					(start 126.154942 -433.289964)
					(mid 125.34519 -433.289964)
					(end 126.154942 -433.289964)
				)
			)
		)
	)
	(zone
		(layers "B.Cu" "In15.Cu")
		(hatch none 0.5)
		(connect_pads
			(clearance 0)
		)
		(min_thickness 0.25)
		(keepout
			(tracks not_allowed)
			(vias allowed)
			(pads allowed)
			(copperpour not_allowed)
			(footprints allowed)
		)
		(placement
			(enabled no)
			(sheetname "")
		)
		(fill yes
			(thermal_gap 0.5)
			(thermal_bridge_width 0.5)
			(island_removal_mode 0)
		)
		(polygon
			(pts
				(arc
					(start 351.448624 -221.133924)
					(mid 350.795844 -221.133924)
					(end 351.448624 -221.133924)
				)
			)
		)
	)
	(zone
		(layers "B.Cu" "In15.Cu")
		(hatch none 0.5)
		(connect_pads
			(clearance 0)
		)
		(min_thickness 0.25)
		(keepout
			(tracks not_allowed)
			(vias allowed)
			(pads allowed)
			(copperpour not_allowed)
			(footprints allowed)
		)
		(placement
			(enabled no)
			(sheetname "")
		)
		(fill yes
			(thermal_gap 0.5)
			(thermal_bridge_width 0.5)
			(island_removal_mode 0)
		)
		(polygon
			(pts
				(arc
					(start 377.763024 -221.133924)
					(mid 377.110244 -221.133924)
					(end 377.763024 -221.133924)
				)
			)
		)
	)
	(zone
		(layers "B.Cu" "In15.Cu")
		(hatch none 0.5)
		(connect_pads
			(clearance 0)
		)
		(min_thickness 0.25)
		(keepout
			(tracks not_allowed)
			(vias allowed)
			(pads allowed)
			(copperpour not_allowed)
			(footprints allowed)
		)
		(placement
			(enabled no)
			(sheetname "")
		)
		(fill yes
			(thermal_gap 0.5)
			(thermal_bridge_width 0.5)
			(island_removal_mode 0)
		)
		(polygon
			(pts
				(arc
					(start 339.70087 -221.94774)
					(mid 339.04809 -221.94774)
					(end 339.70087 -221.94774)
				)
			)
		)
	)
	(zone
		(layers "B.Cu" "In15.Cu")
		(hatch none 0.5)
		(connect_pads
			(clearance 0)
		)
		(min_thickness 0.25)
		(keepout
			(tracks not_allowed)
			(vias allowed)
			(pads allowed)
			(copperpour not_allowed)
			(footprints allowed)
		)
		(placement
			(enabled no)
			(sheetname "")
		)
		(fill yes
			(thermal_gap 0.5)
			(thermal_bridge_width 0.5)
			(island_removal_mode 0)
		)
		(polygon
			(pts
				(arc
					(start 63.054992 -436.889906)
					(mid 62.24524 -436.889906)
					(end 63.054992 -436.889906)
				)
			)
		)
	)
	(zone
		(layers "B.Cu" "In15.Cu")
		(hatch none 0.5)
		(connect_pads
			(clearance 0)
		)
		(min_thickness 0.25)
		(keepout
			(tracks not_allowed)
			(vias allowed)
			(pads allowed)
			(copperpour not_allowed)
			(footprints allowed)
		)
		(placement
			(enabled no)
			(sheetname "")
		)
		(fill yes
			(thermal_gap 0.5)
			(thermal_bridge_width 0.5)
			(island_removal_mode 0)
		)
		(polygon
			(pts
				(arc
					(start 99.279202 -221.94774)
					(mid 98.626422 -221.94774)
					(end 99.279202 -221.94774)
				)
			)
		)
	)
	(zone
		(layers "B.Cu" "In15.Cu")
		(hatch none 0.5)
		(connect_pads
			(clearance 0)
		)
		(min_thickness 0.25)
		(keepout
			(tracks not_allowed)
			(vias allowed)
			(pads allowed)
			(copperpour not_allowed)
			(footprints allowed)
		)
		(placement
			(enabled no)
			(sheetname "")
		)
		(fill yes
			(thermal_gap 0.5)
			(thermal_bridge_width 0.5)
			(island_removal_mode 0)
		)
		(polygon
			(pts
				(arc
					(start 100.689156 -221.133924)
					(mid 100.036376 -221.133924)
					(end 100.689156 -221.133924)
				)
			)
		)
	)
	(zone
		(layers "B.Cu" "In15.Cu")
		(hatch none 0.5)
		(connect_pads
			(clearance 0)
		)
		(min_thickness 0.25)
		(keepout
			(tracks not_allowed)
			(vias allowed)
			(pads allowed)
			(copperpour not_allowed)
			(footprints allowed)
		)
		(placement
			(enabled no)
			(sheetname "")
		)
		(fill yes
			(thermal_gap 0.5)
			(thermal_bridge_width 0.5)
			(island_removal_mode 0)
		)
		(polygon
			(pts
				(arc
					(start 327.054972 -438.089802)
					(mid 326.24522 -438.089802)
					(end 327.054972 -438.089802)
				)
			)
		)
	)
	(zone
		(layers "B.Cu" "In15.Cu")
		(hatch none 0.5)
		(connect_pads
			(clearance 0)
		)
		(min_thickness 0.25)
		(keepout
			(tracks not_allowed)
			(vias allowed)
			(pads allowed)
			(copperpour not_allowed)
			(footprints allowed)
		)
		(placement
			(enabled no)
			(sheetname "")
		)
		(fill yes
			(thermal_gap 0.5)
			(thermal_bridge_width 0.5)
			(island_removal_mode 0)
		)
		(polygon
			(pts
				(arc
					(start 378.23267 -220.319854)
					(mid 377.57989 -220.319854)
					(end 378.23267 -220.319854)
				)
			)
		)
	)
	(zone
		(layers "B.Cu" "In15.Cu")
		(hatch none 0.5)
		(connect_pads
			(clearance 0)
		)
		(min_thickness 0.25)
		(keepout
			(tracks not_allowed)
			(vias allowed)
			(pads allowed)
			(copperpour not_allowed)
			(footprints allowed)
		)
		(placement
			(enabled no)
			(sheetname "")
		)
		(fill yes
			(thermal_gap 0.5)
			(thermal_bridge_width 0.5)
			(island_removal_mode 0)
		)
		(polygon
			(pts
				(arc
					(start 372.124224 -221.133924)
					(mid 371.471444 -221.133924)
					(end 372.124224 -221.133924)
				)
			)
		)
	)
	(zone
		(layers "B.Cu" "In15.Cu")
		(hatch none 0.5)
		(connect_pads
			(clearance 0)
		)
		(min_thickness 0.25)
		(keepout
			(tracks not_allowed)
			(vias allowed)
			(pads allowed)
			(copperpour not_allowed)
			(footprints allowed)
		)
		(placement
			(enabled no)
			(sheetname "")
		)
		(fill yes
			(thermal_gap 0.5)
			(thermal_bridge_width 0.5)
			(island_removal_mode 0)
		)
		(polygon
			(pts
				(arc
					(start 182.393082 -53.954934)
					(mid 181.689502 -53.954934)
					(end 182.393082 -53.954934)
				)
			)
		)
	)
	(zone
		(layers "B.Cu" "In15.Cu")
		(hatch none 0.5)
		(connect_pads
			(clearance 0)
		)
		(min_thickness 0.25)
		(keepout
			(tracks not_allowed)
			(vias allowed)
			(pads allowed)
			(copperpour not_allowed)
			(footprints allowed)
		)
		(placement
			(enabled no)
			(sheetname "")
		)
		(fill yes
			(thermal_gap 0.5)
			(thermal_bridge_width 0.5)
			(island_removal_mode 0)
		)
		(polygon
			(pts
				(arc
					(start 132.642356 -221.133924)
					(mid 131.989576 -221.133924)
					(end 132.642356 -221.133924)
				)
			)
		)
	)
	(zone
		(layers "B.Cu" "In15.Cu")
		(hatch none 0.5)
		(connect_pads
			(clearance 0)
		)
		(min_thickness 0.25)
		(keepout
			(tracks not_allowed)
			(vias allowed)
			(pads allowed)
			(copperpour not_allowed)
			(footprints allowed)
		)
		(placement
			(enabled no)
			(sheetname "")
		)
		(fill yes
			(thermal_gap 0.5)
			(thermal_bridge_width 0.5)
			(island_removal_mode 0)
		)
		(polygon
			(pts
				(arc
					(start 126.063756 -221.133924)
					(mid 125.410976 -221.133924)
					(end 126.063756 -221.133924)
				)
			)
		)
	)
	(zone
		(layers "B.Cu" "In15.Cu")
		(hatch none 0.5)
		(connect_pads
			(clearance 0)
		)
		(min_thickness 0.25)
		(keepout
			(tracks not_allowed)
			(vias allowed)
			(pads allowed)
			(copperpour not_allowed)
			(footprints allowed)
		)
		(placement
			(enabled no)
			(sheetname "")
		)
		(fill yes
			(thermal_gap 0.5)
			(thermal_bridge_width 0.5)
			(island_removal_mode 0)
		)
		(polygon
			(pts
				(arc
					(start 93.170756 -221.133924)
					(mid 92.517976 -221.133924)
					(end 93.170756 -221.133924)
				)
			)
		)
	)
	(zone
		(layers "B.Cu" "In15.Cu")
		(hatch none 0.5)
		(connect_pads
			(clearance 0)
		)
		(min_thickness 0.25)
		(keepout
			(tracks not_allowed)
			(vias allowed)
			(pads allowed)
			(copperpour not_allowed)
			(footprints allowed)
		)
		(placement
			(enabled no)
			(sheetname "")
		)
		(fill yes
			(thermal_gap 0.5)
			(thermal_bridge_width 0.5)
			(island_removal_mode 0)
		)
		(polygon
			(pts
				(arc
					(start 383.401824 -221.133924)
					(mid 382.749044 -221.133924)
					(end 383.401824 -221.133924)
				)
			)
		)
	)
	(zone
		(layers "B.Cu" "In15.Cu")
		(hatch none 0.5)
		(connect_pads
			(clearance 0)
		)
		(min_thickness 0.25)
		(keepout
			(tracks not_allowed)
			(vias allowed)
			(pads allowed)
			(copperpour not_allowed)
			(footprints allowed)
		)
		(placement
			(enabled no)
			(sheetname "")
		)
		(fill yes
			(thermal_gap 0.5)
			(thermal_bridge_width 0.5)
			(island_removal_mode 0)
		)
		(polygon
			(pts
				(arc
					(start 351.91827 -220.319854)
					(mid 351.26549 -220.319854)
					(end 351.91827 -220.319854)
				)
			)
		)
	)
	(zone
		(layers "B.Cu" "In15.Cu")
		(hatch none 0.5)
		(connect_pads
			(clearance 0)
		)
		(min_thickness 0.25)
		(keepout
			(tracks not_allowed)
			(vias allowed)
			(pads allowed)
			(copperpour not_allowed)
			(footprints allowed)
		)
		(placement
			(enabled no)
			(sheetname "")
		)
		(fill yes
			(thermal_gap 0.5)
			(thermal_bridge_width 0.5)
			(island_removal_mode 0)
		)
		(polygon
			(pts
				(arc
					(start 368.83467 -220.319854)
					(mid 368.18189 -220.319854)
					(end 368.83467 -220.319854)
				)
			)
		)
	)
	(zone
		(layers "B.Cu" "In15.Cu")
		(hatch none 0.5)
		(connect_pads
			(clearance 0)
		)
		(min_thickness 0.25)
		(keepout
			(tracks not_allowed)
			(vias allowed)
			(pads allowed)
			(copperpour not_allowed)
			(footprints allowed)
		)
		(placement
			(enabled no)
			(sheetname "")
		)
		(fill yes
			(thermal_gap 0.5)
			(thermal_bridge_width 0.5)
			(island_removal_mode 0)
		)
		(polygon
			(pts
				(arc
					(start 336.054954 -436.889906)
					(mid 335.245202 -436.889906)
					(end 336.054954 -436.889906)
				)
			)
		)
	)
	(zone
		(layers "B.Cu" "In15.Cu")
		(hatch none 0.5)
		(connect_pads
			(clearance 0)
		)
		(min_thickness 0.25)
		(keepout
			(tracks not_allowed)
			(vias allowed)
			(pads allowed)
			(copperpour not_allowed)
			(footprints allowed)
		)
		(placement
			(enabled no)
			(sheetname "")
		)
		(fill yes
			(thermal_gap 0.5)
			(thermal_bridge_width 0.5)
			(island_removal_mode 0)
		)
		(polygon
			(pts
				(arc
					(start 155.154884 -434.48986)
					(mid 154.345132 -434.48986)
					(end 155.154884 -434.48986)
				)
			)
		)
	)
	(zone
		(layers "B.Cu" "In15.Cu")
		(hatch none 0.5)
		(connect_pads
			(clearance 0)
		)
		(min_thickness 0.25)
		(keepout
			(tracks not_allowed)
			(vias allowed)
			(pads allowed)
			(copperpour not_allowed)
			(footprints allowed)
		)
		(placement
			(enabled no)
			(sheetname "")
		)
		(fill yes
			(thermal_gap 0.5)
			(thermal_bridge_width 0.5)
			(island_removal_mode 0)
		)
		(polygon
			(pts
				(arc
					(start 138.154918 -434.48986)
					(mid 137.345166 -434.48986)
					(end 138.154918 -434.48986)
				)
			)
		)
	)
	(zone
		(layers "B.Cu" "In15.Cu")
		(hatch none 0.5)
		(connect_pads
			(clearance 0)
		)
		(min_thickness 0.25)
		(keepout
			(tracks not_allowed)
			(vias allowed)
			(pads allowed)
			(copperpour not_allowed)
			(footprints allowed)
		)
		(placement
			(enabled no)
			(sheetname "")
		)
		(fill yes
			(thermal_gap 0.5)
			(thermal_bridge_width 0.5)
			(island_removal_mode 0)
		)
		(polygon
			(pts
				(arc
					(start 399.154904 -434.48986)
					(mid 398.345152 -434.48986)
					(end 399.154904 -434.48986)
				)
			)
		)
	)
	(zone
		(layers "B.Cu" "In15.Cu")
		(hatch none 0.5)
		(connect_pads
			(clearance 0)
		)
		(min_thickness 0.25)
		(keepout
			(tracks not_allowed)
			(vias allowed)
			(pads allowed)
			(copperpour not_allowed)
			(footprints allowed)
		)
		(placement
			(enabled no)
			(sheetname "")
		)
		(fill yes
			(thermal_gap 0.5)
			(thermal_bridge_width 0.5)
			(island_removal_mode 0)
		)
		(polygon
			(pts
				(arc
					(start 98.809556 -221.133924)
					(mid 98.156776 -221.133924)
					(end 98.809556 -221.133924)
				)
			)
		)
	)
	(zone
		(layers "B.Cu" "In15.Cu")
		(hatch none 0.5)
		(connect_pads
			(clearance 0)
		)
		(min_thickness 0.25)
		(keepout
			(tracks not_allowed)
			(vias allowed)
			(pads allowed)
			(copperpour not_allowed)
			(footprints allowed)
		)
		(placement
			(enabled no)
			(sheetname "")
		)
		(fill yes
			(thermal_gap 0.5)
			(thermal_bridge_width 0.5)
			(island_removal_mode 0)
		)
		(polygon
			(pts
				(arc
					(start 346.749624 -221.133924)
					(mid 346.096844 -221.133924)
					(end 346.749624 -221.133924)
				)
			)
		)
	)
	(zone
		(layers "B.Cu" "In15.Cu")
		(hatch none 0.5)
		(connect_pads
			(clearance 0)
		)
		(min_thickness 0.25)
		(keepout
			(tracks not_allowed)
			(vias allowed)
			(pads allowed)
			(copperpour not_allowed)
			(footprints allowed)
		)
		(placement
			(enabled no)
			(sheetname "")
		)
		(fill yes
			(thermal_gap 0.5)
			(thermal_bridge_width 0.5)
			(island_removal_mode 0)
		)
		(polygon
			(pts
				(arc
					(start 375.883424 -221.133924)
					(mid 375.230644 -221.133924)
					(end 375.883424 -221.133924)
				)
			)
		)
	)
	(zone
		(layers "B.Cu" "In15.Cu")
		(hatch none 0.5)
		(connect_pads
			(clearance 0)
		)
		(min_thickness 0.25)
		(keepout
			(tracks not_allowed)
			(vias allowed)
			(pads allowed)
			(copperpour not_allowed)
			(footprints allowed)
		)
		(placement
			(enabled no)
			(sheetname "")
		)
		(fill yes
			(thermal_gap 0.5)
			(thermal_bridge_width 0.5)
			(island_removal_mode 0)
		)
		(polygon
			(pts
				(arc
					(start 338.76107 -220.319854)
					(mid 338.10829 -220.319854)
					(end 338.76107 -220.319854)
				)
			)
		)
	)
	(zone
		(layers "B.Cu" "In15.Cu")
		(hatch none 0.5)
		(connect_pads
			(clearance 0)
		)
		(min_thickness 0.25)
		(keepout
			(tracks not_allowed)
			(vias allowed)
			(pads allowed)
			(copperpour not_allowed)
			(footprints allowed)
		)
		(placement
			(enabled no)
			(sheetname "")
		)
		(fill yes
			(thermal_gap 0.5)
			(thermal_bridge_width 0.5)
			(island_removal_mode 0)
		)
		(polygon
			(pts
				(arc
					(start 394.154914 -433.289964)
					(mid 393.345162 -433.289964)
					(end 394.154914 -433.289964)
				)
			)
		)
	)
	(zone
		(layers "B.Cu" "In15.Cu")
		(hatch none 0.5)
		(connect_pads
			(clearance 0)
		)
		(min_thickness 0.25)
		(keepout
			(tracks not_allowed)
			(vias allowed)
			(pads allowed)
			(copperpour not_allowed)
			(footprints allowed)
		)
		(placement
			(enabled no)
			(sheetname "")
		)
		(fill yes
			(thermal_gap 0.5)
			(thermal_bridge_width 0.5)
			(island_removal_mode 0)
		)
		(polygon
			(pts
				(arc
					(start 379.642624 -221.133924)
					(mid 378.989844 -221.133924)
					(end 379.642624 -221.133924)
				)
			)
		)
	)
	(zone
		(layers "B.Cu" "In15.Cu")
		(hatch none 0.5)
		(connect_pads
			(clearance 0)
		)
		(min_thickness 0.25)
		(keepout
			(tracks not_allowed)
			(vias allowed)
			(pads allowed)
			(copperpour not_allowed)
			(footprints allowed)
		)
		(placement
			(enabled no)
			(sheetname "")
		)
		(fill yes
			(thermal_gap 0.5)
			(thermal_bridge_width 0.5)
			(island_removal_mode 0)
		)
		(polygon
			(pts
				(arc
					(start 103.508556 -221.133924)
					(mid 102.855776 -221.133924)
					(end 103.508556 -221.133924)
				)
			)
		)
	)
	(zone
		(layers "B.Cu" "In15.Cu")
		(hatch none 0.5)
		(connect_pads
			(clearance 0)
		)
		(min_thickness 0.25)
		(keepout
			(tracks not_allowed)
			(vias allowed)
			(pads allowed)
			(copperpour not_allowed)
			(footprints allowed)
		)
		(placement
			(enabled no)
			(sheetname "")
		)
		(fill yes
			(thermal_gap 0.5)
			(thermal_bridge_width 0.5)
			(island_removal_mode 0)
		)
		(polygon
			(pts
				(arc
					(start 84.05495 -438.089802)
					(mid 83.245198 -438.089802)
					(end 84.05495 -438.089802)
				)
			)
		)
	)
	(zone
		(layers "B.Cu" "In15.Cu")
		(hatch none 0.5)
		(connect_pads
			(clearance 0)
		)
		(min_thickness 0.25)
		(keepout
			(tracks not_allowed)
			(vias allowed)
			(pads allowed)
			(copperpour not_allowed)
			(footprints allowed)
		)
		(placement
			(enabled no)
			(sheetname "")
		)
		(fill yes
			(thermal_gap 0.5)
			(thermal_bridge_width 0.5)
			(island_removal_mode 0)
		)
		(polygon
			(pts
				(arc
					(start 334.054958 -439.0898)
					(mid 333.245206 -439.0898)
					(end 334.054958 -439.0898)
				)
			)
		)
	)
	(zone
		(layers "B.Cu" "In15.Cu")
		(hatch none 0.5)
		(connect_pads
			(clearance 0)
		)
		(min_thickness 0.25)
		(keepout
			(tracks not_allowed)
			(vias allowed)
			(pads allowed)
			(copperpour not_allowed)
			(footprints allowed)
		)
		(placement
			(enabled no)
			(sheetname "")
		)
		(fill yes
			(thermal_gap 0.5)
			(thermal_bridge_width 0.5)
			(island_removal_mode 0)
		)
		(polygon
			(pts
				(arc
					(start 342.52027 -220.319854)
					(mid 341.86749 -220.319854)
					(end 342.52027 -220.319854)
				)
			)
		)
	)
	(zone
		(layers "B.Cu" "In15.Cu")
		(hatch none 0.5)
		(connect_pads
			(clearance 0)
		)
		(min_thickness 0.25)
		(keepout
			(tracks not_allowed)
			(vias allowed)
			(pads allowed)
			(copperpour not_allowed)
			(footprints allowed)
		)
		(placement
			(enabled no)
			(sheetname "")
		)
		(fill yes
			(thermal_gap 0.5)
			(thermal_bridge_width 0.5)
			(island_removal_mode 0)
		)
		(polygon
			(pts
				(arc
					(start 344.39987 -220.319854)
					(mid 343.74709 -220.319854)
					(end 344.39987 -220.319854)
				)
			)
		)
	)
	(zone
		(layers "B.Cu" "In15.Cu")
		(hatch none 0.5)
		(connect_pads
			(clearance 0)
		)
		(min_thickness 0.25)
		(keepout
			(tracks not_allowed)
			(vias allowed)
			(pads allowed)
			(copperpour not_allowed)
			(footprints allowed)
		)
		(placement
			(enabled no)
			(sheetname "")
		)
		(fill yes
			(thermal_gap 0.5)
			(thermal_bridge_width 0.5)
			(island_removal_mode 0)
		)
		(polygon
			(pts
				(arc
					(start 315.054996 -438.089802)
					(mid 314.245244 -438.089802)
					(end 315.054996 -438.089802)
				)
			)
		)
	)
	(zone
		(layers "B.Cu" "In15.Cu")
		(hatch none 0.5)
		(connect_pads
			(clearance 0)
		)
		(min_thickness 0.25)
		(keepout
			(tracks not_allowed)
			(vias allowed)
			(pads allowed)
			(copperpour not_allowed)
			(footprints allowed)
		)
		(placement
			(enabled no)
			(sheetname "")
		)
		(fill yes
			(thermal_gap 0.5)
			(thermal_bridge_width 0.5)
			(island_removal_mode 0)
		)
		(polygon
			(pts
				(arc
					(start 329.054968 -439.0898)
					(mid 328.245216 -439.0898)
					(end 329.054968 -439.0898)
				)
			)
		)
	)
	(zone
		(layers "B.Cu" "In15.Cu")
		(hatch none 0.5)
		(connect_pads
			(clearance 0)
		)
		(min_thickness 0.25)
		(keepout
			(tracks not_allowed)
			(vias allowed)
			(pads allowed)
			(copperpour not_allowed)
			(footprints allowed)
		)
		(placement
			(enabled no)
			(sheetname "")
		)
		(fill yes
			(thermal_gap 0.5)
			(thermal_bridge_width 0.5)
			(island_removal_mode 0)
		)
		(polygon
			(pts
				(arc
					(start 136.154922 -435.489858)
					(mid 135.34517 -435.489858)
					(end 136.154922 -435.489858)
				)
			)
		)
	)
	(zone
		(layers "B.Cu" "In15.Cu")
		(hatch none 0.5)
		(connect_pads
			(clearance 0)
		)
		(min_thickness 0.25)
		(keepout
			(tracks not_allowed)
			(vias allowed)
			(pads allowed)
			(copperpour not_allowed)
			(footprints allowed)
		)
		(placement
			(enabled no)
			(sheetname "")
		)
		(fill yes
			(thermal_gap 0.5)
			(thermal_bridge_width 0.5)
			(island_removal_mode 0)
		)
		(polygon
			(pts
				(arc
					(start 121.834402 -221.94774)
					(mid 121.181622 -221.94774)
					(end 121.834402 -221.94774)
				)
			)
		)
	)
	(zone
		(layers "B.Cu" "In15.Cu")
		(hatch none 0.5)
		(connect_pads
			(clearance 0)
		)
		(min_thickness 0.25)
		(keepout
			(tracks not_allowed)
			(vias allowed)
			(pads allowed)
			(copperpour not_allowed)
			(footprints allowed)
		)
		(placement
			(enabled no)
			(sheetname "")
		)
		(fill yes
			(thermal_gap 0.5)
			(thermal_bridge_width 0.5)
			(island_removal_mode 0)
		)
		(polygon
			(pts
				(arc
					(start 342.054942 -437.889904)
					(mid 341.24519 -437.889904)
					(end 342.054942 -437.889904)
				)
			)
		)
	)
	(zone
		(layers "B.Cu" "In15.Cu")
		(hatch none 0.5)
		(connect_pads
			(clearance 0)
		)
		(min_thickness 0.25)
		(keepout
			(tracks not_allowed)
			(vias allowed)
			(pads allowed)
			(copperpour not_allowed)
			(footprints allowed)
		)
		(placement
			(enabled no)
			(sheetname "")
		)
		(fill yes
			(thermal_gap 0.5)
			(thermal_bridge_width 0.5)
			(island_removal_mode 0)
		)
		(polygon
			(pts
				(arc
					(start 371.184424 -221.133924)
					(mid 370.531644 -221.133924)
					(end 371.184424 -221.133924)
				)
			)
		)
	)
	(zone
		(layers "B.Cu" "In15.Cu")
		(hatch none 0.5)
		(connect_pads
			(clearance 0)
		)
		(min_thickness 0.25)
		(keepout
			(tracks not_allowed)
			(vias allowed)
			(pads allowed)
			(copperpour not_allowed)
			(footprints allowed)
		)
		(placement
			(enabled no)
			(sheetname "")
		)
		(fill yes
			(thermal_gap 0.5)
			(thermal_bridge_width 0.5)
			(island_removal_mode 0)
		)
		(polygon
			(pts
				(arc
					(start 124.653802 -220.319854)
					(mid 124.001022 -220.319854)
					(end 124.653802 -220.319854)
				)
			)
		)
	)
	(zone
		(layers "B.Cu" "In15.Cu")
		(hatch none 0.5)
		(connect_pads
			(clearance 0)
		)
		(min_thickness 0.25)
		(keepout
			(tracks not_allowed)
			(vias allowed)
			(pads allowed)
			(copperpour not_allowed)
			(footprints allowed)
		)
		(placement
			(enabled no)
			(sheetname "")
		)
		(fill yes
			(thermal_gap 0.5)
			(thermal_bridge_width 0.5)
			(island_removal_mode 0)
		)
		(polygon
			(pts
				(arc
					(start 69.05498 -439.0898)
					(mid 68.245228 -439.0898)
					(end 69.05498 -439.0898)
				)
			)
		)
	)
	(zone
		(layers "B.Cu" "In15.Cu")
		(hatch none 0.5)
		(connect_pads
			(clearance 0)
		)
		(min_thickness 0.25)
		(keepout
			(tracks not_allowed)
			(vias allowed)
			(pads allowed)
			(copperpour not_allowed)
			(footprints allowed)
		)
		(placement
			(enabled no)
			(sheetname "")
		)
		(fill yes
			(thermal_gap 0.5)
			(thermal_bridge_width 0.5)
			(island_removal_mode 0)
		)
		(polygon
			(pts
				(arc
					(start 145.154904 -435.489858)
					(mid 144.345152 -435.489858)
					(end 145.154904 -435.489858)
				)
			)
		)
	)
	(zone
		(layers "B.Cu" "In15.Cu")
		(hatch none 0.5)
		(connect_pads
			(clearance 0)
		)
		(min_thickness 0.25)
		(keepout
			(tracks not_allowed)
			(vias allowed)
			(pads allowed)
			(copperpour not_allowed)
			(footprints allowed)
		)
		(placement
			(enabled no)
			(sheetname "")
		)
		(fill yes
			(thermal_gap 0.5)
			(thermal_bridge_width 0.5)
			(island_removal_mode 0)
		)
		(polygon
			(pts
				(arc
					(start 344.054938 -438.089802)
					(mid 343.245186 -438.089802)
					(end 344.054938 -438.089802)
				)
			)
		)
	)
	(zone
		(layers "B.Cu" "In15.Cu")
		(hatch none 0.5)
		(connect_pads
			(clearance 0)
		)
		(min_thickness 0.25)
		(keepout
			(tracks not_allowed)
			(vias allowed)
			(pads allowed)
			(copperpour not_allowed)
			(footprints allowed)
		)
		(placement
			(enabled no)
			(sheetname "")
		)
		(fill yes
			(thermal_gap 0.5)
			(thermal_bridge_width 0.5)
			(island_removal_mode 0)
		)
		(polygon
			(pts
				(arc
					(start 95.520002 -221.94774)
					(mid 94.867222 -221.94774)
					(end 95.520002 -221.94774)
				)
			)
		)
	)
	(zone
		(layers "B.Cu" "In15.Cu")
		(hatch none 0.5)
		(connect_pads
			(clearance 0)
		)
		(min_thickness 0.25)
		(keepout
			(tracks not_allowed)
			(vias allowed)
			(pads allowed)
			(copperpour not_allowed)
			(footprints allowed)
		)
		(placement
			(enabled no)
			(sheetname "")
		)
		(fill yes
			(thermal_gap 0.5)
			(thermal_bridge_width 0.5)
			(island_removal_mode 0)
		)
		(polygon
			(pts
				(arc
					(start 347.689424 -221.133924)
					(mid 347.036644 -221.133924)
					(end 347.689424 -221.133924)
				)
			)
		)
	)
	(zone
		(layers "B.Cu" "In15.Cu")
		(hatch none 0.5)
		(connect_pads
			(clearance 0)
		)
		(min_thickness 0.25)
		(keepout
			(tracks not_allowed)
			(vias allowed)
			(pads allowed)
			(copperpour not_allowed)
			(footprints allowed)
		)
		(placement
			(enabled no)
			(sheetname "")
		)
		(fill yes
			(thermal_gap 0.5)
			(thermal_bridge_width 0.5)
			(island_removal_mode 0)
		)
		(polygon
			(pts
				(arc
					(start 388.154926 -435.489858)
					(mid 387.345174 -435.489858)
					(end 388.154926 -435.489858)
				)
			)
		)
	)
	(zone
		(layers "B.Cu" "In15.Cu")
		(hatch none 0.5)
		(connect_pads
			(clearance 0)
		)
		(min_thickness 0.25)
		(keepout
			(tracks not_allowed)
			(vias allowed)
			(pads allowed)
			(copperpour not_allowed)
			(footprints allowed)
		)
		(placement
			(enabled no)
			(sheetname "")
		)
		(fill yes
			(thermal_gap 0.5)
			(thermal_bridge_width 0.5)
			(island_removal_mode 0)
		)
		(polygon
			(pts
				(arc
					(start 317.054992 -437.889904)
					(mid 316.24524 -437.889904)
					(end 317.054992 -437.889904)
				)
			)
		)
	)
	(zone
		(layers "B.Cu" "In15.Cu")
		(hatch none 0.5)
		(connect_pads
			(clearance 0)
		)
		(min_thickness 0.25)
		(keepout
			(tracks not_allowed)
			(vias allowed)
			(pads allowed)
			(copperpour not_allowed)
			(footprints allowed)
		)
		(placement
			(enabled no)
			(sheetname "")
		)
		(fill yes
			(thermal_gap 0.5)
			(thermal_bridge_width 0.5)
			(island_removal_mode 0)
		)
		(polygon
			(pts
				(arc
					(start 374.47347 -220.319854)
					(mid 373.82069 -220.319854)
					(end 374.47347 -220.319854)
				)
			)
		)
	)
	(zone
		(layers "B.Cu" "In15.Cu")
		(hatch none 0.5)
		(connect_pads
			(clearance 0)
		)
		(min_thickness 0.25)
		(keepout
			(tracks not_allowed)
			(vias allowed)
			(pads allowed)
			(copperpour not_allowed)
			(footprints allowed)
		)
		(placement
			(enabled no)
			(sheetname "")
		)
		(fill yes
			(thermal_gap 0.5)
			(thermal_bridge_width 0.5)
			(island_removal_mode 0)
		)
		(polygon
			(pts
				(arc
					(start 82.054954 -439.0898)
					(mid 81.245202 -439.0898)
					(end 82.054954 -439.0898)
				)
			)
		)
	)
	(zone
		(layers "B.Cu" "In15.Cu")
		(hatch none 0.5)
		(connect_pads
			(clearance 0)
		)
		(min_thickness 0.25)
		(keepout
			(tracks not_allowed)
			(vias allowed)
			(pads allowed)
			(copperpour not_allowed)
			(footprints allowed)
		)
		(placement
			(enabled no)
			(sheetname "")
		)
		(fill yes
			(thermal_gap 0.5)
			(thermal_bridge_width 0.5)
			(island_removal_mode 0)
		)
		(polygon
			(pts
				(arc
					(start 120.894602 -220.319854)
					(mid 120.241822 -220.319854)
					(end 120.894602 -220.319854)
				)
			)
		)
	)
	(zone
		(layers "B.Cu" "In15.Cu")
		(hatch none 0.5)
		(connect_pads
			(clearance 0)
		)
		(min_thickness 0.25)
		(keepout
			(tracks not_allowed)
			(vias allowed)
			(pads allowed)
			(copperpour not_allowed)
			(footprints allowed)
		)
		(placement
			(enabled no)
			(sheetname "")
		)
		(fill yes
			(thermal_gap 0.5)
			(thermal_bridge_width 0.5)
			(island_removal_mode 0)
		)
		(polygon
			(pts
				(arc
					(start 323.05498 -438.089802)
					(mid 322.245228 -438.089802)
					(end 323.05498 -438.089802)
				)
			)
		)
	)
	(zone
		(layers "B.Cu" "In15.Cu")
		(hatch none 0.5)
		(connect_pads
			(clearance 0)
		)
		(min_thickness 0.25)
		(keepout
			(tracks not_allowed)
			(vias allowed)
			(pads allowed)
			(copperpour not_allowed)
			(footprints allowed)
		)
		(placement
			(enabled no)
			(sheetname "")
		)
		(fill yes
			(thermal_gap 0.5)
			(thermal_bridge_width 0.5)
			(island_removal_mode 0)
		)
		(polygon
			(pts
				(arc
					(start 386.15493 -434.48986)
					(mid 385.345178 -434.48986)
					(end 386.15493 -434.48986)
				)
			)
		)
	)
	(zone
		(layers "B.Cu" "In15.Cu")
		(hatch none 0.5)
		(connect_pads
			(clearance 0)
		)
		(min_thickness 0.25)
		(keepout
			(tracks not_allowed)
			(vias allowed)
			(pads allowed)
			(copperpour not_allowed)
			(footprints allowed)
		)
		(placement
			(enabled no)
			(sheetname "")
		)
		(fill yes
			(thermal_gap 0.5)
			(thermal_bridge_width 0.5)
			(island_removal_mode 0)
		)
		(polygon
			(pts
				(arc
					(start 103.978202 -220.319854)
					(mid 103.325422 -220.319854)
					(end 103.978202 -220.319854)
				)
			)
		)
	)
	(zone
		(layers "B.Cu" "In15.Cu")
		(hatch none 0.5)
		(connect_pads
			(clearance 0)
		)
		(min_thickness 0.25)
		(keepout
			(tracks not_allowed)
			(vias allowed)
			(pads allowed)
			(copperpour not_allowed)
			(footprints allowed)
		)
		(placement
			(enabled no)
			(sheetname "")
		)
		(fill yes
			(thermal_gap 0.5)
			(thermal_bridge_width 0.5)
			(island_removal_mode 0)
		)
		(polygon
			(pts
				(arc
					(start 325.054976 -439.0898)
					(mid 324.245224 -439.0898)
					(end 325.054976 -439.0898)
				)
			)
		)
	)
	(zone
		(layers "B.Cu" "In15.Cu")
		(hatch none 0.5)
		(connect_pads
			(clearance 0)
		)
		(min_thickness 0.25)
		(keepout
			(tracks not_allowed)
			(vias allowed)
			(pads allowed)
			(copperpour not_allowed)
			(footprints allowed)
		)
		(placement
			(enabled no)
			(sheetname "")
		)
		(fill yes
			(thermal_gap 0.5)
			(thermal_bridge_width 0.5)
			(island_removal_mode 0)
		)
		(polygon
			(pts
				(arc
					(start 323.05498 -436.889906)
					(mid 322.245228 -436.889906)
					(end 323.05498 -436.889906)
				)
			)
		)
	)
	(zone
		(layers "B.Cu" "In15.Cu")
		(hatch none 0.5)
		(connect_pads
			(clearance 0)
		)
		(min_thickness 0.25)
		(keepout
			(tracks not_allowed)
			(vias allowed)
			(pads allowed)
			(copperpour not_allowed)
			(footprints allowed)
		)
		(placement
			(enabled no)
			(sheetname "")
		)
		(fill yes
			(thermal_gap 0.5)
			(thermal_bridge_width 0.5)
			(island_removal_mode 0)
		)
		(polygon
			(pts
				(arc
					(start 136.154922 -434.289962)
					(mid 135.34517 -434.289962)
					(end 136.154922 -434.289962)
				)
			)
		)
	)
	(zone
		(layers "B.Cu" "In15.Cu")
		(hatch none 0.5)
		(connect_pads
			(clearance 0)
		)
		(min_thickness 0.25)
		(keepout
			(tracks not_allowed)
			(vias allowed)
			(pads allowed)
			(copperpour not_allowed)
			(footprints allowed)
		)
		(placement
			(enabled no)
			(sheetname "")
		)
		(fill yes
			(thermal_gap 0.5)
			(thermal_bridge_width 0.5)
			(island_removal_mode 0)
		)
		(polygon
			(pts
				(arc
					(start 92.700602 -220.319854)
					(mid 92.047822 -220.319854)
					(end 92.700602 -220.319854)
				)
			)
		)
	)
	(zone
		(layers "B.Cu" "In15.Cu")
		(hatch none 0.5)
		(connect_pads
			(clearance 0)
		)
		(min_thickness 0.25)
		(keepout
			(tracks not_allowed)
			(vias allowed)
			(pads allowed)
			(copperpour not_allowed)
			(footprints allowed)
		)
		(placement
			(enabled no)
			(sheetname "")
		)
		(fill yes
			(thermal_gap 0.5)
			(thermal_bridge_width 0.5)
			(island_removal_mode 0)
		)
		(polygon
			(pts
				(arc
					(start 149.154896 -435.489858)
					(mid 148.345144 -435.489858)
					(end 149.154896 -435.489858)
				)
			)
		)
	)
	(zone
		(layers "B.Cu" "In15.Cu")
		(hatch none 0.5)
		(connect_pads
			(clearance 0)
		)
		(min_thickness 0.25)
		(keepout
			(tracks not_allowed)
			(vias allowed)
			(pads allowed)
			(copperpour not_allowed)
			(footprints allowed)
		)
		(placement
			(enabled no)
			(sheetname "")
		)
		(fill yes
			(thermal_gap 0.5)
			(thermal_bridge_width 0.5)
			(island_removal_mode 0)
		)
		(polygon
			(pts
				(arc
					(start 319.054988 -438.089802)
					(mid 318.245236 -438.089802)
					(end 319.054988 -438.089802)
				)
			)
		)
	)
	(zone
		(layers "B.Cu" "In15.Cu")
		(hatch none 0.5)
		(connect_pads
			(clearance 0)
		)
		(min_thickness 0.25)
		(keepout
			(tracks not_allowed)
			(vias allowed)
			(pads allowed)
			(copperpour not_allowed)
			(footprints allowed)
		)
		(placement
			(enabled no)
			(sheetname "")
		)
		(fill yes
			(thermal_gap 0.5)
			(thermal_bridge_width 0.5)
			(island_removal_mode 0)
		)
		(polygon
			(pts
				(arc
					(start 97.869756 -221.133924)
					(mid 97.216976 -221.133924)
					(end 97.869756 -221.133924)
				)
			)
		)
	)
	(zone
		(layers "B.Cu" "In15.Cu")
		(hatch none 0.5)
		(connect_pads
			(clearance 0)
		)
		(min_thickness 0.25)
		(keepout
			(tracks not_allowed)
			(vias allowed)
			(pads allowed)
			(copperpour not_allowed)
			(footprints allowed)
		)
		(placement
			(enabled no)
			(sheetname "")
		)
		(fill yes
			(thermal_gap 0.5)
			(thermal_bridge_width 0.5)
			(island_removal_mode 0)
		)
		(polygon
			(pts
				(arc
					(start 325.054976 -437.889904)
					(mid 324.245224 -437.889904)
					(end 325.054976 -437.889904)
				)
			)
		)
	)
	(zone
		(layers "B.Cu" "In15.Cu")
		(hatch none 0.5)
		(connect_pads
			(clearance 0)
		)
		(min_thickness 0.25)
		(keepout
			(tracks not_allowed)
			(vias allowed)
			(pads allowed)
			(copperpour not_allowed)
			(footprints allowed)
		)
		(placement
			(enabled no)
			(sheetname "")
		)
		(fill yes
			(thermal_gap 0.5)
			(thermal_bridge_width 0.5)
			(island_removal_mode 0)
		)
		(polygon
			(pts
				(arc
					(start 61.054996 -437.889904)
					(mid 60.245244 -437.889904)
					(end 61.054996 -437.889904)
				)
			)
		)
	)
	(zone
		(layers "B.Cu" "In15.Cu")
		(hatch none 0.5)
		(connect_pads
			(clearance 0)
		)
		(min_thickness 0.25)
		(keepout
			(tracks not_allowed)
			(vias allowed)
			(pads allowed)
			(copperpour not_allowed)
			(footprints allowed)
		)
		(placement
			(enabled no)
			(sheetname "")
		)
		(fill yes
			(thermal_gap 0.5)
			(thermal_bridge_width 0.5)
			(island_removal_mode 0)
		)
		(polygon
			(pts
				(arc
					(start 182.393082 -50.085498)
					(mid 181.689502 -50.085498)
					(end 182.393082 -50.085498)
				)
			)
		)
	)
	(zone
		(layers "B.Cu" "In15.Cu")
		(hatch none 0.5)
		(connect_pads
			(clearance 0)
		)
		(min_thickness 0.25)
		(keepout
			(tracks not_allowed)
			(vias allowed)
			(pads allowed)
			(copperpour not_allowed)
			(footprints allowed)
		)
		(placement
			(enabled no)
			(sheetname "")
		)
		(fill yes
			(thermal_gap 0.5)
			(thermal_bridge_width 0.5)
			(island_removal_mode 0)
		)
		(polygon
			(pts
				(arc
					(start 348.15907 -220.319854)
					(mid 347.50629 -220.319854)
					(end 348.15907 -220.319854)
				)
			)
		)
	)
	(zone
		(layers "B.Cu" "In15.Cu")
		(hatch none 0.5)
		(connect_pads
			(clearance 0)
		)
		(min_thickness 0.25)
		(keepout
			(tracks not_allowed)
			(vias allowed)
			(pads allowed)
			(copperpour not_allowed)
			(footprints allowed)
		)
		(placement
			(enabled no)
			(sheetname "")
		)
		(fill yes
			(thermal_gap 0.5)
			(thermal_bridge_width 0.5)
			(island_removal_mode 0)
		)
		(polygon
			(pts
				(arc
					(start 67.054984 -436.889906)
					(mid 66.245232 -436.889906)
					(end 67.054984 -436.889906)
				)
			)
		)
	)
	(zone
		(layers "B.Cu" "In15.Cu")
		(hatch none 0.5)
		(connect_pads
			(clearance 0)
		)
		(min_thickness 0.25)
		(keepout
			(tracks not_allowed)
			(vias allowed)
			(pads allowed)
			(copperpour not_allowed)
			(footprints allowed)
		)
		(placement
			(enabled no)
			(sheetname "")
		)
		(fill yes
			(thermal_gap 0.5)
			(thermal_bridge_width 0.5)
			(island_removal_mode 0)
		)
		(polygon
			(pts
				(arc
					(start 338.05495 -439.0898)
					(mid 337.245198 -439.0898)
					(end 338.05495 -439.0898)
				)
			)
		)
	)
	(zone
		(layers "B.Cu" "In15.Cu")
		(hatch none 0.5)
		(connect_pads
			(clearance 0)
		)
		(min_thickness 0.25)
		(keepout
			(tracks not_allowed)
			(vias allowed)
			(pads allowed)
			(copperpour not_allowed)
			(footprints allowed)
		)
		(placement
			(enabled no)
			(sheetname "")
		)
		(fill yes
			(thermal_gap 0.5)
			(thermal_bridge_width 0.5)
			(island_removal_mode 0)
		)
		(polygon
			(pts
				(arc
					(start 370.244624 -221.133924)
					(mid 369.591844 -221.133924)
					(end 370.244624 -221.133924)
				)
			)
		)
	)
	(zone
		(layers "B.Cu" "In15.Cu")
		(hatch none 0.5)
		(connect_pads
			(clearance 0)
		)
		(min_thickness 0.25)
		(keepout
			(tracks not_allowed)
			(vias allowed)
			(pads allowed)
			(copperpour not_allowed)
			(footprints allowed)
		)
		(placement
			(enabled no)
			(sheetname "")
		)
		(fill yes
			(thermal_gap 0.5)
			(thermal_bridge_width 0.5)
			(island_removal_mode 0)
		)
		(polygon
			(pts
				(arc
					(start 341.110824 -221.133924)
					(mid 340.458044 -221.133924)
					(end 341.110824 -221.133924)
				)
			)
		)
	)
	(zone
		(layers "B.Cu" "In15.Cu")
		(hatch none 0.5)
		(connect_pads
			(clearance 0)
		)
		(min_thickness 0.25)
		(keepout
			(tracks not_allowed)
			(vias allowed)
			(pads allowed)
			(copperpour not_allowed)
			(footprints allowed)
		)
		(placement
			(enabled no)
			(sheetname "")
		)
		(fill yes
			(thermal_gap 0.5)
			(thermal_bridge_width 0.5)
			(island_removal_mode 0)
		)
		(polygon
			(pts
				(arc
					(start 122.304556 -221.133924)
					(mid 121.651776 -221.133924)
					(end 122.304556 -221.133924)
				)
			)
		)
	)
	(zone
		(layers "B.Cu" "In15.Cu")
		(hatch none 0.5)
		(connect_pads
			(clearance 0)
		)
		(min_thickness 0.25)
		(keepout
			(tracks not_allowed)
			(vias allowed)
			(pads allowed)
			(copperpour not_allowed)
			(footprints allowed)
		)
		(placement
			(enabled no)
			(sheetname "")
		)
		(fill yes
			(thermal_gap 0.5)
			(thermal_bridge_width 0.5)
			(island_removal_mode 0)
		)
		(polygon
			(pts
				(arc
					(start 376.823224 -221.133924)
					(mid 376.170444 -221.133924)
					(end 376.823224 -221.133924)
				)
			)
		)
	)
	(zone
		(layers "B.Cu" "In15.Cu")
		(hatch none 0.5)
		(connect_pads
			(clearance 0)
		)
		(min_thickness 0.25)
		(keepout
			(tracks not_allowed)
			(vias allowed)
			(pads allowed)
			(copperpour not_allowed)
			(footprints allowed)
		)
		(placement
			(enabled no)
			(sheetname "")
		)
		(fill yes
			(thermal_gap 0.5)
			(thermal_bridge_width 0.5)
			(island_removal_mode 0)
		)
		(polygon
			(pts
				(arc
					(start 73.054972 -439.0898)
					(mid 72.24522 -439.0898)
					(end 73.054972 -439.0898)
				)
			)
		)
	)
	(zone
		(layers "B.Cu" "In15.Cu")
		(hatch none 0.5)
		(connect_pads
			(clearance 0)
		)
		(min_thickness 0.25)
		(keepout
			(tracks not_allowed)
			(vias allowed)
			(pads allowed)
			(copperpour not_allowed)
			(footprints allowed)
		)
		(placement
			(enabled no)
			(sheetname "")
		)
		(fill yes
			(thermal_gap 0.5)
			(thermal_bridge_width 0.5)
			(island_removal_mode 0)
		)
		(polygon
			(pts
				(arc
					(start 332.054962 -438.089802)
					(mid 331.24521 -438.089802)
					(end 332.054962 -438.089802)
				)
			)
		)
	)
	(zone
		(layers "B.Cu" "In15.Cu")
		(hatch none 0.5)
		(connect_pads
			(clearance 0)
		)
		(min_thickness 0.25)
		(keepout
			(tracks not_allowed)
			(vias allowed)
			(pads allowed)
			(copperpour not_allowed)
			(footprints allowed)
		)
		(placement
			(enabled no)
			(sheetname "")
		)
		(fill yes
			(thermal_gap 0.5)
			(thermal_bridge_width 0.5)
			(island_removal_mode 0)
		)
		(polygon
			(pts
				(arc
					(start 95.990156 -221.133924)
					(mid 95.337376 -221.133924)
					(end 95.990156 -221.133924)
				)
			)
		)
	)
	(zone
		(layers "B.Cu" "In15.Cu")
		(hatch none 0.5)
		(connect_pads
			(clearance 0)
		)
		(min_thickness 0.25)
		(keepout
			(tracks not_allowed)
			(vias allowed)
			(pads allowed)
			(copperpour not_allowed)
			(footprints allowed)
		)
		(placement
			(enabled no)
			(sheetname "")
		)
		(fill yes
			(thermal_gap 0.5)
			(thermal_bridge_width 0.5)
			(island_removal_mode 0)
		)
		(polygon
			(pts
				(arc
					(start 71.054976 -438.089802)
					(mid 70.245224 -438.089802)
					(end 71.054976 -438.089802)
				)
			)
		)
	)
	(zone
		(layers "B.Cu" "In15.Cu")
		(hatch none 0.5)
		(connect_pads
			(clearance 0)
		)
		(min_thickness 0.25)
		(keepout
			(tracks not_allowed)
			(vias allowed)
			(pads allowed)
			(copperpour not_allowed)
			(footprints allowed)
		)
		(placement
			(enabled no)
			(sheetname "")
		)
		(fill yes
			(thermal_gap 0.5)
			(thermal_bridge_width 0.5)
			(island_removal_mode 0)
		)
		(polygon
			(pts
				(arc
					(start 86.054946 -439.0898)
					(mid 85.245194 -439.0898)
					(end 86.054946 -439.0898)
				)
			)
		)
	)
	(zone
		(layers "B.Cu" "In15.Cu")
		(hatch none 0.5)
		(connect_pads
			(clearance 0)
		)
		(min_thickness 0.25)
		(keepout
			(tracks not_allowed)
			(vias allowed)
			(pads allowed)
			(copperpour not_allowed)
			(footprints allowed)
		)
		(placement
			(enabled no)
			(sheetname "")
		)
		(fill yes
			(thermal_gap 0.5)
			(thermal_bridge_width 0.5)
			(island_removal_mode 0)
		)
		(polygon
			(pts
				(arc
					(start 153.154888 -435.489858)
					(mid 152.345136 -435.489858)
					(end 153.154888 -435.489858)
				)
			)
		)
	)
	(zone
		(layers "B.Cu" "In15.Cu")
		(hatch none 0.5)
		(connect_pads
			(clearance 0)
		)
		(min_thickness 0.25)
		(keepout
			(tracks not_allowed)
			(vias allowed)
			(pads allowed)
			(copperpour not_allowed)
			(footprints allowed)
		)
		(placement
			(enabled no)
			(sheetname "")
		)
		(fill yes
			(thermal_gap 0.5)
			(thermal_bridge_width 0.5)
			(island_removal_mode 0)
		)
		(polygon
			(pts
				(arc
					(start 390.154922 -434.48986)
					(mid 389.34517 -434.48986)
					(end 390.154922 -434.48986)
				)
			)
		)
	)
	(zone
		(layers "B.Cu" "In15.Cu")
		(hatch none 0.5)
		(connect_pads
			(clearance 0)
		)
		(min_thickness 0.25)
		(keepout
			(tracks not_allowed)
			(vias allowed)
			(pads allowed)
			(copperpour not_allowed)
			(footprints allowed)
		)
		(placement
			(enabled no)
			(sheetname "")
		)
		(fill yes
			(thermal_gap 0.5)
			(thermal_bridge_width 0.5)
			(island_removal_mode 0)
		)
		(polygon
			(pts
				(arc
					(start 76.054966 -436.889906)
					(mid 75.245214 -436.889906)
					(end 76.054966 -436.889906)
				)
			)
		)
	)
	(zone
		(layers "B.Cu" "In15.Cu")
		(hatch none 0.5)
		(connect_pads
			(clearance 0)
		)
		(min_thickness 0.25)
		(keepout
			(tracks not_allowed)
			(vias allowed)
			(pads allowed)
			(copperpour not_allowed)
			(footprints allowed)
		)
		(placement
			(enabled no)
			(sheetname "")
		)
		(fill yes
			(thermal_gap 0.5)
			(thermal_bridge_width 0.5)
			(island_removal_mode 0)
		)
		(polygon
			(pts
				(arc
					(start 384.154934 -434.289962)
					(mid 383.345182 -434.289962)
					(end 384.154934 -434.289962)
				)
			)
		)
	)
	(zone
		(layers "B.Cu" "In15.Cu")
		(hatch none 0.5)
		(connect_pads
			(clearance 0)
		)
		(min_thickness 0.25)
		(keepout
			(tracks not_allowed)
			(vias allowed)
			(pads allowed)
			(copperpour not_allowed)
			(footprints allowed)
		)
		(placement
			(enabled no)
			(sheetname "")
		)
		(fill yes
			(thermal_gap 0.5)
			(thermal_bridge_width 0.5)
			(island_removal_mode 0)
		)
		(polygon
			(pts
				(arc
					(start 99.749356 -221.133924)
					(mid 99.096576 -221.133924)
					(end 99.749356 -221.133924)
				)
			)
		)
	)
	(zone
		(layers "B.Cu" "In15.Cu")
		(hatch none 0.5)
		(connect_pads
			(clearance 0)
		)
		(min_thickness 0.25)
		(keepout
			(tracks not_allowed)
			(vias allowed)
			(pads allowed)
			(copperpour not_allowed)
			(footprints allowed)
		)
		(placement
			(enabled no)
			(sheetname "")
		)
		(fill yes
			(thermal_gap 0.5)
			(thermal_bridge_width 0.5)
			(island_removal_mode 0)
		)
		(polygon
			(pts
				(arc
					(start 394.154914 -434.48986)
					(mid 393.345162 -434.48986)
					(end 394.154914 -434.48986)
				)
			)
		)
	)
	(zone
		(layers "B.Cu" "In15.Cu")
		(hatch none 0.5)
		(connect_pads
			(clearance 0)
		)
		(min_thickness 0.25)
		(keepout
			(tracks not_allowed)
			(vias allowed)
			(pads allowed)
			(copperpour not_allowed)
			(footprints allowed)
		)
		(placement
			(enabled no)
			(sheetname "")
		)
		(fill yes
			(thermal_gap 0.5)
			(thermal_bridge_width 0.5)
			(island_removal_mode 0)
		)
		(polygon
			(pts
				(arc
					(start 411.15488 -434.48986)
					(mid 410.345128 -434.48986)
					(end 411.15488 -434.48986)
				)
			)
		)
	)
	(zone
		(layers "B.Cu" "In15.Cu")
		(hatch none 0.5)
		(connect_pads
			(clearance 0)
		)
		(min_thickness 0.25)
		(keepout
			(tracks not_allowed)
			(vias allowed)
			(pads allowed)
			(copperpour not_allowed)
			(footprints allowed)
		)
		(placement
			(enabled no)
			(sheetname "")
		)
		(fill yes
			(thermal_gap 0.5)
			(thermal_bridge_width 0.5)
			(island_removal_mode 0)
		)
		(polygon
			(pts
				(arc
					(start 80.054958 -438.089802)
					(mid 79.245206 -438.089802)
					(end 80.054958 -438.089802)
				)
			)
		)
	)
	(zone
		(layers "B.Cu" "In15.Cu")
		(hatch none 0.5)
		(connect_pads
			(clearance 0)
		)
		(min_thickness 0.25)
		(keepout
			(tracks not_allowed)
			(vias allowed)
			(pads allowed)
			(copperpour not_allowed)
			(footprints allowed)
		)
		(placement
			(enabled no)
			(sheetname "")
		)
		(fill yes
			(thermal_gap 0.5)
			(thermal_bridge_width 0.5)
			(island_removal_mode 0)
		)
		(polygon
			(pts
				(arc
					(start 127.943356 -221.133924)
					(mid 127.290576 -221.133924)
					(end 127.943356 -221.133924)
				)
			)
		)
	)
	(zone
		(layers "B.Cu" "In15.Cu")
		(hatch none 0.5)
		(connect_pads
			(clearance 0)
		)
		(min_thickness 0.25)
		(keepout
			(tracks not_allowed)
			(vias allowed)
			(pads allowed)
			(copperpour not_allowed)
			(footprints allowed)
		)
		(placement
			(enabled no)
			(sheetname "")
		)
		(fill yes
			(thermal_gap 0.5)
			(thermal_bridge_width 0.5)
			(island_removal_mode 0)
		)
		(polygon
			(pts
				(arc
					(start 341.58047 -221.94774)
					(mid 340.92769 -221.94774)
					(end 341.58047 -221.94774)
				)
			)
		)
	)
	(zone
		(layers "B.Cu" "In15.Cu")
		(hatch none 0.5)
		(connect_pads
			(clearance 0)
		)
		(min_thickness 0.25)
		(keepout
			(tracks not_allowed)
			(vias allowed)
			(pads allowed)
			(copperpour not_allowed)
			(footprints allowed)
		)
		(placement
			(enabled no)
			(sheetname "")
		)
		(fill yes
			(thermal_gap 0.5)
			(thermal_bridge_width 0.5)
			(island_removal_mode 0)
		)
		(polygon
			(pts
				(arc
					(start 319.054988 -436.889906)
					(mid 318.245236 -436.889906)
					(end 319.054988 -436.889906)
				)
			)
		)
	)
	(zone
		(layers "B.Cu" "In15.Cu")
		(hatch none 0.5)
		(connect_pads
			(clearance 0)
		)
		(min_thickness 0.25)
		(keepout
			(tracks not_allowed)
			(vias allowed)
			(pads allowed)
			(copperpour not_allowed)
			(footprints allowed)
		)
		(placement
			(enabled no)
			(sheetname "")
		)
		(fill yes
			(thermal_gap 0.5)
			(thermal_bridge_width 0.5)
			(island_removal_mode 0)
		)
		(polygon
			(pts
				(arc
					(start 347.21927 -221.94774)
					(mid 346.56649 -221.94774)
					(end 347.21927 -221.94774)
				)
			)
		)
	)
	(zone
		(layers "B.Cu" "In15.Cu")
		(hatch none 0.5)
		(connect_pads
			(clearance 0)
		)
		(min_thickness 0.25)
		(keepout
			(tracks not_allowed)
			(vias allowed)
			(pads allowed)
			(copperpour not_allowed)
			(footprints allowed)
		)
		(placement
			(enabled no)
			(sheetname "")
		)
		(fill yes
			(thermal_gap 0.5)
			(thermal_bridge_width 0.5)
			(island_removal_mode 0)
		)
		(polygon
			(pts
				(arc
					(start 382.462024 -221.133924)
					(mid 381.809244 -221.133924)
					(end 382.462024 -221.133924)
				)
			)
		)
	)
	(zone
		(layers "B.Cu" "In15.Cu")
		(hatch none 0.5)
		(connect_pads
			(clearance 0)
		)
		(min_thickness 0.25)
		(keepout
			(tracks not_allowed)
			(vias allowed)
			(pads allowed)
			(copperpour not_allowed)
			(footprints allowed)
		)
		(placement
			(enabled no)
			(sheetname "")
		)
		(fill yes
			(thermal_gap 0.5)
			(thermal_bridge_width 0.5)
			(island_removal_mode 0)
		)
		(polygon
			(pts
				(arc
					(start 134.154926 -433.289964)
					(mid 133.345174 -433.289964)
					(end 134.154926 -433.289964)
				)
			)
		)
	)
	(zone
		(layers "B.Cu" "In15.Cu")
		(hatch none 0.5)
		(connect_pads
			(clearance 0)
		)
		(min_thickness 0.25)
		(keepout
			(tracks not_allowed)
			(vias allowed)
			(pads allowed)
			(copperpour not_allowed)
			(footprints allowed)
		)
		(placement
			(enabled no)
			(sheetname "")
		)
		(fill yes
			(thermal_gap 0.5)
			(thermal_bridge_width 0.5)
			(island_removal_mode 0)
		)
		(polygon
			(pts
				(arc
					(start 88.054942 -436.889906)
					(mid 87.24519 -436.889906)
					(end 88.054942 -436.889906)
				)
			)
		)
	)
	(zone
		(layers "B.Cu" "In15.Cu")
		(hatch none 0.5)
		(connect_pads
			(clearance 0)
		)
		(min_thickness 0.25)
		(keepout
			(tracks not_allowed)
			(vias allowed)
			(pads allowed)
			(copperpour not_allowed)
			(footprints allowed)
		)
		(placement
			(enabled no)
			(sheetname "")
		)
		(fill yes
			(thermal_gap 0.5)
			(thermal_bridge_width 0.5)
			(island_removal_mode 0)
		)
		(polygon
			(pts
				(arc
					(start 65.054988 -437.889904)
					(mid 64.245236 -437.889904)
					(end 65.054988 -437.889904)
				)
			)
		)
	)
	(zone
		(layers "B.Cu" "In15.Cu")
		(hatch none 0.5)
		(connect_pads
			(clearance 0)
		)
		(min_thickness 0.25)
		(keepout
			(tracks not_allowed)
			(vias allowed)
			(pads allowed)
			(copperpour not_allowed)
			(footprints allowed)
		)
		(placement
			(enabled no)
			(sheetname "")
		)
		(fill yes
			(thermal_gap 0.5)
			(thermal_bridge_width 0.5)
			(island_removal_mode 0)
		)
		(polygon
			(pts
				(arc
					(start 373.53367 -221.94774)
					(mid 372.88089 -221.94774)
					(end 373.53367 -221.94774)
				)
			)
		)
	)
	(zone
		(layers "B.Cu" "In15.Cu")
		(hatch none 0.5)
		(connect_pads
			(clearance 0)
		)
		(min_thickness 0.25)
		(keepout
			(tracks not_allowed)
			(vias allowed)
			(pads allowed)
			(copperpour not_allowed)
			(footprints allowed)
		)
		(placement
			(enabled no)
			(sheetname "")
		)
		(fill yes
			(thermal_gap 0.5)
			(thermal_bridge_width 0.5)
			(island_removal_mode 0)
		)
		(polygon
			(pts
				(arc
					(start 155.154884 -433.289964)
					(mid 154.345132 -433.289964)
					(end 155.154884 -433.289964)
				)
			)
		)
	)
	(zone
		(layers "B.Cu" "In15.Cu")
		(hatch none 0.5)
		(connect_pads
			(clearance 0)
		)
		(min_thickness 0.25)
		(keepout
			(tracks not_allowed)
			(vias allowed)
			(pads allowed)
			(copperpour not_allowed)
			(footprints allowed)
		)
		(placement
			(enabled no)
			(sheetname "")
		)
		(fill yes
			(thermal_gap 0.5)
			(thermal_bridge_width 0.5)
			(island_removal_mode 0)
		)
		(polygon
			(pts
				(arc
					(start 401.1549 -435.489858)
					(mid 400.345148 -435.489858)
					(end 401.1549 -435.489858)
				)
			)
		)
	)
	(zone
		(layers "B.Cu" "In15.Cu")
		(hatch none 0.5)
		(connect_pads
			(clearance 0)
		)
		(min_thickness 0.25)
		(keepout
			(tracks not_allowed)
			(vias allowed)
			(pads allowed)
			(copperpour not_allowed)
			(footprints allowed)
		)
		(placement
			(enabled no)
			(sheetname "")
		)
		(fill yes
			(thermal_gap 0.5)
			(thermal_bridge_width 0.5)
			(island_removal_mode 0)
		)
		(polygon
			(pts
				(arc
					(start 339.231224 -221.133924)
					(mid 338.578444 -221.133924)
					(end 339.231224 -221.133924)
				)
			)
		)
	)
	(zone
		(layers "B.Cu" "In15.Cu")
		(hatch none 0.5)
		(connect_pads
			(clearance 0)
		)
		(min_thickness 0.25)
		(keepout
			(tracks not_allowed)
			(vias allowed)
			(pads allowed)
			(copperpour not_allowed)
			(footprints allowed)
		)
		(placement
			(enabled no)
			(sheetname "")
		)
		(fill yes
			(thermal_gap 0.5)
			(thermal_bridge_width 0.5)
			(island_removal_mode 0)
		)
		(polygon
			(pts
				(arc
					(start 380.11227 -220.319854)
					(mid 379.45949 -220.319854)
					(end 380.11227 -220.319854)
				)
			)
		)
	)
	(zone
		(layers "B.Cu" "In15.Cu")
		(hatch none 0.5)
		(connect_pads
			(clearance 0)
		)
		(min_thickness 0.25)
		(keepout
			(tracks not_allowed)
			(vias allowed)
			(pads allowed)
			(copperpour not_allowed)
			(footprints allowed)
		)
		(placement
			(enabled no)
			(sheetname "")
		)
		(fill yes
			(thermal_gap 0.5)
			(thermal_bridge_width 0.5)
			(island_removal_mode 0)
		)
		(polygon
			(pts
				(arc
					(start 392.154918 -434.289962)
					(mid 391.345166 -434.289962)
					(end 392.154918 -434.289962)
				)
			)
		)
	)
	(zone
		(layers "B.Cu" "In15.Cu")
		(hatch none 0.5)
		(connect_pads
			(clearance 0)
		)
		(min_thickness 0.25)
		(keepout
			(tracks not_allowed)
			(vias allowed)
			(pads allowed)
			(copperpour not_allowed)
			(footprints allowed)
		)
		(placement
			(enabled no)
			(sheetname "")
		)
		(fill yes
			(thermal_gap 0.5)
			(thermal_bridge_width 0.5)
			(island_removal_mode 0)
		)
		(polygon
			(pts
				(arc
					(start 63.054992 -438.089802)
					(mid 62.24524 -438.089802)
					(end 63.054992 -438.089802)
				)
			)
		)
	)
	(zone
		(layers "B.Cu" "In15.Cu")
		(hatch none 0.5)
		(connect_pads
			(clearance 0)
		)
		(min_thickness 0.25)
		(keepout
			(tracks not_allowed)
			(vias allowed)
			(pads allowed)
			(copperpour not_allowed)
			(footprints allowed)
		)
		(placement
			(enabled no)
			(sheetname "")
		)
		(fill yes
			(thermal_gap 0.5)
			(thermal_bridge_width 0.5)
			(island_removal_mode 0)
		)
		(polygon
			(pts
				(arc
					(start 88.054942 -438.089802)
					(mid 87.24519 -438.089802)
					(end 88.054942 -438.089802)
				)
			)
		)
	)
	(zone
		(layers "B.Cu" "In15.Cu")
		(hatch none 0.5)
		(connect_pads
			(clearance 0)
		)
		(min_thickness 0.25)
		(keepout
			(tracks not_allowed)
			(vias allowed)
			(pads allowed)
			(copperpour not_allowed)
			(footprints allowed)
		)
		(placement
			(enabled no)
			(sheetname "")
		)
		(fill yes
			(thermal_gap 0.5)
			(thermal_bridge_width 0.5)
			(island_removal_mode 0)
		)
		(polygon
			(pts
				(arc
					(start 129.352802 -221.94774)
					(mid 128.700022 -221.94774)
					(end 129.352802 -221.94774)
				)
			)
		)
	)
	(zone
		(layers "B.Cu" "In15.Cu")
		(hatch none 0.5)
		(connect_pads
			(clearance 0)
		)
		(min_thickness 0.25)
		(keepout
			(tracks not_allowed)
			(vias allowed)
			(pads allowed)
			(copperpour not_allowed)
			(footprints allowed)
		)
		(placement
			(enabled no)
			(sheetname "")
		)
		(fill yes
			(thermal_gap 0.5)
			(thermal_bridge_width 0.5)
			(island_removal_mode 0)
		)
		(polygon
			(pts
				(arc
					(start 86.054946 -437.889904)
					(mid 85.245194 -437.889904)
					(end 86.054946 -437.889904)
				)
			)
		)
	)
	(zone
		(layers "B.Cu" "In15.Cu")
		(hatch none 0.5)
		(connect_pads
			(clearance 0)
		)
		(min_thickness 0.25)
		(keepout
			(tracks not_allowed)
			(vias allowed)
			(pads allowed)
			(copperpour not_allowed)
			(footprints allowed)
		)
		(placement
			(enabled no)
			(sheetname "")
		)
		(fill yes
			(thermal_gap 0.5)
			(thermal_bridge_width 0.5)
			(island_removal_mode 0)
		)
		(polygon
			(pts
				(arc
					(start 132.15493 -435.489858)
					(mid 131.345178 -435.489858)
					(end 132.15493 -435.489858)
				)
			)
		)
	)
	(zone
		(layers "B.Cu" "In15.Cu")
		(hatch none 0.5)
		(connect_pads
			(clearance 0)
		)
		(min_thickness 0.25)
		(keepout
			(tracks not_allowed)
			(vias allowed)
			(pads allowed)
			(copperpour not_allowed)
			(footprints allowed)
		)
		(placement
			(enabled no)
			(sheetname "")
		)
		(fill yes
			(thermal_gap 0.5)
			(thermal_bridge_width 0.5)
			(island_removal_mode 0)
		)
		(polygon
			(pts
				(arc
					(start 317.054992 -439.0898)
					(mid 316.24524 -439.0898)
					(end 317.054992 -439.0898)
				)
			)
		)
	)
	(zone
		(layers "B.Cu" "In15.Cu")
		(hatch none 0.5)
		(connect_pads
			(clearance 0)
		)
		(min_thickness 0.25)
		(keepout
			(tracks not_allowed)
			(vias allowed)
			(pads allowed)
			(copperpour not_allowed)
			(footprints allowed)
		)
		(placement
			(enabled no)
			(sheetname "")
		)
		(fill yes
			(thermal_gap 0.5)
			(thermal_bridge_width 0.5)
			(island_removal_mode 0)
		)
		(polygon
			(pts
				(arc
					(start 343.875868 -42.811192)
					(mid 343.223088 -42.811192)
					(end 343.875868 -42.811192)
				)
			)
		)
	)
	(zone
		(layers "B.Cu" "In15.Cu")
		(hatch none 0.5)
		(connect_pads
			(clearance 0)
		)
		(min_thickness 0.25)
		(keepout
			(tracks not_allowed)
			(vias allowed)
			(pads allowed)
			(copperpour not_allowed)
			(footprints allowed)
		)
		(placement
			(enabled no)
			(sheetname "")
		)
		(fill yes
			(thermal_gap 0.5)
			(thermal_bridge_width 0.5)
			(island_removal_mode 0)
		)
		(polygon
			(pts
				(arc
					(start 343.061544 -45.160692)
					(mid 342.408764 -45.160692)
					(end 343.061544 -45.160692)
				)
			)
		)
	)
	(zone
		(layers "B.Cu" "In15.Cu")
		(hatch none 0.5)
		(connect_pads
			(clearance 0)
		)
		(min_thickness 0.25)
		(keepout
			(tracks not_allowed)
			(vias allowed)
			(pads allowed)
			(copperpour not_allowed)
			(footprints allowed)
		)
		(placement
			(enabled no)
			(sheetname "")
		)
		(fill yes
			(thermal_gap 0.5)
			(thermal_bridge_width 0.5)
			(island_removal_mode 0)
		)
		(polygon
			(pts
				(arc
					(start 128.154938 -434.289962)
					(mid 127.345186 -434.289962)
					(end 128.154938 -434.289962)
				)
			)
		)
	)
	(zone
		(layers "B.Cu" "In15.Cu")
		(hatch none 0.5)
		(connect_pads
			(clearance 0)
		)
		(min_thickness 0.25)
		(keepout
			(tracks not_allowed)
			(vias allowed)
			(pads allowed)
			(copperpour not_allowed)
			(footprints allowed)
		)
		(placement
			(enabled no)
			(sheetname "")
		)
		(fill yes
			(thermal_gap 0.5)
			(thermal_bridge_width 0.5)
			(island_removal_mode 0)
		)
		(polygon
			(pts
				(arc
					(start 340.64067 -220.319854)
					(mid 339.98789 -220.319854)
					(end 340.64067 -220.319854)
				)
			)
		)
	)
	(zone
		(layers "B.Cu" "In15.Cu")
		(hatch none 0.5)
		(connect_pads
			(clearance 0)
		)
		(min_thickness 0.25)
		(keepout
			(tracks not_allowed)
			(vias allowed)
			(pads allowed)
			(copperpour not_allowed)
			(footprints allowed)
		)
		(placement
			(enabled no)
			(sheetname "")
		)
		(fill yes
			(thermal_gap 0.5)
			(thermal_bridge_width 0.5)
			(island_removal_mode 0)
		)
		(polygon
			(pts
				(arc
					(start 153.154888 -434.289962)
					(mid 152.345136 -434.289962)
					(end 153.154888 -434.289962)
				)
			)
		)
	)
	(zone
		(layers "B.Cu" "In15.Cu")
		(hatch none 0.5)
		(connect_pads
			(clearance 0)
		)
		(min_thickness 0.25)
		(keepout
			(tracks not_allowed)
			(vias allowed)
			(pads allowed)
			(copperpour not_allowed)
			(footprints allowed)
		)
		(placement
			(enabled no)
			(sheetname "")
		)
		(fill yes
			(thermal_gap 0.5)
			(thermal_bridge_width 0.5)
			(island_removal_mode 0)
		)
		(polygon
			(pts
				(arc
					(start 327.054972 -436.889906)
					(mid 326.24522 -436.889906)
					(end 327.054972 -436.889906)
				)
			)
		)
	)
	(zone
		(layers "B.Cu" "In15.Cu")
		(hatch none 0.5)
		(connect_pads
			(clearance 0)
		)
		(min_thickness 0.25)
		(keepout
			(tracks not_allowed)
			(vias allowed)
			(pads allowed)
			(copperpour not_allowed)
			(footprints allowed)
		)
		(placement
			(enabled no)
			(sheetname "")
		)
		(fill yes
			(thermal_gap 0.5)
			(thermal_bridge_width 0.5)
			(island_removal_mode 0)
		)
		(polygon
			(pts
				(arc
					(start 399.154904 -433.289964)
					(mid 398.345152 -433.289964)
					(end 399.154904 -433.289964)
				)
			)
		)
	)
	(zone
		(layers "B.Cu" "In15.Cu")
		(hatch none 0.5)
		(connect_pads
			(clearance 0)
		)
		(min_thickness 0.25)
		(keepout
			(tracks not_allowed)
			(vias allowed)
			(pads allowed)
			(copperpour not_allowed)
			(footprints allowed)
		)
		(placement
			(enabled no)
			(sheetname "")
		)
		(fill yes
			(thermal_gap 0.5)
			(thermal_bridge_width 0.5)
			(island_removal_mode 0)
		)
		(polygon
			(pts
				(arc
					(start 98.339402 -220.319854)
					(mid 97.686622 -220.319854)
					(end 98.339402 -220.319854)
				)
			)
		)
	)
	(zone
		(layers "B.Cu" "In15.Cu")
		(hatch none 0.5)
		(connect_pads
			(clearance 0)
		)
		(min_thickness 0.25)
		(keepout
			(tracks not_allowed)
			(vias allowed)
			(pads allowed)
			(copperpour not_allowed)
			(footprints allowed)
		)
		(placement
			(enabled no)
			(sheetname "")
		)
		(fill yes
			(thermal_gap 0.5)
			(thermal_bridge_width 0.5)
			(island_removal_mode 0)
		)
		(polygon
			(pts
				(arc
					(start 123.244356 -221.133924)
					(mid 122.591576 -221.133924)
					(end 123.244356 -221.133924)
				)
			)
		)
	)
	(zone
		(layers "B.Cu" "In15.Cu")
		(hatch none 0.5)
		(connect_pads
			(clearance 0)
		)
		(min_thickness 0.25)
		(keepout
			(tracks not_allowed)
			(vias allowed)
			(pads allowed)
			(copperpour not_allowed)
			(footprints allowed)
		)
		(placement
			(enabled no)
			(sheetname "")
		)
		(fill yes
			(thermal_gap 0.5)
			(thermal_bridge_width 0.5)
			(island_removal_mode 0)
		)
		(polygon
			(pts
				(arc
					(start 342.054942 -439.0898)
					(mid 341.24519 -439.0898)
					(end 342.054942 -439.0898)
				)
			)
		)
	)
	(zone
		(layers "B.Cu" "In15.Cu")
		(hatch none 0.5)
		(connect_pads
			(clearance 0)
		)
		(min_thickness 0.25)
		(keepout
			(tracks not_allowed)
			(vias allowed)
			(pads allowed)
			(copperpour not_allowed)
			(footprints allowed)
		)
		(placement
			(enabled no)
			(sheetname "")
		)
		(fill yes
			(thermal_gap 0.5)
			(thermal_bridge_width 0.5)
			(island_removal_mode 0)
		)
		(polygon
			(pts
				(arc
					(start 381.522224 -221.133924)
					(mid 380.869444 -221.133924)
					(end 381.522224 -221.133924)
				)
			)
		)
	)
	(zone
		(layers "B.Cu" "In15.Cu")
		(hatch none 0.5)
		(connect_pads
			(clearance 0)
		)
		(min_thickness 0.25)
		(keepout
			(tracks not_allowed)
			(vias allowed)
			(pads allowed)
			(copperpour not_allowed)
			(footprints allowed)
		)
		(placement
			(enabled no)
			(sheetname "")
		)
		(fill yes
			(thermal_gap 0.5)
			(thermal_bridge_width 0.5)
			(island_removal_mode 0)
		)
		(polygon
			(pts
				(arc
					(start 381.05207 -221.94774)
					(mid 380.39929 -221.94774)
					(end 381.05207 -221.94774)
				)
			)
		)
	)
	(zone
		(layers "B.Cu" "In15.Cu")
		(hatch none 0.5)
		(connect_pads
			(clearance 0)
		)
		(min_thickness 0.25)
		(keepout
			(tracks not_allowed)
			(vias allowed)
			(pads allowed)
			(copperpour not_allowed)
			(footprints allowed)
		)
		(placement
			(enabled no)
			(sheetname "")
		)
		(fill yes
			(thermal_gap 0.5)
			(thermal_bridge_width 0.5)
			(island_removal_mode 0)
		)
		(polygon
			(pts
				(arc
					(start 343.875868 -43.750992)
					(mid 343.223088 -43.750992)
					(end 343.875868 -43.750992)
				)
			)
		)
	)
	(zone
		(layers "B.Cu" "In15.Cu")
		(hatch none 0.5)
		(connect_pads
			(clearance 0)
		)
		(min_thickness 0.25)
		(keepout
			(tracks not_allowed)
			(vias allowed)
			(pads allowed)
			(copperpour not_allowed)
			(footprints allowed)
		)
		(placement
			(enabled no)
			(sheetname "")
		)
		(fill yes
			(thermal_gap 0.5)
			(thermal_bridge_width 0.5)
			(island_removal_mode 0)
		)
		(polygon
			(pts
				(arc
					(start 411.15488 -433.289964)
					(mid 410.345128 -433.289964)
					(end 411.15488 -433.289964)
				)
			)
		)
	)
	(zone
		(layers "B.Cu" "In15.Cu")
		(hatch none 0.5)
		(connect_pads
			(clearance 0)
		)
		(min_thickness 0.25)
		(keepout
			(tracks not_allowed)
			(vias allowed)
			(pads allowed)
			(copperpour not_allowed)
			(footprints allowed)
		)
		(placement
			(enabled no)
			(sheetname "")
		)
		(fill yes
			(thermal_gap 0.5)
			(thermal_bridge_width 0.5)
			(island_removal_mode 0)
		)
		(polygon
			(pts
				(arc
					(start 401.1549 -434.289962)
					(mid 400.345148 -434.289962)
					(end 401.1549 -434.289962)
				)
			)
		)
	)
	(zone
		(layers "B.Cu" "In15.Cu")
		(hatch none 0.5)
		(connect_pads
			(clearance 0)
		)
		(min_thickness 0.25)
		(keepout
			(tracks not_allowed)
			(vias allowed)
			(pads allowed)
			(copperpour not_allowed)
			(footprints allowed)
		)
		(placement
			(enabled no)
			(sheetname "")
		)
		(fill yes
			(thermal_gap 0.5)
			(thermal_bridge_width 0.5)
			(island_removal_mode 0)
		)
		(polygon
			(pts
				(arc
					(start 73.054972 -437.889904)
					(mid 72.24522 -437.889904)
					(end 73.054972 -437.889904)
				)
			)
		)
	)
	(zone
		(layers "B.Cu" "In15.Cu")
		(hatch none 0.5)
		(connect_pads
			(clearance 0)
		)
		(min_thickness 0.25)
		(keepout
			(tracks not_allowed)
			(vias allowed)
			(pads allowed)
			(copperpour not_allowed)
			(footprints allowed)
		)
		(placement
			(enabled no)
			(sheetname "")
		)
		(fill yes
			(thermal_gap 0.5)
			(thermal_bridge_width 0.5)
			(island_removal_mode 0)
		)
		(polygon
			(pts
				(arc
					(start 97.399602 -221.94774)
					(mid 96.746822 -221.94774)
					(end 97.399602 -221.94774)
				)
			)
		)
	)
	(zone
		(layers "B.Cu" "In15.Cu")
		(hatch none 0.5)
		(connect_pads
			(clearance 0)
		)
		(min_thickness 0.25)
		(keepout
			(tracks not_allowed)
			(vias allowed)
			(pads allowed)
			(copperpour not_allowed)
			(footprints allowed)
		)
		(placement
			(enabled no)
			(sheetname "")
		)
		(fill yes
			(thermal_gap 0.5)
			(thermal_bridge_width 0.5)
			(island_removal_mode 0)
		)
		(polygon
			(pts
				(arc
					(start 151.154892 -433.289964)
					(mid 150.34514 -433.289964)
					(end 151.154892 -433.289964)
				)
			)
		)
	)
	(zone
		(layers "B.Cu" "In15.Cu")
		(hatch none 0.5)
		(connect_pads
			(clearance 0)
		)
		(min_thickness 0.25)
		(keepout
			(tracks not_allowed)
			(vias allowed)
			(pads allowed)
			(copperpour not_allowed)
			(footprints allowed)
		)
		(placement
			(enabled no)
			(sheetname "")
		)
		(fill yes
			(thermal_gap 0.5)
			(thermal_bridge_width 0.5)
			(island_removal_mode 0)
		)
		(polygon
			(pts
				(arc
					(start 337.351624 -221.133924)
					(mid 336.698844 -221.133924)
					(end 337.351624 -221.133924)
				)
			)
		)
	)
	(zone
		(layers "B.Cu" "In15.Cu")
		(hatch none 0.5)
		(connect_pads
			(clearance 0)
		)
		(min_thickness 0.25)
		(keepout
			(tracks not_allowed)
			(vias allowed)
			(pads allowed)
			(copperpour not_allowed)
			(footprints allowed)
		)
		(placement
			(enabled no)
			(sheetname "")
		)
		(fill yes
			(thermal_gap 0.5)
			(thermal_bridge_width 0.5)
			(island_removal_mode 0)
		)
		(polygon
			(pts
				(arc
					(start 182.393082 -47.164498)
					(mid 181.689502 -47.164498)
					(end 182.393082 -47.164498)
				)
			)
		)
	)
	(zone
		(layers "B.Cu" "In15.Cu")
		(hatch none 0.5)
		(connect_pads
			(clearance 0)
		)
		(min_thickness 0.25)
		(keepout
			(tracks not_allowed)
			(vias allowed)
			(pads allowed)
			(copperpour not_allowed)
			(footprints allowed)
		)
		(placement
			(enabled no)
			(sheetname "")
		)
		(fill yes
			(thermal_gap 0.5)
			(thermal_bridge_width 0.5)
			(island_removal_mode 0)
		)
		(polygon
			(pts
				(arc
					(start 96.459802 -220.319854)
					(mid 95.807022 -220.319854)
					(end 96.459802 -220.319854)
				)
			)
		)
	)
	(zone
		(layers "B.Cu" "In15.Cu")
		(hatch none 0.5)
		(connect_pads
			(clearance 0)
		)
		(min_thickness 0.25)
		(keepout
			(tracks not_allowed)
			(vias allowed)
			(pads allowed)
			(copperpour not_allowed)
			(footprints allowed)
		)
		(placement
			(enabled no)
			(sheetname "")
		)
		(fill yes
			(thermal_gap 0.5)
			(thermal_bridge_width 0.5)
			(island_removal_mode 0)
		)
		(polygon
			(pts
				(arc
					(start 344.689938 -42.341292)
					(mid 344.037158 -42.341292)
					(end 344.689938 -42.341292)
				)
			)
		)
	)
	(zone
		(layers "B.Cu" "In15.Cu")
		(hatch none 0.5)
		(connect_pads
			(clearance 0)
		)
		(min_thickness 0.25)
		(keepout
			(tracks not_allowed)
			(vias allowed)
			(pads allowed)
			(copperpour not_allowed)
			(footprints allowed)
		)
		(placement
			(enabled no)
			(sheetname "")
		)
		(fill yes
			(thermal_gap 0.5)
			(thermal_bridge_width 0.5)
			(island_removal_mode 0)
		)
		(polygon
			(pts
				(arc
					(start 89.411556 -221.133924)
					(mid 88.758776 -221.133924)
					(end 89.411556 -221.133924)
				)
			)
		)
	)
	(zone
		(layers "B.Cu" "In15.Cu")
		(hatch none 0.5)
		(connect_pads
			(clearance 0)
		)
		(min_thickness 0.25)
		(keepout
			(tracks not_allowed)
			(vias allowed)
			(pads allowed)
			(copperpour not_allowed)
			(footprints allowed)
		)
		(placement
			(enabled no)
			(sheetname "")
		)
		(fill yes
			(thermal_gap 0.5)
			(thermal_bridge_width 0.5)
			(island_removal_mode 0)
		)
		(polygon
			(pts
				(arc
					(start 369.77447 -221.94774)
					(mid 369.12169 -221.94774)
					(end 369.77447 -221.94774)
				)
			)
		)
	)
	(zone
		(layers "B.Cu" "In15.Cu")
		(hatch none 0.5)
		(connect_pads
			(clearance 0)
		)
		(min_thickness 0.25)
		(keepout
			(tracks not_allowed)
			(vias allowed)
			(pads allowed)
			(copperpour not_allowed)
			(footprints allowed)
		)
		(placement
			(enabled no)
			(sheetname "")
		)
		(fill yes
			(thermal_gap 0.5)
			(thermal_bridge_width 0.5)
			(island_removal_mode 0)
		)
		(polygon
			(pts
				(arc
					(start 90.054938 -439.0898)
					(mid 89.245186 -439.0898)
					(end 90.054938 -439.0898)
				)
			)
		)
	)
	(zone
		(layers "B.Cu" "In15.Cu")
		(hatch none 0.5)
		(connect_pads
			(clearance 0)
		)
		(min_thickness 0.25)
		(keepout
			(tracks not_allowed)
			(vias allowed)
			(pads allowed)
			(copperpour not_allowed)
			(footprints allowed)
		)
		(placement
			(enabled no)
			(sheetname "")
		)
		(fill yes
			(thermal_gap 0.5)
			(thermal_bridge_width 0.5)
			(island_removal_mode 0)
		)
		(polygon
			(pts
				(arc
					(start 321.054984 -439.0898)
					(mid 320.245232 -439.0898)
					(end 321.054984 -439.0898)
				)
			)
		)
	)
	(zone
		(layers "B.Cu" "In15.Cu")
		(hatch none 0.5)
		(connect_pads
			(clearance 0)
		)
		(min_thickness 0.25)
		(keepout
			(tracks not_allowed)
			(vias allowed)
			(pads allowed)
			(copperpour not_allowed)
			(footprints allowed)
		)
		(placement
			(enabled no)
			(sheetname "")
		)
		(fill yes
			(thermal_gap 0.5)
			(thermal_bridge_width 0.5)
			(island_removal_mode 0)
		)
		(polygon
			(pts
				(arc
					(start 409.154884 -435.489858)
					(mid 408.345132 -435.489858)
					(end 409.154884 -435.489858)
				)
			)
		)
	)
	(zone
		(layers "B.Cu" "In15.Cu")
		(hatch none 0.5)
		(connect_pads
			(clearance 0)
		)
		(min_thickness 0.25)
		(keepout
			(tracks not_allowed)
			(vias allowed)
			(pads allowed)
			(copperpour not_allowed)
			(footprints allowed)
		)
		(placement
			(enabled no)
			(sheetname "")
		)
		(fill yes
			(thermal_gap 0.5)
			(thermal_bridge_width 0.5)
			(island_removal_mode 0)
		)
		(polygon
			(pts
				(arc
					(start 343.061544 -44.220892)
					(mid 342.408764 -44.220892)
					(end 343.061544 -44.220892)
				)
			)
		)
	)
	(zone
		(layers "B.Cu" "In15.Cu")
		(hatch none 0.5)
		(connect_pads
			(clearance 0)
		)
		(min_thickness 0.25)
		(keepout
			(tracks not_allowed)
			(vias allowed)
			(pads allowed)
			(copperpour not_allowed)
			(footprints allowed)
		)
		(placement
			(enabled no)
			(sheetname "")
		)
		(fill yes
			(thermal_gap 0.5)
			(thermal_bridge_width 0.5)
			(island_removal_mode 0)
		)
		(polygon
			(pts
				(arc
					(start 407.154888 -433.289964)
					(mid 406.345136 -433.289964)
					(end 407.154888 -433.289964)
				)
			)
		)
	)
	(zone
		(layers "B.Cu" "In15.Cu")
		(hatch none 0.5)
		(connect_pads
			(clearance 0)
		)
		(min_thickness 0.25)
		(keepout
			(tracks not_allowed)
			(vias allowed)
			(pads allowed)
			(copperpour not_allowed)
			(footprints allowed)
		)
		(placement
			(enabled no)
			(sheetname "")
		)
		(fill yes
			(thermal_gap 0.5)
			(thermal_bridge_width 0.5)
			(island_removal_mode 0)
		)
		(polygon
			(pts
				(arc
					(start 59.055 -436.889906)
					(mid 58.245248 -436.889906)
					(end 59.055 -436.889906)
				)
			)
		)
	)
	(zone
		(layers "B.Cu" "In15.Cu")
		(hatch none 0.5)
		(connect_pads
			(clearance 0)
		)
		(min_thickness 0.25)
		(keepout
			(tracks not_allowed)
			(vias allowed)
			(pads allowed)
			(copperpour not_allowed)
			(footprints allowed)
		)
		(placement
			(enabled no)
			(sheetname "")
		)
		(fill yes
			(thermal_gap 0.5)
			(thermal_bridge_width 0.5)
			(island_removal_mode 0)
		)
		(polygon
			(pts
				(arc
					(start 182.393082 -44.980098)
					(mid 181.689502 -44.980098)
					(end 182.393082 -44.980098)
				)
			)
		)
	)
	(zone
		(layers "B.Cu" "In15.Cu")
		(hatch none 0.5)
		(connect_pads
			(clearance 0)
		)
		(min_thickness 0.25)
		(keepout
			(tracks not_allowed)
			(vias allowed)
			(pads allowed)
			(copperpour not_allowed)
			(footprints allowed)
		)
		(placement
			(enabled no)
			(sheetname "")
		)
		(fill yes
			(thermal_gap 0.5)
			(thermal_bridge_width 0.5)
			(island_removal_mode 0)
		)
		(polygon
			(pts
				(arc
					(start 135.461756 -221.133924)
					(mid 134.808976 -221.133924)
					(end 135.461756 -221.133924)
				)
			)
		)
	)
	(zone
		(layers "B.Cu" "In15.Cu")
		(hatch none 0.5)
		(connect_pads
			(clearance 0)
		)
		(min_thickness 0.25)
		(keepout
			(tracks not_allowed)
			(vias allowed)
			(pads allowed)
			(copperpour not_allowed)
			(footprints allowed)
		)
		(placement
			(enabled no)
			(sheetname "")
		)
		(fill yes
			(thermal_gap 0.5)
			(thermal_bridge_width 0.5)
			(island_removal_mode 0)
		)
		(polygon
			(pts
				(arc
					(start 388.154926 -434.289962)
					(mid 387.345174 -434.289962)
					(end 388.154926 -434.289962)
				)
			)
		)
	)
	(zone
		(layers "B.Cu" "In15.Cu")
		(hatch none 0.5)
		(connect_pads
			(clearance 0)
		)
		(min_thickness 0.25)
		(keepout
			(tracks not_allowed)
			(vias allowed)
			(pads allowed)
			(copperpour not_allowed)
			(footprints allowed)
		)
		(placement
			(enabled no)
			(sheetname "")
		)
		(fill yes
			(thermal_gap 0.5)
			(thermal_bridge_width 0.5)
			(island_removal_mode 0)
		)
		(polygon
			(pts
				(arc
					(start 130.154934 -434.48986)
					(mid 129.345182 -434.48986)
					(end 130.154934 -434.48986)
				)
			)
		)
	)
	(zone
		(layers "B.Cu" "In15.Cu")
		(hatch none 0.5)
		(connect_pads
			(clearance 0)
		)
		(min_thickness 0.25)
		(keepout
			(tracks not_allowed)
			(vias allowed)
			(pads allowed)
			(copperpour not_allowed)
			(footprints allowed)
		)
		(placement
			(enabled no)
			(sheetname "")
		)
		(fill yes
			(thermal_gap 0.5)
			(thermal_bridge_width 0.5)
			(island_removal_mode 0)
		)
		(polygon
			(pts
				(arc
					(start 334.054958 -437.889904)
					(mid 333.245206 -437.889904)
					(end 334.054958 -437.889904)
				)
			)
		)
	)
	(zone
		(layers "B.Cu" "In15.Cu")
		(hatch none 0.5)
		(connect_pads
			(clearance 0)
		)
		(min_thickness 0.25)
		(keepout
			(tracks not_allowed)
			(vias allowed)
			(pads allowed)
			(copperpour not_allowed)
			(footprints allowed)
		)
		(placement
			(enabled no)
			(sheetname "")
		)
		(fill yes
			(thermal_gap 0.5)
			(thermal_bridge_width 0.5)
			(island_removal_mode 0)
		)
		(polygon
			(pts
				(arc
					(start 140.154914 -434.289962)
					(mid 139.345162 -434.289962)
					(end 140.154914 -434.289962)
				)
			)
		)
	)
	(zone
		(layers "B.Cu" "In15.Cu")
		(hatch none 0.5)
		(connect_pads
			(clearance 0)
		)
		(min_thickness 0.25)
		(keepout
			(tracks not_allowed)
			(vias allowed)
			(pads allowed)
			(copperpour not_allowed)
			(footprints allowed)
		)
		(placement
			(enabled no)
			(sheetname "")
		)
		(fill yes
			(thermal_gap 0.5)
			(thermal_bridge_width 0.5)
			(island_removal_mode 0)
		)
		(polygon
			(pts
				(arc
					(start 92.230956 -221.133924)
					(mid 91.578176 -221.133924)
					(end 92.230956 -221.133924)
				)
			)
		)
	)
	(zone
		(layers "B.Cu" "In15.Cu")
		(hatch none 0.5)
		(connect_pads
			(clearance 0)
		)
		(min_thickness 0.25)
		(keepout
			(tracks not_allowed)
			(vias allowed)
			(pads allowed)
			(copperpour not_allowed)
			(footprints allowed)
		)
		(placement
			(enabled no)
			(sheetname "")
		)
		(fill yes
			(thermal_gap 0.5)
			(thermal_bridge_width 0.5)
			(island_removal_mode 0)
		)
		(polygon
			(pts
				(arc
					(start 413.154876 -435.489858)
					(mid 412.345124 -435.489858)
					(end 413.154876 -435.489858)
				)
			)
		)
	)
	(zone
		(layers "B.Cu" "In15.Cu")
		(hatch none 0.5)
		(connect_pads
			(clearance 0)
		)
		(min_thickness 0.25)
		(keepout
			(tracks not_allowed)
			(vias allowed)
			(pads allowed)
			(copperpour not_allowed)
			(footprints allowed)
		)
		(placement
			(enabled no)
			(sheetname "")
		)
		(fill yes
			(thermal_gap 0.5)
			(thermal_bridge_width 0.5)
			(island_removal_mode 0)
		)
		(polygon
			(pts
				(arc
					(start 94.580202 -220.319854)
					(mid 93.927422 -220.319854)
					(end 94.580202 -220.319854)
				)
			)
		)
	)
	(zone
		(layers "B.Cu" "In15.Cu")
		(hatch none 0.5)
		(connect_pads
			(clearance 0)
		)
		(min_thickness 0.25)
		(keepout
			(tracks not_allowed)
			(vias allowed)
			(pads allowed)
			(copperpour not_allowed)
			(footprints allowed)
		)
		(placement
			(enabled no)
			(sheetname "")
		)
		(fill yes
			(thermal_gap 0.5)
			(thermal_bridge_width 0.5)
			(island_removal_mode 0)
		)
		(polygon
			(pts
				(arc
					(start 130.154934 -433.289964)
					(mid 129.345182 -433.289964)
					(end 130.154934 -433.289964)
				)
			)
		)
	)
	(zone
		(layers "B.Cu" "In15.Cu")
		(hatch none 0.5)
		(connect_pads
			(clearance 0)
		)
		(min_thickness 0.25)
		(keepout
			(tracks not_allowed)
			(vias allowed)
			(pads allowed)
			(copperpour not_allowed)
			(footprints allowed)
		)
		(placement
			(enabled no)
			(sheetname "")
		)
		(fill yes
			(thermal_gap 0.5)
			(thermal_bridge_width 0.5)
			(island_removal_mode 0)
		)
		(polygon
			(pts
				(arc
					(start 382.154938 -434.48986)
					(mid 381.345186 -434.48986)
					(end 382.154938 -434.48986)
				)
			)
		)
	)
	(zone
		(layers "B.Cu" "In15.Cu")
		(hatch none 0.5)
		(connect_pads
			(clearance 0)
		)
		(min_thickness 0.25)
		(keepout
			(tracks not_allowed)
			(vias allowed)
			(pads allowed)
			(copperpour not_allowed)
			(footprints allowed)
		)
		(placement
			(enabled no)
			(sheetname "")
		)
		(fill yes
			(thermal_gap 0.5)
			(thermal_bridge_width 0.5)
			(island_removal_mode 0)
		)
		(polygon
			(pts
				(arc
					(start 130.762756 -221.133924)
					(mid 130.109976 -221.133924)
					(end 130.762756 -221.133924)
				)
			)
		)
	)
	(zone
		(layers "B.Cu" "In15.Cu")
		(hatch none 0.5)
		(connect_pads
			(clearance 0)
		)
		(min_thickness 0.25)
		(keepout
			(tracks not_allowed)
			(vias allowed)
			(pads allowed)
			(copperpour not_allowed)
			(footprints allowed)
		)
		(placement
			(enabled no)
			(sheetname "")
		)
		(fill yes
			(thermal_gap 0.5)
			(thermal_bridge_width 0.5)
			(island_removal_mode 0)
		)
		(polygon
			(pts
				(arc
					(start 59.055 -438.089802)
					(mid 58.245248 -438.089802)
					(end 59.055 -438.089802)
				)
			)
		)
	)
	(zone
		(layers "B.Cu" "In15.Cu")
		(hatch none 0.5)
		(connect_pads
			(clearance 0)
		)
		(min_thickness 0.25)
		(keepout
			(tracks not_allowed)
			(vias allowed)
			(pads allowed)
			(copperpour not_allowed)
			(footprints allowed)
		)
		(placement
			(enabled no)
			(sheetname "")
		)
		(fill yes
			(thermal_gap 0.5)
			(thermal_bridge_width 0.5)
			(island_removal_mode 0)
		)
		(polygon
			(pts
				(arc
					(start 128.154938 -435.489858)
					(mid 127.345186 -435.489858)
					(end 128.154938 -435.489858)
				)
			)
		)
	)
	(zone
		(layers "B.Cu" "In15.Cu")
		(hatch none 0.5)
		(connect_pads
			(clearance 0)
		)
		(min_thickness 0.25)
		(keepout
			(tracks not_allowed)
			(vias allowed)
			(pads allowed)
			(copperpour not_allowed)
			(footprints allowed)
		)
		(placement
			(enabled no)
			(sheetname "")
		)
		(fill yes
			(thermal_gap 0.5)
			(thermal_bridge_width 0.5)
			(island_removal_mode 0)
		)
		(polygon
			(pts
				(arc
					(start 145.154904 -434.289962)
					(mid 144.345152 -434.289962)
					(end 145.154904 -434.289962)
				)
			)
		)
	)
	(zone
		(layers "B.Cu" "In15.Cu")
		(hatch none 0.5)
		(connect_pads
			(clearance 0)
		)
		(min_thickness 0.25)
		(keepout
			(tracks not_allowed)
			(vias allowed)
			(pads allowed)
			(copperpour not_allowed)
			(footprints allowed)
		)
		(placement
			(enabled no)
			(sheetname "")
		)
		(fill yes
			(thermal_gap 0.5)
			(thermal_bridge_width 0.5)
			(island_removal_mode 0)
		)
		(polygon
			(pts
				(arc
					(start 127.003556 -221.133924)
					(mid 126.350776 -221.133924)
					(end 127.003556 -221.133924)
				)
			)
		)
	)
	(zone
		(layers "B.Cu" "In15.Cu")
		(hatch none 0.5)
		(connect_pads
			(clearance 0)
		)
		(min_thickness 0.25)
		(keepout
			(tracks not_allowed)
			(vias allowed)
			(pads allowed)
			(copperpour not_allowed)
			(footprints allowed)
		)
		(placement
			(enabled no)
			(sheetname "")
		)
		(fill yes
			(thermal_gap 0.5)
			(thermal_bridge_width 0.5)
			(island_removal_mode 0)
		)
		(polygon
			(pts
				(arc
					(start 340.054946 -438.089802)
					(mid 339.245194 -438.089802)
					(end 340.054946 -438.089802)
				)
			)
		)
	)
	(zone
		(layers "B.Cu" "In15.Cu")
		(hatch none 0.5)
		(connect_pads
			(clearance 0)
		)
		(min_thickness 0.25)
		(keepout
			(tracks not_allowed)
			(vias allowed)
			(pads allowed)
			(copperpour not_allowed)
			(footprints allowed)
		)
		(placement
			(enabled no)
			(sheetname "")
		)
		(fill yes
			(thermal_gap 0.5)
			(thermal_bridge_width 0.5)
			(island_removal_mode 0)
		)
		(polygon
			(pts
				(arc
					(start 332.054962 -436.889906)
					(mid 331.24521 -436.889906)
					(end 332.054962 -436.889906)
				)
			)
		)
	)
	(zone
		(layers "B.Cu" "In15.Cu")
		(hatch none 0.5)
		(connect_pads
			(clearance 0)
		)
		(min_thickness 0.25)
		(keepout
			(tracks not_allowed)
			(vias allowed)
			(pads allowed)
			(copperpour not_allowed)
			(footprints allowed)
		)
		(placement
			(enabled no)
			(sheetname "")
		)
		(fill yes
			(thermal_gap 0.5)
			(thermal_bridge_width 0.5)
			(island_removal_mode 0)
		)
		(polygon
			(pts
				(arc
					(start 182.393082 -50.949098)
					(mid 181.689502 -50.949098)
					(end 182.393082 -50.949098)
				)
			)
		)
	)
	(zone
		(layers "B.Cu" "In15.Cu")
		(hatch none 0.5)
		(connect_pads
			(clearance 0)
		)
		(min_thickness 0.25)
		(keepout
			(tracks not_allowed)
			(vias allowed)
			(pads allowed)
			(copperpour not_allowed)
			(footprints allowed)
		)
		(placement
			(enabled no)
			(sheetname "")
		)
		(fill yes
			(thermal_gap 0.5)
			(thermal_bridge_width 0.5)
			(island_removal_mode 0)
		)
		(polygon
			(pts
				(arc
					(start 182.393082 -44.116498)
					(mid 181.689502 -44.116498)
					(end 182.393082 -44.116498)
				)
			)
		)
	)
	(zone
		(layers "B.Cu" "In15.Cu")
		(hatch none 0.5)
		(connect_pads
			(clearance 0)
		)
		(min_thickness 0.25)
		(keepout
			(tracks not_allowed)
			(vias allowed)
			(pads allowed)
			(copperpour not_allowed)
			(footprints allowed)
		)
		(placement
			(enabled no)
			(sheetname "")
		)
		(fill yes
			(thermal_gap 0.5)
			(thermal_bridge_width 0.5)
			(island_removal_mode 0)
		)
		(polygon
			(pts
				(arc
					(start 343.061544 -43.281092)
					(mid 342.408764 -43.281092)
					(end 343.061544 -43.281092)
				)
			)
		)
	)
	(zone
		(layers "B.Cu" "In15.Cu")
		(hatch none 0.5)
		(connect_pads
			(clearance 0)
		)
		(min_thickness 0.25)
		(keepout
			(tracks not_allowed)
			(vias allowed)
			(pads allowed)
			(copperpour not_allowed)
			(footprints allowed)
		)
		(placement
			(enabled no)
			(sheetname "")
		)
		(fill yes
			(thermal_gap 0.5)
			(thermal_bridge_width 0.5)
			(island_removal_mode 0)
		)
		(polygon
			(pts
				(arc
					(start 384.154934 -435.489858)
					(mid 383.345182 -435.489858)
					(end 384.154934 -435.489858)
				)
			)
		)
	)
	(zone
		(layers "B.Cu" "In15.Cu")
		(hatch none 0.5)
		(connect_pads
			(clearance 0)
		)
		(min_thickness 0.25)
		(keepout
			(tracks not_allowed)
			(vias allowed)
			(pads allowed)
			(copperpour not_allowed)
			(footprints allowed)
		)
		(placement
			(enabled no)
			(sheetname "")
		)
		(fill yes
			(thermal_gap 0.5)
			(thermal_bridge_width 0.5)
			(island_removal_mode 0)
		)
		(polygon
			(pts
				(arc
					(start 157.15488 -435.489858)
					(mid 156.345128 -435.489858)
					(end 157.15488 -435.489858)
				)
			)
		)
	)
	(zone
		(layers "B.Cu" "In15.Cu")
		(hatch none 0.5)
		(connect_pads
			(clearance 0)
		)
		(min_thickness 0.25)
		(keepout
			(tracks not_allowed)
			(vias allowed)
			(pads allowed)
			(copperpour not_allowed)
			(footprints allowed)
		)
		(placement
			(enabled no)
			(sheetname "")
		)
		(fill yes
			(thermal_gap 0.5)
			(thermal_bridge_width 0.5)
			(island_removal_mode 0)
		)
		(polygon
			(pts
				(arc
					(start 407.154888 -434.48986)
					(mid 406.345136 -434.48986)
					(end 407.154888 -434.48986)
				)
			)
		)
	)
	(zone
		(layers "B.Cu" "In15.Cu")
		(hatch none 0.5)
		(connect_pads
			(clearance 0)
		)
		(min_thickness 0.25)
		(keepout
			(tracks not_allowed)
			(vias allowed)
			(pads allowed)
			(copperpour not_allowed)
			(footprints allowed)
		)
		(placement
			(enabled no)
			(sheetname "")
		)
		(fill yes
			(thermal_gap 0.5)
			(thermal_bridge_width 0.5)
			(island_removal_mode 0)
		)
		(polygon
			(pts
				(arc
					(start 348.629224 -221.133924)
					(mid 347.976444 -221.133924)
					(end 348.629224 -221.133924)
				)
			)
		)
	)
	(zone
		(layers "B.Cu" "In15.Cu")
		(hatch none 0.5)
		(connect_pads
			(clearance 0)
		)
		(min_thickness 0.25)
		(keepout
			(tracks not_allowed)
			(vias allowed)
			(pads allowed)
			(copperpour not_allowed)
			(footprints allowed)
		)
		(placement
			(enabled no)
			(sheetname "")
		)
		(fill yes
			(thermal_gap 0.5)
			(thermal_bridge_width 0.5)
			(island_removal_mode 0)
		)
		(polygon
			(pts
				(arc
					(start 396.15491 -435.489858)
					(mid 395.345158 -435.489858)
					(end 396.15491 -435.489858)
				)
			)
		)
	)
	(zone
		(layers "B.Cu" "In15.Cu")
		(hatch none 0.5)
		(connect_pads
			(clearance 0)
		)
		(min_thickness 0.25)
		(keepout
			(tracks not_allowed)
			(vias allowed)
			(pads allowed)
			(copperpour not_allowed)
			(footprints allowed)
		)
		(placement
			(enabled no)
			(sheetname "")
		)
		(fill yes
			(thermal_gap 0.5)
			(thermal_bridge_width 0.5)
			(island_removal_mode 0)
		)
		(polygon
			(pts
				(arc
					(start 101.628956 -221.133924)
					(mid 100.976176 -221.133924)
					(end 101.628956 -221.133924)
				)
			)
		)
	)
	(zone
		(layers "B.Cu" "In15.Cu")
		(hatch none 0.5)
		(connect_pads
			(clearance 0)
		)
		(min_thickness 0.25)
		(keepout
			(tracks not_allowed)
			(vias allowed)
			(pads allowed)
			(copperpour not_allowed)
			(footprints allowed)
		)
		(placement
			(enabled no)
			(sheetname "")
		)
		(fill yes
			(thermal_gap 0.5)
			(thermal_bridge_width 0.5)
			(island_removal_mode 0)
		)
		(polygon
			(pts
				(arc
					(start 126.154942 -434.48986)
					(mid 125.34519 -434.48986)
					(end 126.154942 -434.48986)
				)
			)
		)
	)
	(zone
		(layers "B.Cu" "In15.Cu")
		(hatch none 0.5)
		(connect_pads
			(clearance 0)
		)
		(min_thickness 0.25)
		(keepout
			(tracks not_allowed)
			(vias allowed)
			(pads allowed)
			(copperpour not_allowed)
			(footprints allowed)
		)
		(placement
			(enabled no)
			(sheetname "")
		)
		(fill yes
			(thermal_gap 0.5)
			(thermal_bridge_width 0.5)
			(island_removal_mode 0)
		)
		(polygon
			(pts
				(arc
					(start 134.521956 -221.133924)
					(mid 133.869176 -221.133924)
					(end 134.521956 -221.133924)
				)
			)
		)
	)
	(zone
		(layers "B.Cu" "In15.Cu")
		(hatch none 0.5)
		(connect_pads
			(clearance 0)
		)
		(min_thickness 0.25)
		(keepout
			(tracks not_allowed)
			(vias allowed)
			(pads allowed)
			(copperpour not_allowed)
			(footprints allowed)
		)
		(placement
			(enabled no)
			(sheetname "")
		)
		(fill yes
			(thermal_gap 0.5)
			(thermal_bridge_width 0.5)
			(island_removal_mode 0)
		)
		(polygon
			(pts
				(arc
					(start 380.582424 -221.133924)
					(mid 379.929644 -221.133924)
					(end 380.582424 -221.133924)
				)
			)
		)
	)
	(zone
		(layers "B.Cu" "In15.Cu")
		(hatch none 0.5)
		(connect_pads
			(clearance 0)
		)
		(min_thickness 0.25)
		(keepout
			(tracks not_allowed)
			(vias allowed)
			(pads allowed)
			(copperpour not_allowed)
			(footprints allowed)
		)
		(placement
			(enabled no)
			(sheetname "")
		)
		(fill yes
			(thermal_gap 0.5)
			(thermal_bridge_width 0.5)
			(island_removal_mode 0)
		)
		(polygon
			(pts
				(arc
					(start 89.881202 -221.94774)
					(mid 89.228422 -221.94774)
					(end 89.881202 -221.94774)
				)
			)
		)
	)
	(zone
		(layers "B.Cu" "In15.Cu")
		(hatch none 0.5)
		(connect_pads
			(clearance 0)
		)
		(min_thickness 0.25)
		(keepout
			(tracks not_allowed)
			(vias allowed)
			(pads allowed)
			(copperpour not_allowed)
			(footprints allowed)
		)
		(placement
			(enabled no)
			(sheetname "")
		)
		(fill yes
			(thermal_gap 0.5)
			(thermal_bridge_width 0.5)
			(island_removal_mode 0)
		)
		(polygon
			(pts
				(arc
					(start 84.05495 -436.889906)
					(mid 83.245198 -436.889906)
					(end 84.05495 -436.889906)
				)
			)
		)
	)
	(zone
		(layers "B.Cu" "In15.Cu")
		(hatch none 0.5)
		(connect_pads
			(clearance 0)
		)
		(min_thickness 0.25)
		(keepout
			(tracks not_allowed)
			(vias allowed)
			(pads allowed)
			(copperpour not_allowed)
			(footprints allowed)
		)
		(placement
			(enabled no)
			(sheetname "")
		)
		(fill yes
			(thermal_gap 0.5)
			(thermal_bridge_width 0.5)
			(island_removal_mode 0)
		)
		(polygon
			(pts
				(arc
					(start 345.809824 -221.133924)
					(mid 345.157044 -221.133924)
					(end 345.809824 -221.133924)
				)
			)
		)
	)
	(zone
		(layers "B.Cu" "In15.Cu")
		(hatch none 0.5)
		(connect_pads
			(clearance 0)
		)
		(min_thickness 0.25)
		(keepout
			(tracks not_allowed)
			(vias allowed)
			(pads allowed)
			(copperpour not_allowed)
			(footprints allowed)
		)
		(placement
			(enabled no)
			(sheetname "")
		)
		(fill yes
			(thermal_gap 0.5)
			(thermal_bridge_width 0.5)
			(island_removal_mode 0)
		)
		(polygon
			(pts
				(arc
					(start 344.870024 -221.133924)
					(mid 344.217244 -221.133924)
					(end 344.870024 -221.133924)
				)
			)
		)
	)
	(zone
		(layers "B.Cu" "In15.Cu")
		(hatch none 0.5)
		(connect_pads
			(clearance 0)
		)
		(min_thickness 0.25)
		(keepout
			(tracks not_allowed)
			(vias allowed)
			(pads allowed)
			(copperpour not_allowed)
			(footprints allowed)
		)
		(placement
			(enabled no)
			(sheetname "")
		)
		(fill yes
			(thermal_gap 0.5)
			(thermal_bridge_width 0.5)
			(island_removal_mode 0)
		)
		(polygon
			(pts
				(arc
					(start 315.054996 -436.889906)
					(mid 314.245244 -436.889906)
					(end 315.054996 -436.889906)
				)
			)
		)
	)
	(zone
		(layers "B.Cu" "In15.Cu")
		(hatch none 0.5)
		(connect_pads
			(clearance 0)
		)
		(min_thickness 0.25)
		(keepout
			(tracks not_allowed)
			(vias allowed)
			(pads allowed)
			(copperpour not_allowed)
			(footprints allowed)
		)
		(placement
			(enabled no)
			(sheetname "")
		)
		(fill yes
			(thermal_gap 0.5)
			(thermal_bridge_width 0.5)
			(island_removal_mode 0)
		)
		(polygon
			(pts
				(arc
					(start 82.054954 -437.889904)
					(mid 81.245202 -437.889904)
					(end 82.054954 -437.889904)
				)
			)
		)
	)
	(zone
		(layers "B.Cu" "In15.Cu")
		(hatch none 0.5)
		(connect_pads
			(clearance 0)
		)
		(min_thickness 0.25)
		(keepout
			(tracks not_allowed)
			(vias allowed)
			(pads allowed)
			(copperpour not_allowed)
			(footprints allowed)
		)
		(placement
			(enabled no)
			(sheetname "")
		)
		(fill yes
			(thermal_gap 0.5)
			(thermal_bridge_width 0.5)
			(island_removal_mode 0)
		)
		(polygon
			(pts
				(arc
					(start 123.714002 -221.94774)
					(mid 123.061222 -221.94774)
					(end 123.714002 -221.94774)
				)
			)
		)
	)
	(zone
		(layers "B.Cu" "In15.Cu")
		(hatch none 0.5)
		(connect_pads
			(clearance 0)
		)
		(min_thickness 0.25)
		(keepout
			(tracks not_allowed)
			(vias allowed)
			(pads allowed)
			(copperpour not_allowed)
			(footprints allowed)
		)
		(placement
			(enabled no)
			(sheetname "")
		)
		(fill yes
			(thermal_gap 0.5)
			(thermal_bridge_width 0.5)
			(island_removal_mode 0)
		)
		(polygon
			(pts
				(arc
					(start 138.154918 -433.289964)
					(mid 137.345166 -433.289964)
					(end 138.154918 -433.289964)
				)
			)
		)
	)
	(zone
		(layers "B.Cu" "In15.Cu")
		(hatch none 0.5)
		(connect_pads
			(clearance 0)
		)
		(min_thickness 0.25)
		(keepout
			(tracks not_allowed)
			(vias allowed)
			(pads allowed)
			(copperpour not_allowed)
			(footprints allowed)
		)
		(placement
			(enabled no)
			(sheetname "")
		)
		(fill yes
			(thermal_gap 0.5)
			(thermal_bridge_width 0.5)
			(island_removal_mode 0)
		)
		(polygon
			(pts
				(arc
					(start 128.413002 -220.319854)
					(mid 127.760222 -220.319854)
					(end 128.413002 -220.319854)
				)
			)
		)
	)
	(zone
		(layers "B.Cu" "In15.Cu")
		(hatch none 0.5)
		(connect_pads
			(clearance 0)
		)
		(min_thickness 0.25)
		(keepout
			(tracks not_allowed)
			(vias allowed)
			(pads allowed)
			(copperpour not_allowed)
			(footprints allowed)
		)
		(placement
			(enabled no)
			(sheetname "")
		)
		(fill yes
			(thermal_gap 0.5)
			(thermal_bridge_width 0.5)
			(island_removal_mode 0)
		)
		(polygon
			(pts
				(arc
					(start 131.702556 -221.133924)
					(mid 131.049776 -221.133924)
					(end 131.702556 -221.133924)
				)
			)
		)
	)
	(zone
		(layers "B.Cu" "In15.Cu")
		(hatch none 0.5)
		(connect_pads
			(clearance 0)
		)
		(min_thickness 0.25)
		(keepout
			(tracks not_allowed)
			(vias allowed)
			(pads allowed)
			(copperpour not_allowed)
			(footprints allowed)
		)
		(placement
			(enabled no)
			(sheetname "")
		)
		(fill yes
			(thermal_gap 0.5)
			(thermal_bridge_width 0.5)
			(island_removal_mode 0)
		)
		(polygon
			(pts
				(arc
					(start 100.219002 -220.319854)
					(mid 99.566222 -220.319854)
					(end 100.219002 -220.319854)
				)
			)
		)
	)
	(zone
		(layers "B.Cu" "In15.Cu")
		(hatch none 0.5)
		(connect_pads
			(clearance 0)
		)
		(min_thickness 0.25)
		(keepout
			(tracks not_allowed)
			(vias allowed)
			(pads allowed)
			(copperpour not_allowed)
			(footprints allowed)
		)
		(placement
			(enabled no)
			(sheetname "")
		)
		(fill yes
			(thermal_gap 0.5)
			(thermal_bridge_width 0.5)
			(island_removal_mode 0)
		)
		(polygon
			(pts
				(arc
					(start 338.291424 -221.133924)
					(mid 337.638644 -221.133924)
					(end 338.291424 -221.133924)
				)
			)
		)
	)
	(zone
		(layers "B.Cu" "In15.Cu")
		(hatch none 0.5)
		(connect_pads
			(clearance 0)
		)
		(min_thickness 0.25)
		(keepout
			(tracks not_allowed)
			(vias allowed)
			(pads allowed)
			(copperpour not_allowed)
			(footprints allowed)
		)
		(placement
			(enabled no)
			(sheetname "")
		)
		(fill yes
			(thermal_gap 0.5)
			(thermal_bridge_width 0.5)
			(island_removal_mode 0)
		)
		(polygon
			(pts
				(arc
					(start 122.774202 -220.319854)
					(mid 122.121422 -220.319854)
					(end 122.774202 -220.319854)
				)
			)
		)
	)
	(zone
		(layers "B.Cu" "In15.Cu")
		(hatch none 0.5)
		(connect_pads
			(clearance 0)
		)
		(min_thickness 0.25)
		(keepout
			(tracks not_allowed)
			(vias allowed)
			(pads allowed)
			(copperpour not_allowed)
			(footprints allowed)
		)
		(placement
			(enabled no)
			(sheetname "")
		)
		(fill yes
			(thermal_gap 0.5)
			(thermal_bridge_width 0.5)
			(island_removal_mode 0)
		)
		(polygon
			(pts
				(arc
					(start 65.054988 -439.0898)
					(mid 64.245236 -439.0898)
					(end 65.054988 -439.0898)
				)
			)
		)
	)
	(zone
		(layers "B.Cu" "In15.Cu")
		(hatch none 0.5)
		(connect_pads
			(clearance 0)
		)
		(min_thickness 0.25)
		(keepout
			(tracks not_allowed)
			(vias allowed)
			(pads allowed)
			(copperpour not_allowed)
			(footprints allowed)
		)
		(placement
			(enabled no)
			(sheetname "")
		)
		(fill yes
			(thermal_gap 0.5)
			(thermal_bridge_width 0.5)
			(island_removal_mode 0)
		)
		(polygon
			(pts
				(arc
					(start 375.41327 -221.94774)
					(mid 374.76049 -221.94774)
					(end 375.41327 -221.94774)
				)
			)
		)
	)
	(zone
		(layers "B.Cu" "In15.Cu")
		(hatch none 0.5)
		(connect_pads
			(clearance 0)
		)
		(min_thickness 0.25)
		(keepout
			(tracks not_allowed)
			(vias allowed)
			(pads allowed)
			(copperpour not_allowed)
			(footprints allowed)
		)
		(placement
			(enabled no)
			(sheetname "")
		)
		(fill yes
			(thermal_gap 0.5)
			(thermal_bridge_width 0.5)
			(island_removal_mode 0)
		)
		(polygon
			(pts
				(arc
					(start 157.15488 -434.289962)
					(mid 156.345128 -434.289962)
					(end 157.15488 -434.289962)
				)
			)
		)
	)
	(zone
		(layers "B.Cu" "In15.Cu")
		(hatch none 0.5)
		(connect_pads
			(clearance 0)
		)
		(min_thickness 0.25)
		(keepout
			(tracks not_allowed)
			(vias allowed)
			(pads allowed)
			(copperpour not_allowed)
			(footprints allowed)
		)
		(placement
			(enabled no)
			(sheetname "")
		)
		(fill yes
			(thermal_gap 0.5)
			(thermal_bridge_width 0.5)
			(island_removal_mode 0)
		)
		(polygon
			(pts
				(arc
					(start 125.123956 -221.133924)
					(mid 124.471176 -221.133924)
					(end 125.123956 -221.133924)
				)
			)
		)
	)
	(zone
		(layers "B.Cu" "In15.Cu")
		(hatch none 0.5)
		(connect_pads
			(clearance 0)
		)
		(min_thickness 0.25)
		(keepout
			(tracks not_allowed)
			(vias allowed)
			(pads allowed)
			(copperpour not_allowed)
			(footprints allowed)
		)
		(placement
			(enabled no)
			(sheetname "")
		)
		(fill yes
			(thermal_gap 0.5)
			(thermal_bridge_width 0.5)
			(island_removal_mode 0)
		)
		(polygon
			(pts
				(arc
					(start 343.46007 -221.94774)
					(mid 342.80729 -221.94774)
					(end 343.46007 -221.94774)
				)
			)
		)
	)
	(zone
		(layers "B.Cu" "In15.Cu")
		(hatch none 0.5)
		(connect_pads
			(clearance 0)
		)
		(min_thickness 0.25)
		(keepout
			(tracks not_allowed)
			(vias allowed)
			(pads allowed)
			(copperpour not_allowed)
			(footprints allowed)
		)
		(placement
			(enabled no)
			(sheetname "")
		)
		(fill yes
			(thermal_gap 0.5)
			(thermal_bridge_width 0.5)
			(island_removal_mode 0)
		)
		(polygon
			(pts
				(arc
					(start 78.054962 -437.889904)
					(mid 77.24521 -437.889904)
					(end 78.054962 -437.889904)
				)
			)
		)
	)
	(zone
		(layers "B.Cu" "In15.Cu")
		(hatch none 0.5)
		(connect_pads
			(clearance 0)
		)
		(min_thickness 0.25)
		(keepout
			(tracks not_allowed)
			(vias allowed)
			(pads allowed)
			(copperpour not_allowed)
			(footprints allowed)
		)
		(placement
			(enabled no)
			(sheetname "")
		)
		(fill yes
			(thermal_gap 0.5)
			(thermal_bridge_width 0.5)
			(island_removal_mode 0)
		)
		(polygon
			(pts
				(arc
					(start 350.03867 -220.319854)
					(mid 349.38589 -220.319854)
					(end 350.03867 -220.319854)
				)
			)
		)
	)
	(zone
		(layers "B.Cu" "In15.Cu")
		(hatch none 0.5)
		(connect_pads
			(clearance 0)
		)
		(min_thickness 0.25)
		(keepout
			(tracks not_allowed)
			(vias allowed)
			(pads allowed)
			(copperpour not_allowed)
			(footprints allowed)
		)
		(placement
			(enabled no)
			(sheetname "")
		)
		(fill yes
			(thermal_gap 0.5)
			(thermal_bridge_width 0.5)
			(island_removal_mode 0)
		)
		(polygon
			(pts
				(arc
					(start 94.110556 -221.133924)
					(mid 93.457776 -221.133924)
					(end 94.110556 -221.133924)
				)
			)
		)
	)
	(zone
		(layers "B.Cu" "In15.Cu")
		(hatch none 0.5)
		(connect_pads
			(clearance 0)
		)
		(min_thickness 0.25)
		(keepout
			(tracks not_allowed)
			(vias allowed)
			(pads allowed)
			(copperpour not_allowed)
			(footprints allowed)
		)
		(placement
			(enabled no)
			(sheetname "")
		)
		(fill yes
			(thermal_gap 0.5)
			(thermal_bridge_width 0.5)
			(island_removal_mode 0)
		)
		(polygon
			(pts
				(arc
					(start 396.15491 -434.289962)
					(mid 395.345158 -434.289962)
					(end 396.15491 -434.289962)
				)
			)
		)
	)
	(zone
		(layers "B.Cu" "In15.Cu")
		(hatch none 0.5)
		(connect_pads
			(clearance 0)
		)
		(min_thickness 0.25)
		(keepout
			(tracks not_allowed)
			(vias allowed)
			(pads allowed)
			(copperpour not_allowed)
			(footprints allowed)
		)
		(placement
			(enabled no)
			(sheetname "")
		)
		(fill yes
			(thermal_gap 0.5)
			(thermal_bridge_width 0.5)
			(island_removal_mode 0)
		)
		(polygon
			(pts
				(arc
					(start 349.569024 -221.133924)
					(mid 348.916244 -221.133924)
					(end 349.569024 -221.133924)
				)
			)
		)
	)
	(zone
		(layers "B.Cu" "In15.Cu")
		(hatch none 0.5)
		(connect_pads
			(clearance 0)
		)
		(min_thickness 0.25)
		(keepout
			(tracks not_allowed)
			(vias allowed)
			(pads allowed)
			(copperpour not_allowed)
			(footprints allowed)
		)
		(placement
			(enabled no)
			(sheetname "")
		)
		(fill yes
			(thermal_gap 0.5)
			(thermal_bridge_width 0.5)
			(island_removal_mode 0)
		)
		(polygon
			(pts
				(arc
					(start 147.1549 -433.289964)
					(mid 146.345148 -433.289964)
					(end 147.1549 -433.289964)
				)
			)
		)
	)
	(zone
		(layers "B.Cu" "In15.Cu")
		(hatch none 0.5)
		(connect_pads
			(clearance 0)
		)
		(min_thickness 0.25)
		(keepout
			(tracks not_allowed)
			(vias allowed)
			(pads allowed)
			(copperpour not_allowed)
			(footprints allowed)
		)
		(placement
			(enabled no)
			(sheetname "")
		)
		(fill yes
			(thermal_gap 0.5)
			(thermal_bridge_width 0.5)
			(island_removal_mode 0)
		)
		(polygon
			(pts
				(arc
					(start 390.154922 -433.289964)
					(mid 389.34517 -433.289964)
					(end 390.154922 -433.289964)
				)
			)
		)
	)
	(zone
		(layers "B.Cu" "In15.Cu")
		(hatch none 0.5)
		(connect_pads
			(clearance 0)
		)
		(min_thickness 0.25)
		(keepout
			(tracks not_allowed)
			(vias allowed)
			(pads allowed)
			(copperpour not_allowed)
			(footprints allowed)
		)
		(placement
			(enabled no)
			(sheetname "")
		)
		(fill yes
			(thermal_gap 0.5)
			(thermal_bridge_width 0.5)
			(island_removal_mode 0)
		)
		(polygon
			(pts
				(arc
					(start 346.27947 -220.319854)
					(mid 345.62669 -220.319854)
					(end 346.27947 -220.319854)
				)
			)
		)
	)
	(zone
		(layers "B.Cu" "In15.Cu")
		(hatch none 0.5)
		(connect_pads
			(clearance 0)
		)
		(min_thickness 0.25)
		(keepout
			(tracks not_allowed)
			(vias allowed)
			(pads allowed)
			(copperpour not_allowed)
			(footprints allowed)
		)
		(placement
			(enabled no)
			(sheetname "")
		)
		(fill yes
			(thermal_gap 0.5)
			(thermal_bridge_width 0.5)
			(island_removal_mode 0)
		)
		(polygon
			(pts
				(arc
					(start 386.15493 -433.289964)
					(mid 385.345178 -433.289964)
					(end 386.15493 -433.289964)
				)
			)
		)
	)
	(zone
		(layer "In1.Cu")
		(hatch none 0.5)
		(connect_pads
			(clearance 0)
		)
		(min_thickness 0.25)
		(keepout
			(tracks not_allowed)
			(vias allowed)
			(pads allowed)
			(copperpour not_allowed)
			(footprints allowed)
		)
		(placement
			(enabled no)
			(sheetname "")
		)
		(fill
			(thermal_gap 0.5)
			(thermal_bridge_width 0.5)
			(island_removal_mode 0)
		)
		(polygon
			(pts
				(arc
					(start 176.38268 -49.43602)
					(mid 176.328798 -49.413702)
					(end 176.30648 -49.35982)
				)
				(arc
					(start 176.30648 -48.72736)
					(mid 176.328798 -48.673478)
					(end 176.38268 -48.65116)
				)
				(arc
					(start 177.83556 -48.65116)
					(mid 177.889442 -48.673478)
					(end 177.91176 -48.72736)
				)
				(arc
					(start 177.91176 -49.35982)
					(mid 177.889442 -49.413702)
					(end 177.83556 -49.43602)
				)
			)
		)
	)
	(zone
		(layer "In1.Cu")
		(hatch none 0.5)
		(connect_pads
			(clearance 0)
		)
		(min_thickness 0.25)
		(keepout
			(tracks not_allowed)
			(vias allowed)
			(pads allowed)
			(copperpour not_allowed)
			(footprints allowed)
		)
		(placement
			(enabled no)
			(sheetname "")
		)
		(fill
			(thermal_gap 0.5)
			(thermal_bridge_width 0.5)
			(island_removal_mode 0)
		)
		(polygon
			(pts
				(arc
					(start 155.786328 -46.081442)
					(mid 155.825369 -46.073685)
					(end 155.85821 -46.051216)
				)
				(arc
					(start 155.85821 -46.051216)
					(mid 155.878252 -46.020528)
					(end 155.885896 -45.984668)
				)
				(xy 155.885896 -45.842428) (xy 155.885642 -45.842428)
				(arc
					(start 155.885642 -44.915074)
					(mid 155.856452 -44.851568)
					(end 155.792424 -44.823634)
				)
				(arc
					(start 155.485592 -44.823634)
					(mid 155.446551 -44.831391)
					(end 155.41371 -44.85386)
				)
				(arc
					(start 155.41371 -44.85386)
					(mid 155.393668 -44.884548)
					(end 155.386024 -44.920408)
				)
				(xy 155.386024 -45.951648) (xy 155.386278 -45.951648)
				(arc
					(start 155.386278 -45.990002)
					(mid 155.415468 -46.053508)
					(end 155.479496 -46.081442)
				)
			)
		)
	)
	(zone
		(layer "In1.Cu")
		(hatch none 0.5)
		(connect_pads
			(clearance 0)
		)
		(min_thickness 0.25)
		(keepout
			(tracks not_allowed)
			(vias allowed)
			(pads allowed)
			(copperpour not_allowed)
			(footprints allowed)
		)
		(placement
			(enabled no)
			(sheetname "")
		)
		(fill
			(thermal_gap 0.5)
			(thermal_bridge_width 0.5)
			(island_removal_mode 0)
		)
		(polygon
			(pts
				(arc
					(start 49.150524 -16.442436)
					(mid 49.172842 -16.496318)
					(end 49.226724 -16.518636)
				)
				(arc
					(start 49.422304 -16.518636)
					(mid 49.44418 -16.515504)
					(end 49.464214 -16.50619)
				)
				(arc
					(start 49.757838 -16.313658)
					(mid 49.799494 -16.301256)
					(end 49.84115 -16.313658)
				)
				(arc
					(start 50.136044 -16.50619)
					(mid 50.155968 -16.515426)
					(end 50.1777 -16.518636)
				)
				(arc
					(start 50.372264 -16.518636)
					(mid 50.426146 -16.496318)
					(end 50.448464 -16.442436)
				)
				(arc
					(start 50.448464 -15.756636)
					(mid 50.426146 -15.702754)
					(end 50.372264 -15.680436)
				)
				(arc
					(start 50.1777 -15.680436)
					(mid 50.155956 -15.683604)
					(end 50.136044 -15.692882)
				)
				(arc
					(start 49.83988 -15.885668)
					(mid 49.798196 -15.89789)
					(end 49.756568 -15.885414)
				)
				(arc
					(start 49.462944 -15.692882)
					(mid 49.44302 -15.683646)
					(end 49.421288 -15.680436)
				)
				(arc
					(start 49.226724 -15.680436)
					(mid 49.172842 -15.702754)
					(end 49.150524 -15.756636)
				)
			)
		)
	)
	(zone
		(layer "In1.Cu")
		(hatch none 0.5)
		(connect_pads
			(clearance 0)
		)
		(min_thickness 0.25)
		(keepout
			(tracks not_allowed)
			(vias allowed)
			(pads allowed)
			(copperpour not_allowed)
			(footprints allowed)
		)
		(placement
			(enabled no)
			(sheetname "")
		)
		(fill
			(thermal_gap 0.5)
			(thermal_bridge_width 0.5)
			(island_removal_mode 0)
		)
		(polygon
			(pts
				(arc
					(start 332.678278 -408.860244)
					(mid 332.700596 -408.914126)
					(end 332.754478 -408.936444)
				)
				(arc
					(start 332.950058 -408.936444)
					(mid 332.971934 -408.933312)
					(end 332.991968 -408.923998)
				)
				(arc
					(start 333.285592 -408.731466)
					(mid 333.327248 -408.719064)
					(end 333.368904 -408.731466)
				)
				(arc
					(start 333.663798 -408.923998)
					(mid 333.683722 -408.933234)
					(end 333.705454 -408.936444)
				)
				(arc
					(start 333.900018 -408.936444)
					(mid 333.9539 -408.914126)
					(end 333.976218 -408.860244)
				)
				(arc
					(start 333.976218 -408.174444)
					(mid 333.9539 -408.120562)
					(end 333.900018 -408.098244)
				)
				(arc
					(start 333.705454 -408.098244)
					(mid 333.68371 -408.101412)
					(end 333.663798 -408.11069)
				)
				(arc
					(start 333.367634 -408.303476)
					(mid 333.32595 -408.315698)
					(end 333.284322 -408.303222)
				)
				(arc
					(start 332.990698 -408.11069)
					(mid 332.970774 -408.101454)
					(end 332.949042 -408.098244)
				)
				(arc
					(start 332.754478 -408.098244)
					(mid 332.700596 -408.120562)
					(end 332.678278 -408.174444)
				)
			)
		)
	)
	(zone
		(layer "In1.Cu")
		(hatch none 0.5)
		(connect_pads
			(clearance 0)
		)
		(min_thickness 0.25)
		(keepout
			(tracks not_allowed)
			(vias allowed)
			(pads allowed)
			(copperpour not_allowed)
			(footprints allowed)
		)
		(placement
			(enabled no)
			(sheetname "")
		)
		(fill
			(thermal_gap 0.5)
			(thermal_bridge_width 0.5)
			(island_removal_mode 0)
		)
		(polygon
			(pts
				(arc
					(start 93.711268 -402.713952)
					(mid 93.733586 -402.767834)
					(end 93.787468 -402.790152)
				)
				(arc
					(start 93.983048 -402.790152)
					(mid 94.004924 -402.78702)
					(end 94.024958 -402.777706)
				)
				(arc
					(start 94.318582 -402.585174)
					(mid 94.360238 -402.572772)
					(end 94.401894 -402.585174)
				)
				(arc
					(start 94.696788 -402.777706)
					(mid 94.716712 -402.786942)
					(end 94.738444 -402.790152)
				)
				(arc
					(start 94.933008 -402.790152)
					(mid 94.98689 -402.767834)
					(end 95.009208 -402.713952)
				)
				(arc
					(start 95.009208 -402.028152)
					(mid 94.98689 -401.97427)
					(end 94.933008 -401.951952)
				)
				(arc
					(start 94.738444 -401.951952)
					(mid 94.7167 -401.95512)
					(end 94.696788 -401.964398)
				)
				(arc
					(start 94.400624 -402.157184)
					(mid 94.35894 -402.169406)
					(end 94.317312 -402.15693)
				)
				(arc
					(start 94.023688 -401.964398)
					(mid 94.003764 -401.955162)
					(end 93.982032 -401.951952)
				)
				(arc
					(start 93.787468 -401.951952)
					(mid 93.733586 -401.97427)
					(end 93.711268 -402.028152)
				)
			)
		)
	)
	(zone
		(layer "In1.Cu")
		(hatch none 0.5)
		(connect_pads
			(clearance 0)
		)
		(min_thickness 0.25)
		(keepout
			(tracks not_allowed)
			(vias allowed)
			(pads allowed)
			(copperpour not_allowed)
			(footprints allowed)
		)
		(placement
			(enabled no)
			(sheetname "")
		)
		(fill
			(thermal_gap 0.5)
			(thermal_bridge_width 0.5)
			(island_removal_mode 0)
		)
		(polygon
			(pts
				(arc
					(start 139.663424 -408.860244)
					(mid 139.685742 -408.914126)
					(end 139.739624 -408.936444)
				)
				(arc
					(start 139.935204 -408.936444)
					(mid 139.95708 -408.933312)
					(end 139.977114 -408.923998)
				)
				(arc
					(start 140.270738 -408.731466)
					(mid 140.312394 -408.719064)
					(end 140.35405 -408.731466)
				)
				(arc
					(start 140.648944 -408.923998)
					(mid 140.668868 -408.933234)
					(end 140.6906 -408.936444)
				)
				(arc
					(start 140.885164 -408.936444)
					(mid 140.939046 -408.914126)
					(end 140.961364 -408.860244)
				)
				(arc
					(start 140.961364 -408.174444)
					(mid 140.939046 -408.120562)
					(end 140.885164 -408.098244)
				)
				(arc
					(start 140.6906 -408.098244)
					(mid 140.668856 -408.101412)
					(end 140.648944 -408.11069)
				)
				(arc
					(start 140.35278 -408.303476)
					(mid 140.311096 -408.315698)
					(end 140.269468 -408.303222)
				)
				(arc
					(start 139.975844 -408.11069)
					(mid 139.95592 -408.101454)
					(end 139.934188 -408.098244)
				)
				(arc
					(start 139.739624 -408.098244)
					(mid 139.685742 -408.120562)
					(end 139.663424 -408.174444)
				)
			)
		)
	)
	(zone
		(layer "In1.Cu")
		(hatch none 0.5)
		(connect_pads
			(clearance 0)
		)
		(min_thickness 0.25)
		(keepout
			(tracks not_allowed)
			(vias allowed)
			(pads allowed)
			(copperpour not_allowed)
			(footprints allowed)
		)
		(placement
			(enabled no)
			(sheetname "")
		)
		(fill
			(thermal_gap 0.5)
			(thermal_bridge_width 0.5)
			(island_removal_mode 0)
		)
		(polygon
			(pts
				(arc
					(start 26.121868 -398.317466)
					(mid 26.160909 -398.309709)
					(end 26.19375 -398.28724)
				)
				(arc
					(start 26.19375 -398.28724)
					(mid 26.213792 -398.256552)
					(end 26.221436 -398.220692)
				)
				(xy 26.221436 -398.078452) (xy 26.221182 -398.078452)
				(arc
					(start 26.221182 -397.151098)
					(mid 26.191992 -397.087592)
					(end 26.127964 -397.059658)
				)
				(arc
					(start 25.821132 -397.059658)
					(mid 25.782091 -397.067415)
					(end 25.74925 -397.089884)
				)
				(arc
					(start 25.74925 -397.089884)
					(mid 25.729208 -397.120572)
					(end 25.721564 -397.156432)
				)
				(xy 25.721564 -398.187672) (xy 25.721818 -398.187672)
				(arc
					(start 25.721818 -398.226026)
					(mid 25.751008 -398.289532)
					(end 25.815036 -398.317466)
				)
			)
		)
	)
	(zone
		(layer "In1.Cu")
		(hatch none 0.5)
		(connect_pads
			(clearance 0)
		)
		(min_thickness 0.25)
		(keepout
			(tracks not_allowed)
			(vias allowed)
			(pads allowed)
			(copperpour not_allowed)
			(footprints allowed)
		)
		(placement
			(enabled no)
			(sheetname "")
		)
		(fill
			(thermal_gap 0.5)
			(thermal_bridge_width 0.5)
			(island_removal_mode 0)
		)
		(polygon
			(pts
				(arc
					(start 157.211776 -45.291502)
					(mid 157.250817 -45.283745)
					(end 157.283658 -45.261276)
				)
				(arc
					(start 157.283658 -45.261276)
					(mid 157.3037 -45.230588)
					(end 157.311344 -45.194728)
				)
				(xy 157.311344 -45.052488) (xy 157.31109 -45.052488)
				(arc
					(start 157.31109 -44.125134)
					(mid 157.2819 -44.061628)
					(end 157.217872 -44.033694)
				)
				(arc
					(start 156.91104 -44.033694)
					(mid 156.871999 -44.041451)
					(end 156.839158 -44.06392)
				)
				(arc
					(start 156.839158 -44.06392)
					(mid 156.819116 -44.094608)
					(end 156.811472 -44.130468)
				)
				(xy 156.811472 -45.161708) (xy 156.811726 -45.161708)
				(arc
					(start 156.811726 -45.200062)
					(mid 156.840916 -45.263568)
					(end 156.904944 -45.291502)
				)
			)
		)
	)
	(zone
		(layer "In1.Cu")
		(hatch none 0.5)
		(connect_pads
			(clearance 0)
		)
		(min_thickness 0.25)
		(keepout
			(tracks not_allowed)
			(vias allowed)
			(pads allowed)
			(copperpour not_allowed)
			(footprints allowed)
		)
		(placement
			(enabled no)
			(sheetname "")
		)
		(fill
			(thermal_gap 0.5)
			(thermal_bridge_width 0.5)
			(island_removal_mode 0)
		)
		(polygon
			(pts
				(arc
					(start 57.56656 -17.966436)
					(mid 57.588878 -18.020318)
					(end 57.64276 -18.042636)
				)
				(arc
					(start 57.83834 -18.042636)
					(mid 57.860216 -18.039504)
					(end 57.88025 -18.03019)
				)
				(arc
					(start 58.173874 -17.837658)
					(mid 58.21553 -17.825256)
					(end 58.257186 -17.837658)
				)
				(arc
					(start 58.55208 -18.03019)
					(mid 58.572004 -18.039426)
					(end 58.593736 -18.042636)
				)
				(arc
					(start 58.7883 -18.042636)
					(mid 58.842182 -18.020318)
					(end 58.8645 -17.966436)
				)
				(arc
					(start 58.8645 -17.280636)
					(mid 58.842182 -17.226754)
					(end 58.7883 -17.204436)
				)
				(arc
					(start 58.593736 -17.204436)
					(mid 58.571992 -17.207604)
					(end 58.55208 -17.216882)
				)
				(arc
					(start 58.255916 -17.409668)
					(mid 58.214232 -17.42189)
					(end 58.172604 -17.409414)
				)
				(arc
					(start 57.87898 -17.216882)
					(mid 57.859056 -17.207646)
					(end 57.837324 -17.204436)
				)
				(arc
					(start 57.64276 -17.204436)
					(mid 57.588878 -17.226754)
					(end 57.56656 -17.280636)
				)
			)
		)
	)
	(zone
		(layer "In1.Cu")
		(hatch none 0.5)
		(connect_pads
			(clearance 0)
		)
		(min_thickness 0.25)
		(keepout
			(tracks not_allowed)
			(vias allowed)
			(pads allowed)
			(copperpour not_allowed)
			(footprints allowed)
		)
		(placement
			(enabled no)
			(sheetname "")
		)
		(fill
			(thermal_gap 0.5)
			(thermal_bridge_width 0.5)
			(island_removal_mode 0)
		)
		(polygon
			(pts
				(arc
					(start 328.268838 -402.713952)
					(mid 328.291156 -402.767834)
					(end 328.345038 -402.790152)
				)
				(arc
					(start 328.540618 -402.790152)
					(mid 328.562494 -402.78702)
					(end 328.582528 -402.777706)
				)
				(arc
					(start 328.876152 -402.585174)
					(mid 328.917808 -402.572772)
					(end 328.959464 -402.585174)
				)
				(arc
					(start 329.254358 -402.777706)
					(mid 329.274282 -402.786942)
					(end 329.296014 -402.790152)
				)
				(arc
					(start 329.490578 -402.790152)
					(mid 329.54446 -402.767834)
					(end 329.566778 -402.713952)
				)
				(arc
					(start 329.566778 -402.028152)
					(mid 329.54446 -401.97427)
					(end 329.490578 -401.951952)
				)
				(arc
					(start 329.296014 -401.951952)
					(mid 329.27427 -401.95512)
					(end 329.254358 -401.964398)
				)
				(arc
					(start 328.958194 -402.157184)
					(mid 328.91651 -402.169406)
					(end 328.874882 -402.15693)
				)
				(arc
					(start 328.581258 -401.964398)
					(mid 328.561334 -401.955162)
					(end 328.539602 -401.951952)
				)
				(arc
					(start 328.345038 -401.951952)
					(mid 328.291156 -401.97427)
					(end 328.268838 -402.028152)
				)
			)
		)
	)
	(zone
		(layer "In1.Cu")
		(hatch none 0.5)
		(connect_pads
			(clearance 0)
		)
		(min_thickness 0.25)
		(keepout
			(tracks not_allowed)
			(vias allowed)
			(pads allowed)
			(copperpour not_allowed)
			(footprints allowed)
		)
		(placement
			(enabled no)
			(sheetname "")
		)
		(fill
			(thermal_gap 0.5)
			(thermal_bridge_width 0.5)
			(island_removal_mode 0)
		)
		(polygon
			(pts
				(arc
					(start 56.687212 -7.672324)
					(mid 56.664894 -7.618442)
					(end 56.611012 -7.596124)
				)
				(arc
					(start 55.329582 -7.596124)
					(mid 55.2757 -7.618442)
					(end 55.253382 -7.672324)
				)
				(arc
					(start 55.253382 -9.094724)
					(mid 55.2757 -9.148606)
					(end 55.329582 -9.170924)
				)
				(arc
					(start 56.611012 -9.170924)
					(mid 56.664894 -9.148606)
					(end 56.687212 -9.094724)
				)
			)
		)
	)
	(zone
		(layer "In1.Cu")
		(hatch none 0.5)
		(connect_pads
			(clearance 0)
		)
		(min_thickness 0.25)
		(keepout
			(tracks not_allowed)
			(vias allowed)
			(pads allowed)
			(copperpour not_allowed)
			(footprints allowed)
		)
		(placement
			(enabled no)
			(sheetname "")
		)
		(fill
			(thermal_gap 0.5)
			(thermal_bridge_width 0.5)
			(island_removal_mode 0)
		)
		(polygon
			(pts
				(arc
					(start 406.588214 -16.431514)
					(mid 406.610532 -16.485396)
					(end 406.664414 -16.507714)
				)
				(arc
					(start 406.859994 -16.507714)
					(mid 406.88187 -16.504582)
					(end 406.901904 -16.495268)
				)
				(arc
					(start 407.195528 -16.302736)
					(mid 407.237184 -16.290334)
					(end 407.27884 -16.302736)
				)
				(arc
					(start 407.573734 -16.495268)
					(mid 407.593658 -16.504504)
					(end 407.61539 -16.507714)
				)
				(arc
					(start 407.809954 -16.507714)
					(mid 407.863836 -16.485396)
					(end 407.886154 -16.431514)
				)
				(arc
					(start 407.886154 -15.745714)
					(mid 407.863836 -15.691832)
					(end 407.809954 -15.669514)
				)
				(arc
					(start 407.61539 -15.669514)
					(mid 407.593646 -15.672682)
					(end 407.573734 -15.68196)
				)
				(arc
					(start 407.27757 -15.874746)
					(mid 407.235886 -15.886968)
					(end 407.194258 -15.874492)
				)
				(arc
					(start 406.900634 -15.68196)
					(mid 406.88071 -15.672724)
					(end 406.858978 -15.669514)
				)
				(arc
					(start 406.664414 -15.669514)
					(mid 406.610532 -15.691832)
					(end 406.588214 -15.745714)
				)
			)
		)
	)
	(zone
		(layer "In1.Cu")
		(hatch none 0.5)
		(connect_pads
			(clearance 0)
		)
		(min_thickness 0.25)
		(keepout
			(tracks not_allowed)
			(vias allowed)
			(pads allowed)
			(copperpour not_allowed)
			(footprints allowed)
		)
		(placement
			(enabled no)
			(sheetname "")
		)
		(fill
			(thermal_gap 0.5)
			(thermal_bridge_width 0.5)
			(island_removal_mode 0)
		)
		(polygon
			(pts
				(arc
					(start 338.804758 -408.860244)
					(mid 338.827076 -408.914126)
					(end 338.880958 -408.936444)
				)
				(arc
					(start 339.076538 -408.936444)
					(mid 339.098414 -408.933312)
					(end 339.118448 -408.923998)
				)
				(arc
					(start 339.412072 -408.731466)
					(mid 339.453728 -408.719064)
					(end 339.495384 -408.731466)
				)
				(arc
					(start 339.790278 -408.923998)
					(mid 339.810202 -408.933234)
					(end 339.831934 -408.936444)
				)
				(arc
					(start 340.026498 -408.936444)
					(mid 340.08038 -408.914126)
					(end 340.102698 -408.860244)
				)
				(arc
					(start 340.102698 -408.174444)
					(mid 340.08038 -408.120562)
					(end 340.026498 -408.098244)
				)
				(arc
					(start 339.831934 -408.098244)
					(mid 339.81019 -408.101412)
					(end 339.790278 -408.11069)
				)
				(arc
					(start 339.494114 -408.303476)
					(mid 339.45243 -408.315698)
					(end 339.410802 -408.303222)
				)
				(arc
					(start 339.117178 -408.11069)
					(mid 339.097254 -408.101454)
					(end 339.075522 -408.098244)
				)
				(arc
					(start 338.880958 -408.098244)
					(mid 338.827076 -408.120562)
					(end 338.804758 -408.174444)
				)
			)
		)
	)
	(zone
		(layer "In1.Cu")
		(hatch none 0.5)
		(connect_pads
			(clearance 0)
		)
		(min_thickness 0.25)
		(keepout
			(tracks not_allowed)
			(vias allowed)
			(pads allowed)
			(copperpour not_allowed)
			(footprints allowed)
		)
		(placement
			(enabled no)
			(sheetname "")
		)
		(fill
			(thermal_gap 0.5)
			(thermal_bridge_width 0.5)
			(island_removal_mode 0)
		)
		(polygon
			(pts
				(arc
					(start 160.430718 -45.26153)
					(mid 160.469759 -45.253773)
					(end 160.5026 -45.231304)
				)
				(arc
					(start 160.5026 -45.231304)
					(mid 160.522642 -45.200616)
					(end 160.530286 -45.164756)
				)
				(xy 160.530286 -45.022516) (xy 160.530032 -45.022516)
				(arc
					(start 160.530032 -44.095162)
					(mid 160.500842 -44.031656)
					(end 160.436814 -44.003722)
				)
				(arc
					(start 160.129982 -44.003722)
					(mid 160.090941 -44.011479)
					(end 160.0581 -44.033948)
				)
				(arc
					(start 160.0581 -44.033948)
					(mid 160.038058 -44.064636)
					(end 160.030414 -44.100496)
				)
				(xy 160.030414 -45.131736) (xy 160.030668 -45.131736)
				(arc
					(start 160.030668 -45.17009)
					(mid 160.059858 -45.233596)
					(end 160.123886 -45.26153)
				)
			)
		)
	)
	(zone
		(layer "In1.Cu")
		(hatch none 0.5)
		(connect_pads
			(clearance 0)
		)
		(min_thickness 0.25)
		(keepout
			(tracks not_allowed)
			(vias allowed)
			(pads allowed)
			(copperpour not_allowed)
			(footprints allowed)
		)
		(placement
			(enabled no)
			(sheetname "")
		)
		(fill
			(thermal_gap 0.5)
			(thermal_bridge_width 0.5)
			(island_removal_mode 0)
		)
		(polygon
			(pts
				(arc
					(start 16.791686 -105.38714)
					(mid 16.830727 -105.379383)
					(end 16.863568 -105.356914)
				)
				(arc
					(start 16.863568 -105.356914)
					(mid 16.88361 -105.326226)
					(end 16.891254 -105.290366)
				)
				(xy 16.891254 -105.148126) (xy 16.891 -105.148126)
				(arc
					(start 16.891 -104.220772)
					(mid 16.86181 -104.157266)
					(end 16.797782 -104.129332)
				)
				(arc
					(start 16.49095 -104.129332)
					(mid 16.451909 -104.137089)
					(end 16.419068 -104.159558)
				)
				(arc
					(start 16.419068 -104.159558)
					(mid 16.399026 -104.190246)
					(end 16.391382 -104.226106)
				)
				(xy 16.391382 -105.257346) (xy 16.391636 -105.257346)
				(arc
					(start 16.391636 -105.2957)
					(mid 16.420826 -105.359206)
					(end 16.484854 -105.38714)
				)
			)
		)
	)
	(zone
		(layer "In1.Cu")
		(hatch none 0.5)
		(connect_pads
			(clearance 0)
		)
		(min_thickness 0.25)
		(keepout
			(tracks not_allowed)
			(vias allowed)
			(pads allowed)
			(copperpour not_allowed)
			(footprints allowed)
		)
		(placement
			(enabled no)
			(sheetname "")
		)
		(fill
			(thermal_gap 0.5)
			(thermal_bridge_width 0.5)
			(island_removal_mode 0)
		)
		(polygon
			(pts
				(arc
					(start 82.804508 -408.860244)
					(mid 82.826826 -408.914126)
					(end 82.880708 -408.936444)
				)
				(arc
					(start 83.076288 -408.936444)
					(mid 83.098164 -408.933312)
					(end 83.118198 -408.923998)
				)
				(arc
					(start 83.411822 -408.731466)
					(mid 83.453478 -408.719064)
					(end 83.495134 -408.731466)
				)
				(arc
					(start 83.790028 -408.923998)
					(mid 83.809952 -408.933234)
					(end 83.831684 -408.936444)
				)
				(arc
					(start 84.026248 -408.936444)
					(mid 84.08013 -408.914126)
					(end 84.102448 -408.860244)
				)
				(arc
					(start 84.102448 -408.174444)
					(mid 84.08013 -408.120562)
					(end 84.026248 -408.098244)
				)
				(arc
					(start 83.831684 -408.098244)
					(mid 83.80994 -408.101412)
					(end 83.790028 -408.11069)
				)
				(arc
					(start 83.493864 -408.303476)
					(mid 83.45218 -408.315698)
					(end 83.410552 -408.303222)
				)
				(arc
					(start 83.116928 -408.11069)
					(mid 83.097004 -408.101454)
					(end 83.075272 -408.098244)
				)
				(arc
					(start 82.880708 -408.098244)
					(mid 82.826826 -408.120562)
					(end 82.804508 -408.174444)
				)
			)
		)
	)
	(zone
		(layer "In1.Cu")
		(hatch none 0.5)
		(connect_pads
			(clearance 0)
		)
		(min_thickness 0.25)
		(keepout
			(tracks not_allowed)
			(vias allowed)
			(pads allowed)
			(copperpour not_allowed)
			(footprints allowed)
		)
		(placement
			(enabled no)
			(sheetname "")
		)
		(fill
			(thermal_gap 0.5)
			(thermal_bridge_width 0.5)
			(island_removal_mode 0)
		)
		(polygon
			(pts
				(arc
					(start 151.916384 -408.860244)
					(mid 151.938702 -408.914126)
					(end 151.992584 -408.936444)
				)
				(arc
					(start 152.188164 -408.936444)
					(mid 152.21004 -408.933312)
					(end 152.230074 -408.923998)
				)
				(arc
					(start 152.523698 -408.731466)
					(mid 152.565354 -408.719064)
					(end 152.60701 -408.731466)
				)
				(arc
					(start 152.901904 -408.923998)
					(mid 152.921828 -408.933234)
					(end 152.94356 -408.936444)
				)
				(arc
					(start 153.138124 -408.936444)
					(mid 153.192006 -408.914126)
					(end 153.214324 -408.860244)
				)
				(arc
					(start 153.214324 -408.174444)
					(mid 153.192006 -408.120562)
					(end 153.138124 -408.098244)
				)
				(arc
					(start 152.94356 -408.098244)
					(mid 152.921816 -408.101412)
					(end 152.901904 -408.11069)
				)
				(arc
					(start 152.60574 -408.303476)
					(mid 152.564056 -408.315698)
					(end 152.522428 -408.303222)
				)
				(arc
					(start 152.228804 -408.11069)
					(mid 152.20888 -408.101454)
					(end 152.187148 -408.098244)
				)
				(arc
					(start 151.992584 -408.098244)
					(mid 151.938702 -408.120562)
					(end 151.916384 -408.174444)
				)
			)
		)
	)
	(zone
		(layer "In1.Cu")
		(hatch none 0.5)
		(connect_pads
			(clearance 0)
		)
		(min_thickness 0.25)
		(keepout
			(tracks not_allowed)
			(vias allowed)
			(pads allowed)
			(copperpour not_allowed)
			(footprints allowed)
		)
		(placement
			(enabled no)
			(sheetname "")
		)
		(fill
			(thermal_gap 0.5)
			(thermal_bridge_width 0.5)
			(island_removal_mode 0)
		)
		(polygon
			(pts
				(arc
					(start 54.77256 -16.442436)
					(mid 54.794878 -16.496318)
					(end 54.84876 -16.518636)
				)
				(arc
					(start 55.04434 -16.518636)
					(mid 55.066216 -16.515504)
					(end 55.08625 -16.50619)
				)
				(arc
					(start 55.379874 -16.313658)
					(mid 55.42153 -16.301256)
					(end 55.463186 -16.313658)
				)
				(arc
					(start 55.75808 -16.50619)
					(mid 55.778004 -16.515426)
					(end 55.799736 -16.518636)
				)
				(arc
					(start 55.9943 -16.518636)
					(mid 56.048182 -16.496318)
					(end 56.0705 -16.442436)
				)
				(arc
					(start 56.0705 -15.756636)
					(mid 56.048182 -15.702754)
					(end 55.9943 -15.680436)
				)
				(arc
					(start 55.799736 -15.680436)
					(mid 55.777992 -15.683604)
					(end 55.75808 -15.692882)
				)
				(arc
					(start 55.461916 -15.885668)
					(mid 55.420232 -15.89789)
					(end 55.378604 -15.885414)
				)
				(arc
					(start 55.08498 -15.692882)
					(mid 55.065056 -15.683646)
					(end 55.043324 -15.680436)
				)
				(arc
					(start 54.84876 -15.680436)
					(mid 54.794878 -15.702754)
					(end 54.77256 -15.756636)
				)
			)
		)
	)
	(zone
		(layer "In1.Cu")
		(hatch none 0.5)
		(connect_pads
			(clearance 0)
		)
		(min_thickness 0.25)
		(keepout
			(tracks not_allowed)
			(vias allowed)
			(pads allowed)
			(copperpour not_allowed)
			(footprints allowed)
		)
		(placement
			(enabled no)
			(sheetname "")
		)
		(fill
			(thermal_gap 0.5)
			(thermal_bridge_width 0.5)
			(island_removal_mode 0)
		)
		(polygon
			(pts
				(arc
					(start 69.205348 -402.713952)
					(mid 69.227666 -402.767834)
					(end 69.281548 -402.790152)
				)
				(arc
					(start 69.477128 -402.790152)
					(mid 69.499004 -402.78702)
					(end 69.519038 -402.777706)
				)
				(arc
					(start 69.812662 -402.585174)
					(mid 69.854318 -402.572772)
					(end 69.895974 -402.585174)
				)
				(arc
					(start 70.190868 -402.777706)
					(mid 70.210792 -402.786942)
					(end 70.232524 -402.790152)
				)
				(arc
					(start 70.427088 -402.790152)
					(mid 70.48097 -402.767834)
					(end 70.503288 -402.713952)
				)
				(arc
					(start 70.503288 -402.028152)
					(mid 70.48097 -401.97427)
					(end 70.427088 -401.951952)
				)
				(arc
					(start 70.232524 -401.951952)
					(mid 70.21078 -401.95512)
					(end 70.190868 -401.964398)
				)
				(arc
					(start 69.894704 -402.157184)
					(mid 69.85302 -402.169406)
					(end 69.811392 -402.15693)
				)
				(arc
					(start 69.517768 -401.964398)
					(mid 69.497844 -401.955162)
					(end 69.476112 -401.951952)
				)
				(arc
					(start 69.281548 -401.951952)
					(mid 69.227666 -401.97427)
					(end 69.205348 -402.028152)
				)
			)
		)
	)
	(zone
		(layer "In1.Cu")
		(hatch none 0.5)
		(connect_pads
			(clearance 0)
		)
		(min_thickness 0.25)
		(keepout
			(tracks not_allowed)
			(vias allowed)
			(pads allowed)
			(copperpour not_allowed)
			(footprints allowed)
		)
		(placement
			(enabled no)
			(sheetname "")
		)
		(fill
			(thermal_gap 0.5)
			(thermal_bridge_width 0.5)
			(island_removal_mode 0)
		)
		(polygon
			(pts
				(arc
					(start 400.427698 -11.91768)
					(mid 400.450016 -11.971562)
					(end 400.503898 -11.99388)
				)
				(arc
					(start 401.785328 -11.99388)
					(mid 401.83921 -11.971562)
					(end 401.861528 -11.91768)
				)
				(arc
					(start 401.861528 -10.49528)
					(mid 401.83921 -10.441398)
					(end 401.785328 -10.41908)
				)
				(arc
					(start 400.503898 -10.41908)
					(mid 400.450016 -10.441398)
					(end 400.427698 -10.49528)
				)
			)
		)
	)
	(zone
		(layer "In1.Cu")
		(hatch none 0.5)
		(connect_pads
			(clearance 0)
		)
		(min_thickness 0.25)
		(keepout
			(tracks not_allowed)
			(vias allowed)
			(pads allowed)
			(copperpour not_allowed)
			(footprints allowed)
		)
		(placement
			(enabled no)
			(sheetname "")
		)
		(fill
			(thermal_gap 0.5)
			(thermal_bridge_width 0.5)
			(island_removal_mode 0)
		)
		(polygon
			(pts
				(arc
					(start 55.249064 -11.91768)
					(mid 55.271382 -11.971562)
					(end 55.325264 -11.99388)
				)
				(arc
					(start 56.606694 -11.99388)
					(mid 56.660576 -11.971562)
					(end 56.682894 -11.91768)
				)
				(arc
					(start 56.682894 -10.49528)
					(mid 56.660576 -10.441398)
					(end 56.606694 -10.41908)
				)
				(arc
					(start 55.325264 -10.41908)
					(mid 55.271382 -10.441398)
					(end 55.249064 -10.49528)
				)
			)
		)
	)
	(zone
		(layer "In1.Cu")
		(hatch none 0.5)
		(connect_pads
			(clearance 0)
		)
		(min_thickness 0.25)
		(keepout
			(tracks not_allowed)
			(vias allowed)
			(pads allowed)
			(copperpour not_allowed)
			(footprints allowed)
		)
		(placement
			(enabled no)
			(sheetname "")
		)
		(fill
			(thermal_gap 0.5)
			(thermal_bridge_width 0.5)
			(island_removal_mode 0)
		)
		(polygon
			(pts
				(arc
					(start 16.79575 -106.195114)
					(mid 16.834791 -106.187357)
					(end 16.867632 -106.164888)
				)
				(arc
					(start 16.867632 -106.164888)
					(mid 16.887674 -106.1342)
					(end 16.895318 -106.09834)
				)
				(xy 16.895318 -105.9561) (xy 16.895064 -105.9561)
				(arc
					(start 16.895064 -105.028746)
					(mid 16.865874 -104.96524)
					(end 16.801846 -104.937306)
				)
				(arc
					(start 16.495014 -104.937306)
					(mid 16.455973 -104.945063)
					(end 16.423132 -104.967532)
				)
				(arc
					(start 16.423132 -104.967532)
					(mid 16.40309 -104.99822)
					(end 16.395446 -105.03408)
				)
				(xy 16.395446 -106.06532) (xy 16.3957 -106.06532)
				(arc
					(start 16.3957 -106.103674)
					(mid 16.42489 -106.16718)
					(end 16.488918 -106.195114)
				)
			)
		)
	)
	(zone
		(layer "In1.Cu")
		(hatch none 0.5)
		(connect_pads
			(clearance 0)
		)
		(min_thickness 0.25)
		(keepout
			(tracks not_allowed)
			(vias allowed)
			(pads allowed)
			(copperpour not_allowed)
			(footprints allowed)
		)
		(placement
			(enabled no)
			(sheetname "")
		)
		(fill
			(thermal_gap 0.5)
			(thermal_bridge_width 0.5)
			(island_removal_mode 0)
		)
		(polygon
			(pts
				(arc
					(start 414.09112 -402.713952)
					(mid 414.113438 -402.767834)
					(end 414.16732 -402.790152)
				)
				(arc
					(start 414.3629 -402.790152)
					(mid 414.384776 -402.78702)
					(end 414.40481 -402.777706)
				)
				(arc
					(start 414.698434 -402.585174)
					(mid 414.74009 -402.572772)
					(end 414.781746 -402.585174)
				)
				(arc
					(start 415.07664 -402.777706)
					(mid 415.096564 -402.786942)
					(end 415.118296 -402.790152)
				)
				(arc
					(start 415.31286 -402.790152)
					(mid 415.366742 -402.767834)
					(end 415.38906 -402.713952)
				)
				(arc
					(start 415.38906 -402.028152)
					(mid 415.366742 -401.97427)
					(end 415.31286 -401.951952)
				)
				(arc
					(start 415.118296 -401.951952)
					(mid 415.096552 -401.95512)
					(end 415.07664 -401.964398)
				)
				(arc
					(start 414.780476 -402.157184)
					(mid 414.738792 -402.169406)
					(end 414.697164 -402.15693)
				)
				(arc
					(start 414.40354 -401.964398)
					(mid 414.383616 -401.955162)
					(end 414.361884 -401.951952)
				)
				(arc
					(start 414.16732 -401.951952)
					(mid 414.113438 -401.97427)
					(end 414.09112 -402.028152)
				)
			)
		)
	)
	(zone
		(layer "In1.Cu")
		(hatch none 0.5)
		(connect_pads
			(clearance 0)
		)
		(min_thickness 0.25)
		(keepout
			(tracks not_allowed)
			(vias allowed)
			(pads allowed)
			(copperpour not_allowed)
			(footprints allowed)
		)
		(placement
			(enabled no)
			(sheetname "")
		)
		(fill
			(thermal_gap 0.5)
			(thermal_bridge_width 0.5)
			(island_removal_mode 0)
		)
		(polygon
			(pts
				(arc
					(start 340.521798 -402.713952)
					(mid 340.544116 -402.767834)
					(end 340.597998 -402.790152)
				)
				(arc
					(start 340.793578 -402.790152)
					(mid 340.815454 -402.78702)
					(end 340.835488 -402.777706)
				)
				(arc
					(start 341.129112 -402.585174)
					(mid 341.170768 -402.572772)
					(end 341.212424 -402.585174)
				)
				(arc
					(start 341.507318 -402.777706)
					(mid 341.527242 -402.786942)
					(end 341.548974 -402.790152)
				)
				(arc
					(start 341.743538 -402.790152)
					(mid 341.79742 -402.767834)
					(end 341.819738 -402.713952)
				)
				(arc
					(start 341.819738 -402.028152)
					(mid 341.79742 -401.97427)
					(end 341.743538 -401.951952)
				)
				(arc
					(start 341.548974 -401.951952)
					(mid 341.52723 -401.95512)
					(end 341.507318 -401.964398)
				)
				(arc
					(start 341.211154 -402.157184)
					(mid 341.16947 -402.169406)
					(end 341.127842 -402.15693)
				)
				(arc
					(start 340.834218 -401.964398)
					(mid 340.814294 -401.955162)
					(end 340.792562 -401.951952)
				)
				(arc
					(start 340.597998 -401.951952)
					(mid 340.544116 -401.97427)
					(end 340.521798 -402.028152)
				)
			)
		)
	)
	(zone
		(layer "In1.Cu")
		(hatch none 0.5)
		(connect_pads
			(clearance 0)
		)
		(min_thickness 0.25)
		(keepout
			(tracks not_allowed)
			(vias allowed)
			(pads allowed)
			(copperpour not_allowed)
			(footprints allowed)
		)
		(placement
			(enabled no)
			(sheetname "")
		)
		(fill
			(thermal_gap 0.5)
			(thermal_bridge_width 0.5)
			(island_removal_mode 0)
		)
		(polygon
			(pts
				(arc
					(start 153.633424 -402.713952)
					(mid 153.655742 -402.767834)
					(end 153.709624 -402.790152)
				)
				(arc
					(start 153.905204 -402.790152)
					(mid 153.92708 -402.78702)
					(end 153.947114 -402.777706)
				)
				(arc
					(start 154.240738 -402.585174)
					(mid 154.282394 -402.572772)
					(end 154.32405 -402.585174)
				)
				(arc
					(start 154.618944 -402.777706)
					(mid 154.638868 -402.786942)
					(end 154.6606 -402.790152)
				)
				(arc
					(start 154.855164 -402.790152)
					(mid 154.909046 -402.767834)
					(end 154.931364 -402.713952)
				)
				(arc
					(start 154.931364 -402.028152)
					(mid 154.909046 -401.97427)
					(end 154.855164 -401.951952)
				)
				(arc
					(start 154.6606 -401.951952)
					(mid 154.638856 -401.95512)
					(end 154.618944 -401.964398)
				)
				(arc
					(start 154.32278 -402.157184)
					(mid 154.281096 -402.169406)
					(end 154.239468 -402.15693)
				)
				(arc
					(start 153.945844 -401.964398)
					(mid 153.92592 -401.955162)
					(end 153.904188 -401.951952)
				)
				(arc
					(start 153.709624 -401.951952)
					(mid 153.655742 -401.97427)
					(end 153.633424 -402.028152)
				)
			)
		)
	)
	(zone
		(layer "In1.Cu")
		(hatch none 0.5)
		(connect_pads
			(clearance 0)
		)
		(min_thickness 0.25)
		(keepout
			(tracks not_allowed)
			(vias allowed)
			(pads allowed)
			(copperpour not_allowed)
			(footprints allowed)
		)
		(placement
			(enabled no)
			(sheetname "")
		)
		(fill
			(thermal_gap 0.5)
			(thermal_bridge_width 0.5)
			(island_removal_mode 0)
		)
		(polygon
			(pts
				(arc
					(start 18.791174 -397.439642)
					(mid 18.830215 -397.431885)
					(end 18.863056 -397.409416)
				)
				(arc
					(start 18.863056 -397.409416)
					(mid 18.883098 -397.378728)
					(end 18.890742 -397.342868)
				)
				(xy 18.890742 -397.200628) (xy 18.890488 -397.200628)
				(arc
					(start 18.890488 -396.273274)
					(mid 18.861298 -396.209768)
					(end 18.79727 -396.181834)
				)
				(arc
					(start 18.490438 -396.181834)
					(mid 18.451397 -396.189591)
					(end 18.418556 -396.21206)
				)
				(arc
					(start 18.418556 -396.21206)
					(mid 18.398514 -396.242748)
					(end 18.39087 -396.278608)
				)
				(xy 18.39087 -397.309848) (xy 18.391124 -397.309848)
				(arc
					(start 18.391124 -397.348202)
					(mid 18.420314 -397.411708)
					(end 18.484342 -397.439642)
				)
			)
		)
	)
	(zone
		(layer "In1.Cu")
		(hatch none 0.5)
		(connect_pads
			(clearance 0)
		)
		(min_thickness 0.25)
		(keepout
			(tracks not_allowed)
			(vias allowed)
			(pads allowed)
			(copperpour not_allowed)
			(footprints allowed)
		)
		(placement
			(enabled no)
			(sheetname "")
		)
		(fill
			(thermal_gap 0.5)
			(thermal_bridge_width 0.5)
			(island_removal_mode 0)
		)
		(polygon
			(pts
				(arc
					(start 73.614788 -408.860244)
					(mid 73.637106 -408.914126)
					(end 73.690988 -408.936444)
				)
				(arc
					(start 73.886568 -408.936444)
					(mid 73.908444 -408.933312)
					(end 73.928478 -408.923998)
				)
				(arc
					(start 74.222102 -408.731466)
					(mid 74.263758 -408.719064)
					(end 74.305414 -408.731466)
				)
				(arc
					(start 74.600308 -408.923998)
					(mid 74.620232 -408.933234)
					(end 74.641964 -408.936444)
				)
				(arc
					(start 74.836528 -408.936444)
					(mid 74.89041 -408.914126)
					(end 74.912728 -408.860244)
				)
				(arc
					(start 74.912728 -408.174444)
					(mid 74.89041 -408.120562)
					(end 74.836528 -408.098244)
				)
				(arc
					(start 74.641964 -408.098244)
					(mid 74.62022 -408.101412)
					(end 74.600308 -408.11069)
				)
				(arc
					(start 74.304144 -408.303476)
					(mid 74.26246 -408.315698)
					(end 74.220832 -408.303222)
				)
				(arc
					(start 73.927208 -408.11069)
					(mid 73.907284 -408.101454)
					(end 73.885552 -408.098244)
				)
				(arc
					(start 73.690988 -408.098244)
					(mid 73.637106 -408.120562)
					(end 73.614788 -408.174444)
				)
			)
		)
	)
	(zone
		(layer "In1.Cu")
		(hatch none 0.5)
		(connect_pads
			(clearance 0)
		)
		(min_thickness 0.25)
		(keepout
			(tracks not_allowed)
			(vias allowed)
			(pads allowed)
			(copperpour not_allowed)
			(footprints allowed)
		)
		(placement
			(enabled no)
			(sheetname "")
		)
		(fill
			(thermal_gap 0.5)
			(thermal_bridge_width 0.5)
			(island_removal_mode 0)
		)
		(polygon
			(pts
				(arc
					(start 401.83816 -402.713952)
					(mid 401.860478 -402.767834)
					(end 401.91436 -402.790152)
				)
				(arc
					(start 402.10994 -402.790152)
					(mid 402.131816 -402.78702)
					(end 402.15185 -402.777706)
				)
				(arc
					(start 402.445474 -402.585174)
					(mid 402.48713 -402.572772)
					(end 402.528786 -402.585174)
				)
				(arc
					(start 402.82368 -402.777706)
					(mid 402.843604 -402.786942)
					(end 402.865336 -402.790152)
				)
				(arc
					(start 403.0599 -402.790152)
					(mid 403.113782 -402.767834)
					(end 403.1361 -402.713952)
				)
				(arc
					(start 403.1361 -402.028152)
					(mid 403.113782 -401.97427)
					(end 403.0599 -401.951952)
				)
				(arc
					(start 402.865336 -401.951952)
					(mid 402.843592 -401.95512)
					(end 402.82368 -401.964398)
				)
				(arc
					(start 402.527516 -402.157184)
					(mid 402.485832 -402.169406)
					(end 402.444204 -402.15693)
				)
				(arc
					(start 402.15058 -401.964398)
					(mid 402.130656 -401.955162)
					(end 402.108924 -401.951952)
				)
				(arc
					(start 401.91436 -401.951952)
					(mid 401.860478 -401.97427)
					(end 401.83816 -402.028152)
				)
			)
		)
	)
	(zone
		(layer "In1.Cu")
		(hatch none 0.5)
		(connect_pads
			(clearance 0)
		)
		(min_thickness 0.25)
		(keepout
			(tracks not_allowed)
			(vias allowed)
			(pads allowed)
			(copperpour not_allowed)
			(footprints allowed)
		)
		(placement
			(enabled no)
			(sheetname "")
		)
		(fill
			(thermal_gap 0.5)
			(thermal_bridge_width 0.5)
			(island_removal_mode 0)
		)
		(polygon
			(pts
				(arc
					(start 374.269 -402.713952)
					(mid 374.291318 -402.767834)
					(end 374.3452 -402.790152)
				)
				(arc
					(start 374.54078 -402.790152)
					(mid 374.562656 -402.78702)
					(end 374.58269 -402.777706)
				)
				(arc
					(start 374.876314 -402.585174)
					(mid 374.91797 -402.572772)
					(end 374.959626 -402.585174)
				)
				(arc
					(start 375.25452 -402.777706)
					(mid 375.274444 -402.786942)
					(end 375.296176 -402.790152)
				)
				(arc
					(start 375.49074 -402.790152)
					(mid 375.544622 -402.767834)
					(end 375.56694 -402.713952)
				)
				(arc
					(start 375.56694 -402.028152)
					(mid 375.544622 -401.97427)
					(end 375.49074 -401.951952)
				)
				(arc
					(start 375.296176 -401.951952)
					(mid 375.274432 -401.95512)
					(end 375.25452 -401.964398)
				)
				(arc
					(start 374.958356 -402.157184)
					(mid 374.916672 -402.169406)
					(end 374.875044 -402.15693)
				)
				(arc
					(start 374.58142 -401.964398)
					(mid 374.561496 -401.955162)
					(end 374.539764 -401.951952)
				)
				(arc
					(start 374.3452 -401.951952)
					(mid 374.291318 -401.97427)
					(end 374.269 -402.028152)
				)
			)
		)
	)
	(zone
		(layer "In1.Cu")
		(hatch none 0.5)
		(connect_pads
			(clearance 0)
		)
		(min_thickness 0.25)
		(keepout
			(tracks not_allowed)
			(vias allowed)
			(pads allowed)
			(copperpour not_allowed)
			(footprints allowed)
		)
		(placement
			(enabled no)
			(sheetname "")
		)
		(fill
			(thermal_gap 0.5)
			(thermal_bridge_width 0.5)
			(island_removal_mode 0)
		)
		(polygon
			(pts
				(arc
					(start 23.616666 -384.349244)
					(mid 23.577625 -384.357001)
					(end 23.544784 -384.37947)
				)
				(arc
					(start 23.544784 -384.37947)
					(mid 23.524742 -384.410158)
					(end 23.517098 -384.446018)
				)
				(xy 23.517098 -384.588258) (xy 23.517352 -384.588258)
				(arc
					(start 23.517352 -385.515612)
					(mid 23.546542 -385.579118)
					(end 23.61057 -385.607052)
				)
				(arc
					(start 23.917402 -385.607052)
					(mid 23.956443 -385.599295)
					(end 23.989284 -385.576826)
				)
				(arc
					(start 23.989284 -385.576826)
					(mid 24.009326 -385.546138)
					(end 24.01697 -385.510278)
				)
				(xy 24.01697 -384.479038) (xy 24.016716 -384.479038)
				(arc
					(start 24.016716 -384.440684)
					(mid 23.987526 -384.377178)
					(end 23.923498 -384.349244)
				)
			)
		)
	)
	(zone
		(layer "In1.Cu")
		(hatch none 0.5)
		(connect_pads
			(clearance 0)
		)
		(min_thickness 0.25)
		(keepout
			(tracks not_allowed)
			(vias allowed)
			(pads allowed)
			(copperpour not_allowed)
			(footprints allowed)
		)
		(placement
			(enabled no)
			(sheetname "")
		)
		(fill
			(thermal_gap 0.5)
			(thermal_bridge_width 0.5)
			(island_removal_mode 0)
		)
		(polygon
			(pts
				(arc
					(start 40.768524 -17.966436)
					(mid 40.790842 -18.020318)
					(end 40.844724 -18.042636)
				)
				(arc
					(start 41.040304 -18.042636)
					(mid 41.06218 -18.039504)
					(end 41.082214 -18.03019)
				)
				(arc
					(start 41.375838 -17.837658)
					(mid 41.417494 -17.825256)
					(end 41.45915 -17.837658)
				)
				(arc
					(start 41.754044 -18.03019)
					(mid 41.773968 -18.039426)
					(end 41.7957 -18.042636)
				)
				(arc
					(start 41.990264 -18.042636)
					(mid 42.044146 -18.020318)
					(end 42.066464 -17.966436)
				)
				(arc
					(start 42.066464 -17.280636)
					(mid 42.044146 -17.226754)
					(end 41.990264 -17.204436)
				)
				(arc
					(start 41.7957 -17.204436)
					(mid 41.773956 -17.207604)
					(end 41.754044 -17.216882)
				)
				(arc
					(start 41.45788 -17.409668)
					(mid 41.416196 -17.42189)
					(end 41.374568 -17.409414)
				)
				(arc
					(start 41.080944 -17.216882)
					(mid 41.06102 -17.207646)
					(end 41.039288 -17.204436)
				)
				(arc
					(start 40.844724 -17.204436)
					(mid 40.790842 -17.226754)
					(end 40.768524 -17.280636)
				)
			)
		)
	)
	(zone
		(layer "In1.Cu")
		(hatch none 0.5)
		(connect_pads
			(clearance 0)
		)
		(min_thickness 0.25)
		(keepout
			(tracks not_allowed)
			(vias allowed)
			(pads allowed)
			(copperpour not_allowed)
			(footprints allowed)
		)
		(placement
			(enabled no)
			(sheetname "")
		)
		(fill
			(thermal_gap 0.5)
			(thermal_bridge_width 0.5)
			(island_removal_mode 0)
		)
		(polygon
			(pts
				(arc
					(start 351.057718 -408.860244)
					(mid 351.080036 -408.914126)
					(end 351.133918 -408.936444)
				)
				(arc
					(start 351.329498 -408.936444)
					(mid 351.351374 -408.933312)
					(end 351.371408 -408.923998)
				)
				(arc
					(start 351.665032 -408.731466)
					(mid 351.706688 -408.719064)
					(end 351.748344 -408.731466)
				)
				(arc
					(start 352.043238 -408.923998)
					(mid 352.063162 -408.933234)
					(end 352.084894 -408.936444)
				)
				(arc
					(start 352.279458 -408.936444)
					(mid 352.33334 -408.914126)
					(end 352.355658 -408.860244)
				)
				(arc
					(start 352.355658 -408.174444)
					(mid 352.33334 -408.120562)
					(end 352.279458 -408.098244)
				)
				(arc
					(start 352.084894 -408.098244)
					(mid 352.06315 -408.101412)
					(end 352.043238 -408.11069)
				)
				(arc
					(start 351.747074 -408.303476)
					(mid 351.70539 -408.315698)
					(end 351.663762 -408.303222)
				)
				(arc
					(start 351.370138 -408.11069)
					(mid 351.350214 -408.101454)
					(end 351.328482 -408.098244)
				)
				(arc
					(start 351.133918 -408.098244)
					(mid 351.080036 -408.120562)
					(end 351.057718 -408.174444)
				)
			)
		)
	)
	(zone
		(layer "In1.Cu")
		(hatch none 0.5)
		(connect_pads
			(clearance 0)
		)
		(min_thickness 0.25)
		(keepout
			(tracks not_allowed)
			(vias allowed)
			(pads allowed)
			(copperpour not_allowed)
			(footprints allowed)
		)
		(placement
			(enabled no)
			(sheetname "")
		)
		(fill
			(thermal_gap 0.5)
			(thermal_bridge_width 0.5)
			(island_removal_mode 0)
		)
		(polygon
			(pts
				(arc
					(start 16.395192 -19.819874)
					(mid 15.633192 -19.819874)
					(end 16.395192 -19.819874)
				)
			)
		)
	)
	(zone
		(layer "In1.Cu")
		(hatch none 0.5)
		(connect_pads
			(clearance 0)
		)
		(min_thickness 0.25)
		(keepout
			(tracks not_allowed)
			(vias allowed)
			(pads allowed)
			(copperpour not_allowed)
			(footprints allowed)
		)
		(placement
			(enabled no)
			(sheetname "")
		)
		(fill
			(thermal_gap 0.5)
			(thermal_bridge_width 0.5)
			(island_removal_mode 0)
		)
		(polygon
			(pts
				(arc
					(start 249.541284 3.4671)
					(mid 249.563602 3.520982)
					(end 249.617484 3.5433)
				)
				(arc
					(start 250.229624 3.5433)
					(mid 250.283506 3.520982)
					(end 250.305824 3.4671)
				)
				(arc
					(start 250.305824 2.36982)
					(mid 250.283506 2.315938)
					(end 250.229624 2.29362)
				)
				(arc
					(start 249.617484 2.29362)
					(mid 249.563602 2.315938)
					(end 249.541284 2.36982)
				)
			)
		)
	)
	(zone
		(layer "In1.Cu")
		(hatch none 0.5)
		(connect_pads
			(clearance 0)
		)
		(min_thickness 0.25)
		(keepout
			(tracks not_allowed)
			(vias allowed)
			(pads allowed)
			(copperpour not_allowed)
			(footprints allowed)
		)
		(placement
			(enabled no)
			(sheetname "")
		)
		(fill
			(thermal_gap 0.5)
			(thermal_bridge_width 0.5)
			(island_removal_mode 0)
		)
		(polygon
			(pts
				(arc
					(start 415.43732 -408.860244)
					(mid 415.459638 -408.914126)
					(end 415.51352 -408.936444)
				)
				(arc
					(start 415.7091 -408.936444)
					(mid 415.730976 -408.933312)
					(end 415.75101 -408.923998)
				)
				(arc
					(start 416.044634 -408.731466)
					(mid 416.08629 -408.719064)
					(end 416.127946 -408.731466)
				)
				(arc
					(start 416.42284 -408.923998)
					(mid 416.442764 -408.933234)
					(end 416.464496 -408.936444)
				)
				(arc
					(start 416.65906 -408.936444)
					(mid 416.712942 -408.914126)
					(end 416.73526 -408.860244)
				)
				(arc
					(start 416.73526 -408.174444)
					(mid 416.712942 -408.120562)
					(end 416.65906 -408.098244)
				)
				(arc
					(start 416.464496 -408.098244)
					(mid 416.442752 -408.101412)
					(end 416.42284 -408.11069)
				)
				(arc
					(start 416.126676 -408.303476)
					(mid 416.084992 -408.315698)
					(end 416.043364 -408.303222)
				)
				(arc
					(start 415.74974 -408.11069)
					(mid 415.729816 -408.101454)
					(end 415.708084 -408.098244)
				)
				(arc
					(start 415.51352 -408.098244)
					(mid 415.459638 -408.120562)
					(end 415.43732 -408.174444)
				)
			)
		)
	)
	(zone
		(layer "In1.Cu")
		(hatch none 0.5)
		(connect_pads
			(clearance 0)
		)
		(min_thickness 0.25)
		(keepout
			(tracks not_allowed)
			(vias allowed)
			(pads allowed)
			(copperpour not_allowed)
			(footprints allowed)
		)
		(placement
			(enabled no)
			(sheetname "")
		)
		(fill
			(thermal_gap 0.5)
			(thermal_bridge_width 0.5)
			(island_removal_mode 0)
		)
		(polygon
			(pts
				(arc
					(start 161.106104 -408.860244)
					(mid 161.128422 -408.914126)
					(end 161.182304 -408.936444)
				)
				(arc
					(start 161.377884 -408.936444)
					(mid 161.39976 -408.933312)
					(end 161.419794 -408.923998)
				)
				(arc
					(start 161.713418 -408.731466)
					(mid 161.755074 -408.719064)
					(end 161.79673 -408.731466)
				)
				(arc
					(start 162.091624 -408.923998)
					(mid 162.111548 -408.933234)
					(end 162.13328 -408.936444)
				)
				(arc
					(start 162.327844 -408.936444)
					(mid 162.381726 -408.914126)
					(end 162.404044 -408.860244)
				)
				(arc
					(start 162.404044 -408.174444)
					(mid 162.381726 -408.120562)
					(end 162.327844 -408.098244)
				)
				(arc
					(start 162.13328 -408.098244)
					(mid 162.111536 -408.101412)
					(end 162.091624 -408.11069)
				)
				(arc
					(start 161.79546 -408.303476)
					(mid 161.753776 -408.315698)
					(end 161.712148 -408.303222)
				)
				(arc
					(start 161.418524 -408.11069)
					(mid 161.3986 -408.101454)
					(end 161.376868 -408.098244)
				)
				(arc
					(start 161.182304 -408.098244)
					(mid 161.128422 -408.120562)
					(end 161.106104 -408.174444)
				)
			)
		)
	)
	(zone
		(layer "In1.Cu")
		(hatch none 0.5)
		(connect_pads
			(clearance 0)
		)
		(min_thickness 0.25)
		(keepout
			(tracks not_allowed)
			(vias allowed)
			(pads allowed)
			(copperpour not_allowed)
			(footprints allowed)
		)
		(placement
			(enabled no)
			(sheetname "")
		)
		(fill
			(thermal_gap 0.5)
			(thermal_bridge_width 0.5)
			(island_removal_mode 0)
		)
		(polygon
			(pts
				(arc
					(start 344.931238 -408.860244)
					(mid 344.953556 -408.914126)
					(end 345.007438 -408.936444)
				)
				(arc
					(start 345.203018 -408.936444)
					(mid 345.224894 -408.933312)
					(end 345.244928 -408.923998)
				)
				(arc
					(start 345.538552 -408.731466)
					(mid 345.580208 -408.719064)
					(end 345.621864 -408.731466)
				)
				(arc
					(start 345.916758 -408.923998)
					(mid 345.936682 -408.933234)
					(end 345.958414 -408.936444)
				)
				(arc
					(start 346.152978 -408.936444)
					(mid 346.20686 -408.914126)
					(end 346.229178 -408.860244)
				)
				(arc
					(start 346.229178 -408.174444)
					(mid 346.20686 -408.120562)
					(end 346.152978 -408.098244)
				)
				(arc
					(start 345.958414 -408.098244)
					(mid 345.93667 -408.101412)
					(end 345.916758 -408.11069)
				)
				(arc
					(start 345.620594 -408.303476)
					(mid 345.57891 -408.315698)
					(end 345.537282 -408.303222)
				)
				(arc
					(start 345.243658 -408.11069)
					(mid 345.223734 -408.101454)
					(end 345.202002 -408.098244)
				)
				(arc
					(start 345.007438 -408.098244)
					(mid 344.953556 -408.120562)
					(end 344.931238 -408.174444)
				)
			)
		)
	)
	(zone
		(layer "In1.Cu")
		(hatch none 0.5)
		(connect_pads
			(clearance 0)
		)
		(min_thickness 0.25)
		(keepout
			(tracks not_allowed)
			(vias allowed)
			(pads allowed)
			(copperpour not_allowed)
			(footprints allowed)
		)
		(placement
			(enabled no)
			(sheetname "")
		)
		(fill
			(thermal_gap 0.5)
			(thermal_bridge_width 0.5)
			(island_removal_mode 0)
		)
		(polygon
			(pts
				(arc
					(start 400.066002 -7.672324)
					(mid 400.043684 -7.618442)
					(end 399.989802 -7.596124)
				)
				(arc
					(start 398.708372 -7.596124)
					(mid 398.65449 -7.618442)
					(end 398.632172 -7.672324)
				)
				(arc
					(start 398.632172 -9.094724)
					(mid 398.65449 -9.148606)
					(end 398.708372 -9.170924)
				)
				(arc
					(start 399.989802 -9.170924)
					(mid 400.043684 -9.148606)
					(end 400.066002 -9.094724)
				)
			)
		)
	)
	(zone
		(layer "In1.Cu")
		(hatch none 0.5)
		(connect_pads
			(clearance 0)
		)
		(min_thickness 0.25)
		(keepout
			(tracks not_allowed)
			(vias allowed)
			(pads allowed)
			(copperpour not_allowed)
			(footprints allowed)
		)
		(placement
			(enabled no)
			(sheetname "")
		)
		(fill
			(thermal_gap 0.5)
			(thermal_bridge_width 0.5)
			(island_removal_mode 0)
		)
		(polygon
			(pts
				(arc
					(start 398.77492 -402.713952)
					(mid 398.797238 -402.767834)
					(end 398.85112 -402.790152)
				)
				(arc
					(start 399.0467 -402.790152)
					(mid 399.068576 -402.78702)
					(end 399.08861 -402.777706)
				)
				(arc
					(start 399.382234 -402.585174)
					(mid 399.42389 -402.572772)
					(end 399.465546 -402.585174)
				)
				(arc
					(start 399.76044 -402.777706)
					(mid 399.780364 -402.786942)
					(end 399.802096 -402.790152)
				)
				(arc
					(start 399.99666 -402.790152)
					(mid 400.050542 -402.767834)
					(end 400.07286 -402.713952)
				)
				(arc
					(start 400.07286 -402.028152)
					(mid 400.050542 -401.97427)
					(end 399.99666 -401.951952)
				)
				(arc
					(start 399.802096 -401.951952)
					(mid 399.780352 -401.95512)
					(end 399.76044 -401.964398)
				)
				(arc
					(start 399.464276 -402.157184)
					(mid 399.422592 -402.169406)
					(end 399.380964 -402.15693)
				)
				(arc
					(start 399.08734 -401.964398)
					(mid 399.067416 -401.955162)
					(end 399.045684 -401.951952)
				)
				(arc
					(start 398.85112 -401.951952)
					(mid 398.797238 -401.97427)
					(end 398.77492 -402.028152)
				)
			)
		)
	)
	(zone
		(layer "In1.Cu")
		(hatch none 0.5)
		(connect_pads
			(clearance 0)
		)
		(min_thickness 0.25)
		(keepout
			(tracks not_allowed)
			(vias allowed)
			(pads allowed)
			(copperpour not_allowed)
			(footprints allowed)
		)
		(placement
			(enabled no)
			(sheetname "")
		)
		(fill
			(thermal_gap 0.5)
			(thermal_bridge_width 0.5)
			(island_removal_mode 0)
		)
		(polygon
			(pts
				(arc
					(start 326.551798 -408.860244)
					(mid 326.574116 -408.914126)
					(end 326.627998 -408.936444)
				)
				(arc
					(start 326.823578 -408.936444)
					(mid 326.845454 -408.933312)
					(end 326.865488 -408.923998)
				)
				(arc
					(start 327.159112 -408.731466)
					(mid 327.200768 -408.719064)
					(end 327.242424 -408.731466)
				)
				(arc
					(start 327.537318 -408.923998)
					(mid 327.557242 -408.933234)
					(end 327.578974 -408.936444)
				)
				(arc
					(start 327.773538 -408.936444)
					(mid 327.82742 -408.914126)
					(end 327.849738 -408.860244)
				)
				(arc
					(start 327.849738 -408.174444)
					(mid 327.82742 -408.120562)
					(end 327.773538 -408.098244)
				)
				(arc
					(start 327.578974 -408.098244)
					(mid 327.55723 -408.101412)
					(end 327.537318 -408.11069)
				)
				(arc
					(start 327.241154 -408.303476)
					(mid 327.19947 -408.315698)
					(end 327.157842 -408.303222)
				)
				(arc
					(start 326.864218 -408.11069)
					(mid 326.844294 -408.101454)
					(end 326.822562 -408.098244)
				)
				(arc
					(start 326.627998 -408.098244)
					(mid 326.574116 -408.120562)
					(end 326.551798 -408.174444)
				)
			)
		)
	)
	(zone
		(layer "In1.Cu")
		(hatch none 0.5)
		(connect_pads
			(clearance 0)
		)
		(min_thickness 0.25)
		(keepout
			(tracks not_allowed)
			(vias allowed)
			(pads allowed)
			(copperpour not_allowed)
			(footprints allowed)
		)
		(placement
			(enabled no)
			(sheetname "")
		)
		(fill
			(thermal_gap 0.5)
			(thermal_bridge_width 0.5)
			(island_removal_mode 0)
		)
		(polygon
			(pts
				(arc
					(start 130.473704 -408.860244)
					(mid 130.496022 -408.914126)
					(end 130.549904 -408.936444)
				)
				(arc
					(start 130.745484 -408.936444)
					(mid 130.76736 -408.933312)
					(end 130.787394 -408.923998)
				)
				(arc
					(start 131.081018 -408.731466)
					(mid 131.122674 -408.719064)
					(end 131.16433 -408.731466)
				)
				(arc
					(start 131.459224 -408.923998)
					(mid 131.479148 -408.933234)
					(end 131.50088 -408.936444)
				)
				(arc
					(start 131.695444 -408.936444)
					(mid 131.749326 -408.914126)
					(end 131.771644 -408.860244)
				)
				(arc
					(start 131.771644 -408.174444)
					(mid 131.749326 -408.120562)
					(end 131.695444 -408.098244)
				)
				(arc
					(start 131.50088 -408.098244)
					(mid 131.479136 -408.101412)
					(end 131.459224 -408.11069)
				)
				(arc
					(start 131.16306 -408.303476)
					(mid 131.121376 -408.315698)
					(end 131.079748 -408.303222)
				)
				(arc
					(start 130.786124 -408.11069)
					(mid 130.7662 -408.101454)
					(end 130.744468 -408.098244)
				)
				(arc
					(start 130.549904 -408.098244)
					(mid 130.496022 -408.120562)
					(end 130.473704 -408.174444)
				)
			)
		)
	)
	(zone
		(layer "In1.Cu")
		(hatch none 0.5)
		(connect_pads
			(clearance 0)
		)
		(min_thickness 0.25)
		(keepout
			(tracks not_allowed)
			(vias allowed)
			(pads allowed)
			(copperpour not_allowed)
			(footprints allowed)
		)
		(placement
			(enabled no)
			(sheetname "")
		)
		(fill
			(thermal_gap 0.5)
			(thermal_bridge_width 0.5)
			(island_removal_mode 0)
		)
		(polygon
			(pts
				(arc
					(start 53.889148 -402.713952)
					(mid 53.911466 -402.767834)
					(end 53.965348 -402.790152)
				)
				(arc
					(start 54.160928 -402.790152)
					(mid 54.182804 -402.78702)
					(end 54.202838 -402.777706)
				)
				(arc
					(start 54.496462 -402.585174)
					(mid 54.538118 -402.572772)
					(end 54.579774 -402.585174)
				)
				(arc
					(start 54.874668 -402.777706)
					(mid 54.894592 -402.786942)
					(end 54.916324 -402.790152)
				)
				(arc
					(start 55.110888 -402.790152)
					(mid 55.16477 -402.767834)
					(end 55.187088 -402.713952)
				)
				(arc
					(start 55.187088 -402.028152)
					(mid 55.16477 -401.97427)
					(end 55.110888 -401.951952)
				)
				(arc
					(start 54.916324 -401.951952)
					(mid 54.89458 -401.95512)
					(end 54.874668 -401.964398)
				)
				(arc
					(start 54.578504 -402.157184)
					(mid 54.53682 -402.169406)
					(end 54.495192 -402.15693)
				)
				(arc
					(start 54.201568 -401.964398)
					(mid 54.181644 -401.955162)
					(end 54.159912 -401.951952)
				)
				(arc
					(start 53.965348 -401.951952)
					(mid 53.911466 -401.97427)
					(end 53.889148 -402.028152)
				)
			)
		)
	)
	(zone
		(layer "In1.Cu")
		(hatch none 0.5)
		(connect_pads
			(clearance 0)
		)
		(min_thickness 0.25)
		(keepout
			(tracks not_allowed)
			(vias allowed)
			(pads allowed)
			(copperpour not_allowed)
			(footprints allowed)
		)
		(placement
			(enabled no)
			(sheetname "")
		)
		(fill
			(thermal_gap 0.5)
			(thermal_bridge_width 0.5)
			(island_removal_mode 0)
		)
		(polygon
			(pts
				(arc
					(start 429.385984 -7.672324)
					(mid 429.363666 -7.618442)
					(end 429.309784 -7.596124)
				)
				(arc
					(start 428.028354 -7.596124)
					(mid 427.974472 -7.618442)
					(end 427.952154 -7.672324)
				)
				(arc
					(start 427.952154 -9.094724)
					(mid 427.974472 -9.148606)
					(end 428.028354 -9.170924)
				)
				(arc
					(start 429.309784 -9.170924)
					(mid 429.363666 -9.148606)
					(end 429.385984 -9.094724)
				)
			)
		)
	)
	(zone
		(layer "In1.Cu")
		(hatch none 0.5)
		(connect_pads
			(clearance 0)
		)
		(min_thickness 0.25)
		(keepout
			(tracks not_allowed)
			(vias allowed)
			(pads allowed)
			(copperpour not_allowed)
			(footprints allowed)
		)
		(placement
			(enabled no)
			(sheetname "")
		)
		(fill
			(thermal_gap 0.5)
			(thermal_bridge_width 0.5)
			(island_removal_mode 0)
		)
		(polygon
			(pts
				(arc
					(start 231.43464 -58.361326)
					(mid 231.380758 -58.339008)
					(end 231.35844 -58.285126)
				)
				(arc
					(start 231.35844 -57.457086)
					(mid 231.380758 -57.403204)
					(end 231.43464 -57.380886)
				)
				(arc
					(start 232.55986 -57.380886)
					(mid 232.613742 -57.403204)
					(end 232.63606 -57.457086)
				)
				(arc
					(start 232.63606 -58.285126)
					(mid 232.613742 -58.339008)
					(end 232.55986 -58.361326)
				)
			)
		)
	)
	(zone
		(layer "In1.Cu")
		(hatch none 0.5)
		(connect_pads
			(clearance 0)
		)
		(min_thickness 0.25)
		(keepout
			(tracks not_allowed)
			(vias allowed)
			(pads allowed)
			(copperpour not_allowed)
			(footprints allowed)
		)
		(placement
			(enabled no)
			(sheetname "")
		)
		(fill
			(thermal_gap 0.5)
			(thermal_bridge_width 0.5)
			(island_removal_mode 0)
		)
		(polygon
			(pts
				(arc
					(start 416.376104 -7.672324)
					(mid 416.353786 -7.618442)
					(end 416.299904 -7.596124)
				)
				(arc
					(start 415.018474 -7.596124)
					(mid 414.964592 -7.618442)
					(end 414.942274 -7.672324)
				)
				(arc
					(start 414.942274 -9.094724)
					(mid 414.964592 -9.148606)
					(end 415.018474 -9.170924)
				)
				(arc
					(start 416.299904 -9.170924)
					(mid 416.353786 -9.148606)
					(end 416.376104 -9.094724)
				)
			)
		)
	)
	(zone
		(layer "In1.Cu")
		(hatch none 0.5)
		(connect_pads
			(clearance 0)
		)
		(min_thickness 0.25)
		(keepout
			(tracks not_allowed)
			(vias allowed)
			(pads allowed)
			(copperpour not_allowed)
			(footprints allowed)
		)
		(placement
			(enabled no)
			(sheetname "")
		)
		(fill
			(thermal_gap 0.5)
			(thermal_bridge_width 0.5)
			(island_removal_mode 0)
		)
		(polygon
			(pts
				(arc
					(start 328.126852 6.009894)
					(mid 328.14917 6.063776)
					(end 328.203052 6.086094)
				)
				(arc
					(start 328.815192 6.086094)
					(mid 328.869074 6.063776)
					(end 328.891392 6.009894)
				)
				(arc
					(start 328.891392 4.912614)
					(mid 328.869074 4.858732)
					(end 328.815192 4.836414)
				)
				(arc
					(start 328.203052 4.836414)
					(mid 328.14917 4.858732)
					(end 328.126852 4.912614)
				)
			)
		)
	)
	(zone
		(layer "In1.Cu")
		(hatch none 0.5)
		(connect_pads
			(clearance 0)
		)
		(min_thickness 0.25)
		(keepout
			(tracks not_allowed)
			(vias allowed)
			(pads allowed)
			(copperpour not_allowed)
			(footprints allowed)
		)
		(placement
			(enabled no)
			(sheetname "")
		)
		(fill
			(thermal_gap 0.5)
			(thermal_bridge_width 0.5)
			(island_removal_mode 0)
		)
		(polygon
			(pts
				(arc
					(start 231.43464 -52.961286)
					(mid 231.380758 -52.938968)
					(end 231.35844 -52.885086)
				)
				(arc
					(start 231.35844 -52.057046)
					(mid 231.380758 -52.003164)
					(end 231.43464 -51.980846)
				)
				(arc
					(start 232.55986 -51.980846)
					(mid 232.613742 -52.003164)
					(end 232.63606 -52.057046)
				)
				(arc
					(start 232.63606 -52.885086)
					(mid 232.613742 -52.938968)
					(end 232.55986 -52.961286)
				)
			)
		)
	)
	(zone
		(layer "In1.Cu")
		(hatch none 0.5)
		(connect_pads
			(clearance 0)
		)
		(min_thickness 0.25)
		(keepout
			(tracks not_allowed)
			(vias allowed)
			(pads allowed)
			(copperpour not_allowed)
			(footprints allowed)
		)
		(placement
			(enabled no)
			(sheetname "")
		)
		(fill
			(thermal_gap 0.5)
			(thermal_bridge_width 0.5)
			(island_removal_mode 0)
		)
		(polygon
			(pts
				(arc
					(start 78.395068 -402.713952)
					(mid 78.417386 -402.767834)
					(end 78.471268 -402.790152)
				)
				(arc
					(start 78.666848 -402.790152)
					(mid 78.688724 -402.78702)
					(end 78.708758 -402.777706)
				)
				(arc
					(start 79.002382 -402.585174)
					(mid 79.044038 -402.572772)
					(end 79.085694 -402.585174)
				)
				(arc
					(start 79.380588 -402.777706)
					(mid 79.400512 -402.786942)
					(end 79.422244 -402.790152)
				)
				(arc
					(start 79.616808 -402.790152)
					(mid 79.67069 -402.767834)
					(end 79.693008 -402.713952)
				)
				(arc
					(start 79.693008 -402.028152)
					(mid 79.67069 -401.97427)
					(end 79.616808 -401.951952)
				)
				(arc
					(start 79.422244 -401.951952)
					(mid 79.4005 -401.95512)
					(end 79.380588 -401.964398)
				)
				(arc
					(start 79.084424 -402.157184)
					(mid 79.04274 -402.169406)
					(end 79.001112 -402.15693)
				)
				(arc
					(start 78.707488 -401.964398)
					(mid 78.687564 -401.955162)
					(end 78.665832 -401.951952)
				)
				(arc
					(start 78.471268 -401.951952)
					(mid 78.417386 -401.97427)
					(end 78.395068 -402.028152)
				)
			)
		)
	)
	(zone
		(layer "In1.Cu")
		(hatch none 0.5)
		(connect_pads
			(clearance 0)
		)
		(min_thickness 0.25)
		(keepout
			(tracks not_allowed)
			(vias allowed)
			(pads allowed)
			(copperpour not_allowed)
			(footprints allowed)
		)
		(placement
			(enabled no)
			(sheetname "")
		)
		(fill
			(thermal_gap 0.5)
			(thermal_bridge_width 0.5)
			(island_removal_mode 0)
		)
		(polygon
			(pts
				(arc
					(start 81.458308 -402.713952)
					(mid 81.480626 -402.767834)
					(end 81.534508 -402.790152)
				)
				(arc
					(start 81.730088 -402.790152)
					(mid 81.751964 -402.78702)
					(end 81.771998 -402.777706)
				)
				(arc
					(start 82.065622 -402.585174)
					(mid 82.107278 -402.572772)
					(end 82.148934 -402.585174)
				)
				(arc
					(start 82.443828 -402.777706)
					(mid 82.463752 -402.786942)
					(end 82.485484 -402.790152)
				)
				(arc
					(start 82.680048 -402.790152)
					(mid 82.73393 -402.767834)
					(end 82.756248 -402.713952)
				)
				(arc
					(start 82.756248 -402.028152)
					(mid 82.73393 -401.97427)
					(end 82.680048 -401.951952)
				)
				(arc
					(start 82.485484 -401.951952)
					(mid 82.46374 -401.95512)
					(end 82.443828 -401.964398)
				)
				(arc
					(start 82.147664 -402.157184)
					(mid 82.10598 -402.169406)
					(end 82.064352 -402.15693)
				)
				(arc
					(start 81.770728 -401.964398)
					(mid 81.750804 -401.955162)
					(end 81.729072 -401.951952)
				)
				(arc
					(start 81.534508 -401.951952)
					(mid 81.480626 -401.97427)
					(end 81.458308 -402.028152)
				)
			)
		)
	)
	(zone
		(layer "In1.Cu")
		(hatch none 0.5)
		(connect_pads
			(clearance 0)
		)
		(min_thickness 0.25)
		(keepout
			(tracks not_allowed)
			(vias allowed)
			(pads allowed)
			(copperpour not_allowed)
			(footprints allowed)
		)
		(placement
			(enabled no)
			(sheetname "")
		)
		(fill
			(thermal_gap 0.5)
			(thermal_bridge_width 0.5)
			(island_removal_mode 0)
		)
		(polygon
			(pts
				(arc
					(start 314.298838 -408.860244)
					(mid 314.321156 -408.914126)
					(end 314.375038 -408.936444)
				)
				(arc
					(start 314.570618 -408.936444)
					(mid 314.592494 -408.933312)
					(end 314.612528 -408.923998)
				)
				(arc
					(start 314.906152 -408.731466)
					(mid 314.947808 -408.719064)
					(end 314.989464 -408.731466)
				)
				(arc
					(start 315.284358 -408.923998)
					(mid 315.304282 -408.933234)
					(end 315.326014 -408.936444)
				)
				(arc
					(start 315.520578 -408.936444)
					(mid 315.57446 -408.914126)
					(end 315.596778 -408.860244)
				)
				(arc
					(start 315.596778 -408.174444)
					(mid 315.57446 -408.120562)
					(end 315.520578 -408.098244)
				)
				(arc
					(start 315.326014 -408.098244)
					(mid 315.30427 -408.101412)
					(end 315.284358 -408.11069)
				)
				(arc
					(start 314.988194 -408.303476)
					(mid 314.94651 -408.315698)
					(end 314.904882 -408.303222)
				)
				(arc
					(start 314.611258 -408.11069)
					(mid 314.591334 -408.101454)
					(end 314.569602 -408.098244)
				)
				(arc
					(start 314.375038 -408.098244)
					(mid 314.321156 -408.120562)
					(end 314.298838 -408.174444)
				)
			)
		)
	)
	(zone
		(layer "In1.Cu")
		(hatch none 0.5)
		(connect_pads
			(clearance 0)
		)
		(min_thickness 0.25)
		(keepout
			(tracks not_allowed)
			(vias allowed)
			(pads allowed)
			(copperpour not_allowed)
			(footprints allowed)
		)
		(placement
			(enabled no)
			(sheetname "")
		)
		(fill
			(thermal_gap 0.5)
			(thermal_bridge_width 0.5)
			(island_removal_mode 0)
		)
		(polygon
			(pts
				(arc
					(start 393.99464 -408.860244)
					(mid 394.016958 -408.914126)
					(end 394.07084 -408.936444)
				)
				(arc
					(start 394.26642 -408.936444)
					(mid 394.288296 -408.933312)
					(end 394.30833 -408.923998)
				)
				(arc
					(start 394.601954 -408.731466)
					(mid 394.64361 -408.719064)
					(end 394.685266 -408.731466)
				)
				(arc
					(start 394.98016 -408.923998)
					(mid 395.000084 -408.933234)
					(end 395.021816 -408.936444)
				)
				(arc
					(start 395.21638 -408.936444)
					(mid 395.270262 -408.914126)
					(end 395.29258 -408.860244)
				)
				(arc
					(start 395.29258 -408.174444)
					(mid 395.270262 -408.120562)
					(end 395.21638 -408.098244)
				)
				(arc
					(start 395.021816 -408.098244)
					(mid 395.000072 -408.101412)
					(end 394.98016 -408.11069)
				)
				(arc
					(start 394.683996 -408.303476)
					(mid 394.642312 -408.315698)
					(end 394.600684 -408.303222)
				)
				(arc
					(start 394.30706 -408.11069)
					(mid 394.287136 -408.101454)
					(end 394.265404 -408.098244)
				)
				(arc
					(start 394.07084 -408.098244)
					(mid 394.016958 -408.120562)
					(end 393.99464 -408.174444)
				)
			)
		)
	)
	(zone
		(layer "In1.Cu")
		(hatch none 0.5)
		(connect_pads
			(clearance 0)
		)
		(min_thickness 0.25)
		(keepout
			(tracks not_allowed)
			(vias allowed)
			(pads allowed)
			(copperpour not_allowed)
			(footprints allowed)
		)
		(placement
			(enabled no)
			(sheetname "")
		)
		(fill
			(thermal_gap 0.5)
			(thermal_bridge_width 0.5)
			(island_removal_mode 0)
		)
		(polygon
			(pts
				(arc
					(start 15.316708 -16.442436)
					(mid 15.339026 -16.496318)
					(end 15.392908 -16.518636)
				)
				(arc
					(start 15.588488 -16.518636)
					(mid 15.610364 -16.515504)
					(end 15.630398 -16.50619)
				)
				(arc
					(start 15.924022 -16.313658)
					(mid 15.965678 -16.301256)
					(end 16.007334 -16.313658)
				)
				(arc
					(start 16.302228 -16.50619)
					(mid 16.322152 -16.515426)
					(end 16.343884 -16.518636)
				)
				(arc
					(start 16.538448 -16.518636)
					(mid 16.59233 -16.496318)
					(end 16.614648 -16.442436)
				)
				(arc
					(start 16.614648 -15.756636)
					(mid 16.59233 -15.702754)
					(end 16.538448 -15.680436)
				)
				(arc
					(start 16.343884 -15.680436)
					(mid 16.32214 -15.683604)
					(end 16.302228 -15.692882)
				)
				(arc
					(start 16.006064 -15.885668)
					(mid 15.96438 -15.89789)
					(end 15.922752 -15.885414)
				)
				(arc
					(start 15.629128 -15.692882)
					(mid 15.609204 -15.683646)
					(end 15.587472 -15.680436)
				)
				(arc
					(start 15.392908 -15.680436)
					(mid 15.339026 -15.702754)
					(end 15.316708 -15.756636)
				)
			)
		)
	)
	(zone
		(layer "In1.Cu")
		(hatch none 0.5)
		(connect_pads
			(clearance 0)
		)
		(min_thickness 0.25)
		(keepout
			(tracks not_allowed)
			(vias allowed)
			(pads allowed)
			(copperpour not_allowed)
			(footprints allowed)
		)
		(placement
			(enabled no)
			(sheetname "")
		)
		(fill
			(thermal_gap 0.5)
			(thermal_bridge_width 0.5)
			(island_removal_mode 0)
		)
		(polygon
			(pts
				(arc
					(start 67.488308 -408.860244)
					(mid 67.510626 -408.914126)
					(end 67.564508 -408.936444)
				)
				(arc
					(start 67.760088 -408.936444)
					(mid 67.781964 -408.933312)
					(end 67.801998 -408.923998)
				)
				(arc
					(start 68.095622 -408.731466)
					(mid 68.137278 -408.719064)
					(end 68.178934 -408.731466)
				)
				(arc
					(start 68.473828 -408.923998)
					(mid 68.493752 -408.933234)
					(end 68.515484 -408.936444)
				)
				(arc
					(start 68.710048 -408.936444)
					(mid 68.76393 -408.914126)
					(end 68.786248 -408.860244)
				)
				(arc
					(start 68.786248 -408.174444)
					(mid 68.76393 -408.120562)
					(end 68.710048 -408.098244)
				)
				(arc
					(start 68.515484 -408.098244)
					(mid 68.49374 -408.101412)
					(end 68.473828 -408.11069)
				)
				(arc
					(start 68.177664 -408.303476)
					(mid 68.13598 -408.315698)
					(end 68.094352 -408.303222)
				)
				(arc
					(start 67.800728 -408.11069)
					(mid 67.780804 -408.101454)
					(end 67.759072 -408.098244)
				)
				(arc
					(start 67.564508 -408.098244)
					(mid 67.510626 -408.120562)
					(end 67.488308 -408.174444)
				)
			)
		)
	)
	(zone
		(layer "In1.Cu")
		(hatch none 0.5)
		(connect_pads
			(clearance 0)
		)
		(min_thickness 0.25)
		(keepout
			(tracks not_allowed)
			(vias allowed)
			(pads allowed)
			(copperpour not_allowed)
			(footprints allowed)
		)
		(placement
			(enabled no)
			(sheetname "")
		)
		(fill
			(thermal_gap 0.5)
			(thermal_bridge_width 0.5)
			(island_removal_mode 0)
		)
		(polygon
			(pts
				(arc
					(start 132.190744 -402.713952)
					(mid 132.213062 -402.767834)
					(end 132.266944 -402.790152)
				)
				(arc
					(start 132.462524 -402.790152)
					(mid 132.4844 -402.78702)
					(end 132.504434 -402.777706)
				)
				(arc
					(start 132.798058 -402.585174)
					(mid 132.839714 -402.572772)
					(end 132.88137 -402.585174)
				)
				(arc
					(start 133.176264 -402.777706)
					(mid 133.196188 -402.786942)
					(end 133.21792 -402.790152)
				)
				(arc
					(start 133.412484 -402.790152)
					(mid 133.466366 -402.767834)
					(end 133.488684 -402.713952)
				)
				(arc
					(start 133.488684 -402.028152)
					(mid 133.466366 -401.97427)
					(end 133.412484 -401.951952)
				)
				(arc
					(start 133.21792 -401.951952)
					(mid 133.196176 -401.95512)
					(end 133.176264 -401.964398)
				)
				(arc
					(start 132.8801 -402.157184)
					(mid 132.838416 -402.169406)
					(end 132.796788 -402.15693)
				)
				(arc
					(start 132.503164 -401.964398)
					(mid 132.48324 -401.955162)
					(end 132.461508 -401.951952)
				)
				(arc
					(start 132.266944 -401.951952)
					(mid 132.213062 -401.97427)
					(end 132.190744 -402.028152)
				)
			)
		)
	)
	(zone
		(layer "In1.Cu")
		(hatch none 0.5)
		(connect_pads
			(clearance 0)
		)
		(min_thickness 0.25)
		(keepout
			(tracks not_allowed)
			(vias allowed)
			(pads allowed)
			(copperpour not_allowed)
			(footprints allowed)
		)
		(placement
			(enabled no)
			(sheetname "")
		)
		(fill
			(thermal_gap 0.5)
			(thermal_bridge_width 0.5)
			(island_removal_mode 0)
		)
		(polygon
			(pts
				(arc
					(start 409.31084 -408.860244)
					(mid 409.333158 -408.914126)
					(end 409.38704 -408.936444)
				)
				(arc
					(start 409.58262 -408.936444)
					(mid 409.604496 -408.933312)
					(end 409.62453 -408.923998)
				)
				(arc
					(start 409.918154 -408.731466)
					(mid 409.95981 -408.719064)
					(end 410.001466 -408.731466)
				)
				(arc
					(start 410.29636 -408.923998)
					(mid 410.316284 -408.933234)
					(end 410.338016 -408.936444)
				)
				(arc
					(start 410.53258 -408.936444)
					(mid 410.586462 -408.914126)
					(end 410.60878 -408.860244)
				)
				(arc
					(start 410.60878 -408.174444)
					(mid 410.586462 -408.120562)
					(end 410.53258 -408.098244)
				)
				(arc
					(start 410.338016 -408.098244)
					(mid 410.316272 -408.101412)
					(end 410.29636 -408.11069)
				)
				(arc
					(start 410.000196 -408.303476)
					(mid 409.958512 -408.315698)
					(end 409.916884 -408.303222)
				)
				(arc
					(start 409.62326 -408.11069)
					(mid 409.603336 -408.101454)
					(end 409.581604 -408.098244)
				)
				(arc
					(start 409.38704 -408.098244)
					(mid 409.333158 -408.120562)
					(end 409.31084 -408.174444)
				)
			)
		)
	)
	(zone
		(layer "In1.Cu")
		(hatch none 0.5)
		(connect_pads
			(clearance 0)
		)
		(min_thickness 0.25)
		(keepout
			(tracks not_allowed)
			(vias allowed)
			(pads allowed)
			(copperpour not_allowed)
			(footprints allowed)
		)
		(placement
			(enabled no)
			(sheetname "")
		)
		(fill
			(thermal_gap 0.5)
			(thermal_bridge_width 0.5)
			(island_removal_mode 0)
		)
		(polygon
			(pts
				(arc
					(start 404.9014 -402.713952)
					(mid 404.923718 -402.767834)
					(end 404.9776 -402.790152)
				)
				(arc
					(start 405.17318 -402.790152)
					(mid 405.195056 -402.78702)
					(end 405.21509 -402.777706)
				)
				(arc
					(start 405.508714 -402.585174)
					(mid 405.55037 -402.572772)
					(end 405.592026 -402.585174)
				)
				(arc
					(start 405.88692 -402.777706)
					(mid 405.906844 -402.786942)
					(end 405.928576 -402.790152)
				)
				(arc
					(start 406.12314 -402.790152)
					(mid 406.177022 -402.767834)
					(end 406.19934 -402.713952)
				)
				(arc
					(start 406.19934 -402.028152)
					(mid 406.177022 -401.97427)
					(end 406.12314 -401.951952)
				)
				(arc
					(start 405.928576 -401.951952)
					(mid 405.906832 -401.95512)
					(end 405.88692 -401.964398)
				)
				(arc
					(start 405.590756 -402.157184)
					(mid 405.549072 -402.169406)
					(end 405.507444 -402.15693)
				)
				(arc
					(start 405.21382 -401.964398)
					(mid 405.193896 -401.955162)
					(end 405.172164 -401.951952)
				)
				(arc
					(start 404.9776 -401.951952)
					(mid 404.923718 -401.97427)
					(end 404.9014 -402.028152)
				)
			)
		)
	)
	(zone
		(layer "In1.Cu")
		(hatch none 0.5)
		(connect_pads
			(clearance 0)
		)
		(min_thickness 0.25)
		(keepout
			(tracks not_allowed)
			(vias allowed)
			(pads allowed)
			(copperpour not_allowed)
			(footprints allowed)
		)
		(placement
			(enabled no)
			(sheetname "")
		)
		(fill
			(thermal_gap 0.5)
			(thermal_bridge_width 0.5)
			(island_removal_mode 0)
		)
		(polygon
			(pts
				(arc
					(start 18.728944 -11.91768)
					(mid 18.751262 -11.971562)
					(end 18.805144 -11.99388)
				)
				(arc
					(start 20.086574 -11.99388)
					(mid 20.140456 -11.971562)
					(end 20.162774 -11.91768)
				)
				(arc
					(start 20.162774 -10.49528)
					(mid 20.140456 -10.441398)
					(end 20.086574 -10.41908)
				)
				(arc
					(start 18.805144 -10.41908)
					(mid 18.751262 -10.441398)
					(end 18.728944 -10.49528)
				)
			)
		)
	)
	(zone
		(layer "In1.Cu")
		(hatch none 0.5)
		(connect_pads
			(clearance 0)
		)
		(min_thickness 0.25)
		(keepout
			(tracks not_allowed)
			(vias allowed)
			(pads allowed)
			(copperpour not_allowed)
			(footprints allowed)
		)
		(placement
			(enabled no)
			(sheetname "")
		)
		(fill
			(thermal_gap 0.5)
			(thermal_bridge_width 0.5)
			(island_removal_mode 0)
		)
		(polygon
			(pts
				(arc
					(start 236.03458 -54.761384)
					(mid 235.980698 -54.739066)
					(end 235.95838 -54.685184)
				)
				(arc
					(start 235.95838 -53.857144)
					(mid 235.980698 -53.803262)
					(end 236.03458 -53.780944)
				)
				(arc
					(start 237.1598 -53.780944)
					(mid 237.213682 -53.803262)
					(end 237.236 -53.857144)
				)
				(arc
					(start 237.236 -54.685184)
					(mid 237.213682 -54.739066)
					(end 237.1598 -54.761384)
				)
			)
		)
	)
	(zone
		(layer "In1.Cu")
		(hatch none 0.5)
		(connect_pads
			(clearance 0)
		)
		(min_thickness 0.25)
		(keepout
			(tracks not_allowed)
			(vias allowed)
			(pads allowed)
			(copperpour not_allowed)
			(footprints allowed)
		)
		(placement
			(enabled no)
			(sheetname "")
		)
		(fill
			(thermal_gap 0.5)
			(thermal_bridge_width 0.5)
			(island_removal_mode 0)
		)
		(polygon
			(pts
				(arc
					(start 159.62122 -41.530524)
					(mid 158.858712 -41.530524)
					(end 159.62122 -41.530524)
				)
			)
		)
	)
	(zone
		(layer "In1.Cu")
		(hatch none 0.5)
		(connect_pads
			(clearance 0)
		)
		(min_thickness 0.25)
		(keepout
			(tracks not_allowed)
			(vias allowed)
			(pads allowed)
			(copperpour not_allowed)
			(footprints allowed)
		)
		(placement
			(enabled no)
			(sheetname "")
		)
		(fill
			(thermal_gap 0.5)
			(thermal_bridge_width 0.5)
			(island_removal_mode 0)
		)
		(polygon
			(pts
				(arc
					(start 133.536944 -408.860244)
					(mid 133.559262 -408.914126)
					(end 133.613144 -408.936444)
				)
				(arc
					(start 133.808724 -408.936444)
					(mid 133.8306 -408.933312)
					(end 133.850634 -408.923998)
				)
				(arc
					(start 134.144258 -408.731466)
					(mid 134.185914 -408.719064)
					(end 134.22757 -408.731466)
				)
				(arc
					(start 134.522464 -408.923998)
					(mid 134.542388 -408.933234)
					(end 134.56412 -408.936444)
				)
				(arc
					(start 134.758684 -408.936444)
					(mid 134.812566 -408.914126)
					(end 134.834884 -408.860244)
				)
				(arc
					(start 134.834884 -408.174444)
					(mid 134.812566 -408.120562)
					(end 134.758684 -408.098244)
				)
				(arc
					(start 134.56412 -408.098244)
					(mid 134.542376 -408.101412)
					(end 134.522464 -408.11069)
				)
				(arc
					(start 134.2263 -408.303476)
					(mid 134.184616 -408.315698)
					(end 134.142988 -408.303222)
				)
				(arc
					(start 133.849364 -408.11069)
					(mid 133.82944 -408.101454)
					(end 133.807708 -408.098244)
				)
				(arc
					(start 133.613144 -408.098244)
					(mid 133.559262 -408.120562)
					(end 133.536944 -408.174444)
				)
			)
		)
	)
	(zone
		(layer "In1.Cu")
		(hatch none 0.5)
		(connect_pads
			(clearance 0)
		)
		(min_thickness 0.25)
		(keepout
			(tracks not_allowed)
			(vias allowed)
			(pads allowed)
			(copperpour not_allowed)
			(footprints allowed)
		)
		(placement
			(enabled no)
			(sheetname "")
		)
		(fill
			(thermal_gap 0.5)
			(thermal_bridge_width 0.5)
			(island_removal_mode 0)
		)
		(polygon
			(pts
				(arc
					(start 407.96464 -402.713952)
					(mid 407.986958 -402.767834)
					(end 408.04084 -402.790152)
				)
				(arc
					(start 408.23642 -402.790152)
					(mid 408.258296 -402.78702)
					(end 408.27833 -402.777706)
				)
				(arc
					(start 408.571954 -402.585174)
					(mid 408.61361 -402.572772)
					(end 408.655266 -402.585174)
				)
				(arc
					(start 408.95016 -402.777706)
					(mid 408.970084 -402.786942)
					(end 408.991816 -402.790152)
				)
				(arc
					(start 409.18638 -402.790152)
					(mid 409.240262 -402.767834)
					(end 409.26258 -402.713952)
				)
				(arc
					(start 409.26258 -402.028152)
					(mid 409.240262 -401.97427)
					(end 409.18638 -401.951952)
				)
				(arc
					(start 408.991816 -401.951952)
					(mid 408.970072 -401.95512)
					(end 408.95016 -401.964398)
				)
				(arc
					(start 408.653996 -402.157184)
					(mid 408.612312 -402.169406)
					(end 408.570684 -402.15693)
				)
				(arc
					(start 408.27706 -401.964398)
					(mid 408.257136 -401.955162)
					(end 408.235404 -401.951952)
				)
				(arc
					(start 408.04084 -401.951952)
					(mid 407.986958 -401.97427)
					(end 407.96464 -402.028152)
				)
			)
		)
	)
	(zone
		(layer "In1.Cu")
		(hatch none 0.5)
		(connect_pads
			(clearance 0)
		)
		(min_thickness 0.25)
		(keepout
			(tracks not_allowed)
			(vias allowed)
			(pads allowed)
			(copperpour not_allowed)
			(footprints allowed)
		)
		(placement
			(enabled no)
			(sheetname "")
		)
		(fill
			(thermal_gap 0.5)
			(thermal_bridge_width 0.5)
			(island_removal_mode 0)
		)
		(polygon
			(pts
				(arc
					(start 346.03309 -69.50964)
					(mid 346.010772 -69.455758)
					(end 345.95689 -69.43344)
				)
				(arc
					(start 345.62669 -69.43344)
					(mid 345.572808 -69.455758)
					(end 345.55049 -69.50964)
				)
				(arc
					(start 345.55049 -69.76364)
					(mid 345.572808 -69.817522)
					(end 345.62669 -69.83984)
				)
				(arc
					(start 345.95689 -69.83984)
					(mid 346.010772 -69.817522)
					(end 346.03309 -69.76364)
				)
			)
		)
	)
	(zone
		(layer "In1.Cu")
		(hatch none 0.5)
		(connect_pads
			(clearance 0)
		)
		(min_thickness 0.25)
		(keepout
			(tracks not_allowed)
			(vias allowed)
			(pads allowed)
			(copperpour not_allowed)
			(footprints allowed)
		)
		(placement
			(enabled no)
			(sheetname "")
		)
		(fill
			(thermal_gap 0.5)
			(thermal_bridge_width 0.5)
			(island_removal_mode 0)
		)
		(polygon
			(pts
				(arc
					(start 331.332078 -402.713952)
					(mid 331.354396 -402.767834)
					(end 331.408278 -402.790152)
				)
				(arc
					(start 331.603858 -402.790152)
					(mid 331.625734 -402.78702)
					(end 331.645768 -402.777706)
				)
				(arc
					(start 331.939392 -402.585174)
					(mid 331.981048 -402.572772)
					(end 332.022704 -402.585174)
				)
				(arc
					(start 332.317598 -402.777706)
					(mid 332.337522 -402.786942)
					(end 332.359254 -402.790152)
				)
				(arc
					(start 332.553818 -402.790152)
					(mid 332.6077 -402.767834)
					(end 332.630018 -402.713952)
				)
				(arc
					(start 332.630018 -402.028152)
					(mid 332.6077 -401.97427)
					(end 332.553818 -401.951952)
				)
				(arc
					(start 332.359254 -401.951952)
					(mid 332.33751 -401.95512)
					(end 332.317598 -401.964398)
				)
				(arc
					(start 332.021434 -402.157184)
					(mid 331.97975 -402.169406)
					(end 331.938122 -402.15693)
				)
				(arc
					(start 331.644498 -401.964398)
					(mid 331.624574 -401.955162)
					(end 331.602842 -401.951952)
				)
				(arc
					(start 331.408278 -401.951952)
					(mid 331.354396 -401.97427)
					(end 331.332078 -402.028152)
				)
			)
		)
	)
	(zone
		(layer "In1.Cu")
		(hatch none 0.5)
		(connect_pads
			(clearance 0)
		)
		(min_thickness 0.25)
		(keepout
			(tracks not_allowed)
			(vias allowed)
			(pads allowed)
			(copperpour not_allowed)
			(footprints allowed)
		)
		(placement
			(enabled no)
			(sheetname "")
		)
		(fill
			(thermal_gap 0.5)
			(thermal_bridge_width 0.5)
			(island_removal_mode 0)
		)
		(polygon
			(pts
				(arc
					(start 381.74168 -408.860244)
					(mid 381.763998 -408.914126)
					(end 381.81788 -408.936444)
				)
				(arc
					(start 382.01346 -408.936444)
					(mid 382.035336 -408.933312)
					(end 382.05537 -408.923998)
				)
				(arc
					(start 382.348994 -408.731466)
					(mid 382.39065 -408.719064)
					(end 382.432306 -408.731466)
				)
				(arc
					(start 382.7272 -408.923998)
					(mid 382.747124 -408.933234)
					(end 382.768856 -408.936444)
				)
				(arc
					(start 382.96342 -408.936444)
					(mid 383.017302 -408.914126)
					(end 383.03962 -408.860244)
				)
				(arc
					(start 383.03962 -408.174444)
					(mid 383.017302 -408.120562)
					(end 382.96342 -408.098244)
				)
				(arc
					(start 382.768856 -408.098244)
					(mid 382.747112 -408.101412)
					(end 382.7272 -408.11069)
				)
				(arc
					(start 382.431036 -408.303476)
					(mid 382.389352 -408.315698)
					(end 382.347724 -408.303222)
				)
				(arc
					(start 382.0541 -408.11069)
					(mid 382.034176 -408.101454)
					(end 382.012444 -408.098244)
				)
				(arc
					(start 381.81788 -408.098244)
					(mid 381.763998 -408.120562)
					(end 381.74168 -408.174444)
				)
			)
		)
	)
	(zone
		(layer "In1.Cu")
		(hatch none 0.5)
		(connect_pads
			(clearance 0)
		)
		(min_thickness 0.25)
		(keepout
			(tracks not_allowed)
			(vias allowed)
			(pads allowed)
			(copperpour not_allowed)
			(footprints allowed)
		)
		(placement
			(enabled no)
			(sheetname "")
		)
		(fill
			(thermal_gap 0.5)
			(thermal_bridge_width 0.5)
			(island_removal_mode 0)
		)
		(polygon
			(pts
				(arc
					(start 346.648278 -402.713952)
					(mid 346.670596 -402.767834)
					(end 346.724478 -402.790152)
				)
				(arc
					(start 346.920058 -402.790152)
					(mid 346.941934 -402.78702)
					(end 346.961968 -402.777706)
				)
				(arc
					(start 347.255592 -402.585174)
					(mid 347.297248 -402.572772)
					(end 347.338904 -402.585174)
				)
				(arc
					(start 347.633798 -402.777706)
					(mid 347.653722 -402.786942)
					(end 347.675454 -402.790152)
				)
				(arc
					(start 347.870018 -402.790152)
					(mid 347.9239 -402.767834)
					(end 347.946218 -402.713952)
				)
				(arc
					(start 347.946218 -402.028152)
					(mid 347.9239 -401.97427)
					(end 347.870018 -401.951952)
				)
				(arc
					(start 347.675454 -401.951952)
					(mid 347.65371 -401.95512)
					(end 347.633798 -401.964398)
				)
				(arc
					(start 347.337634 -402.157184)
					(mid 347.29595 -402.169406)
					(end 347.254322 -402.15693)
				)
				(arc
					(start 346.960698 -401.964398)
					(mid 346.940774 -401.955162)
					(end 346.919042 -401.951952)
				)
				(arc
					(start 346.724478 -401.951952)
					(mid 346.670596 -401.97427)
					(end 346.648278 -402.028152)
				)
			)
		)
	)
	(zone
		(layer "In1.Cu")
		(hatch none 0.5)
		(connect_pads
			(clearance 0)
		)
		(min_thickness 0.25)
		(keepout
			(tracks not_allowed)
			(vias allowed)
			(pads allowed)
			(copperpour not_allowed)
			(footprints allowed)
		)
		(placement
			(enabled no)
			(sheetname "")
		)
		(fill
			(thermal_gap 0.5)
			(thermal_bridge_width 0.5)
			(island_removal_mode 0)
		)
		(polygon
			(pts
				(arc
					(start 25.821132 -396.259558)
					(mid 25.782091 -396.267315)
					(end 25.74925 -396.289784)
				)
				(arc
					(start 25.74925 -396.289784)
					(mid 25.729208 -396.320472)
					(end 25.721564 -396.356332)
				)
				(xy 25.721564 -396.498572) (xy 25.721818 -396.498572)
				(arc
					(start 25.721818 -397.425926)
					(mid 25.751008 -397.489432)
					(end 25.815036 -397.517366)
				)
				(arc
					(start 26.121868 -397.517366)
					(mid 26.160909 -397.509609)
					(end 26.19375 -397.48714)
				)
				(arc
					(start 26.19375 -397.48714)
					(mid 26.213792 -397.456452)
					(end 26.221436 -397.420592)
				)
				(xy 26.221436 -396.389352) (xy 26.221182 -396.389352)
				(arc
					(start 26.221182 -396.350998)
					(mid 26.191992 -396.287492)
					(end 26.127964 -396.259558)
				)
			)
		)
	)
	(zone
		(layer "In1.Cu")
		(hatch none 0.5)
		(connect_pads
			(clearance 0)
		)
		(min_thickness 0.25)
		(keepout
			(tracks not_allowed)
			(vias allowed)
			(pads allowed)
			(copperpour not_allowed)
			(footprints allowed)
		)
		(placement
			(enabled no)
			(sheetname "")
		)
		(fill
			(thermal_gap 0.5)
			(thermal_bridge_width 0.5)
			(island_removal_mode 0)
		)
		(polygon
			(pts
				(arc
					(start 402.227796 -11.91768)
					(mid 402.250114 -11.971562)
					(end 402.303996 -11.99388)
				)
				(arc
					(start 403.585426 -11.99388)
					(mid 403.639308 -11.971562)
					(end 403.661626 -11.91768)
				)
				(arc
					(start 403.661626 -10.49528)
					(mid 403.639308 -10.441398)
					(end 403.585426 -10.41908)
				)
				(arc
					(start 402.303996 -10.41908)
					(mid 402.250114 -10.441398)
					(end 402.227796 -10.49528)
				)
			)
		)
	)
	(zone
		(layer "In1.Cu")
		(hatch none 0.5)
		(connect_pads
			(clearance 0)
		)
		(min_thickness 0.25)
		(keepout
			(tracks not_allowed)
			(vias allowed)
			(pads allowed)
			(copperpour not_allowed)
			(footprints allowed)
		)
		(placement
			(enabled no)
			(sheetname "")
		)
		(fill
			(thermal_gap 0.5)
			(thermal_bridge_width 0.5)
			(island_removal_mode 0)
		)
		(polygon
			(pts
				(arc
					(start 12.936474 -106.132884)
					(mid 12.975515 -106.125127)
					(end 13.008356 -106.102658)
				)
				(arc
					(start 13.008356 -106.102658)
					(mid 13.028398 -106.07197)
					(end 13.036042 -106.03611)
				)
				(xy 13.036042 -105.89387) (xy 13.035788 -105.89387)
				(arc
					(start 13.035788 -104.966516)
					(mid 13.006598 -104.90301)
					(end 12.94257 -104.875076)
				)
				(arc
					(start 12.635738 -104.875076)
					(mid 12.596697 -104.882833)
					(end 12.563856 -104.905302)
				)
				(arc
					(start 12.563856 -104.905302)
					(mid 12.543814 -104.93599)
					(end 12.53617 -104.97185)
				)
				(xy 12.53617 -106.00309) (xy 12.536424 -106.00309)
				(arc
					(start 12.536424 -106.041444)
					(mid 12.565614 -106.10495)
					(end 12.629642 -106.132884)
				)
			)
		)
	)
	(zone
		(layer "In1.Cu")
		(hatch none 0.5)
		(connect_pads
			(clearance 0)
		)
		(min_thickness 0.25)
		(keepout
			(tracks not_allowed)
			(vias allowed)
			(pads allowed)
			(copperpour not_allowed)
			(footprints allowed)
		)
		(placement
			(enabled no)
			(sheetname "")
		)
		(fill
			(thermal_gap 0.5)
			(thermal_bridge_width 0.5)
			(island_removal_mode 0)
		)
		(polygon
			(pts
				(arc
					(start 429.747934 -11.91768)
					(mid 429.770252 -11.971562)
					(end 429.824134 -11.99388)
				)
				(arc
					(start 431.105564 -11.99388)
					(mid 431.159446 -11.971562)
					(end 431.181764 -11.91768)
				)
				(arc
					(start 431.181764 -10.49528)
					(mid 431.159446 -10.441398)
					(end 431.105564 -10.41908)
				)
				(arc
					(start 429.824134 -10.41908)
					(mid 429.770252 -10.441398)
					(end 429.747934 -10.49528)
				)
			)
		)
	)
	(zone
		(layer "In1.Cu")
		(hatch none 0.5)
		(connect_pads
			(clearance 0)
		)
		(min_thickness 0.25)
		(keepout
			(tracks not_allowed)
			(vias allowed)
			(pads allowed)
			(copperpour not_allowed)
			(footprints allowed)
		)
		(placement
			(enabled no)
			(sheetname "")
		)
		(fill
			(thermal_gap 0.5)
			(thermal_bridge_width 0.5)
			(island_removal_mode 0)
		)
		(polygon
			(pts
				(arc
					(start 344.89009 -70.12686)
					(mid 344.867772 -70.072978)
					(end 344.81389 -70.05066)
				)
				(arc
					(start 344.48369 -70.05066)
					(mid 344.429808 -70.072978)
					(end 344.40749 -70.12686)
				)
				(arc
					(start 344.40749 -70.38086)
					(mid 344.429808 -70.434742)
					(end 344.48369 -70.45706)
				)
				(arc
					(start 344.81389 -70.45706)
					(mid 344.867772 -70.434742)
					(end 344.89009 -70.38086)
				)
			)
		)
	)
	(zone
		(layer "In1.Cu")
		(hatch none 0.5)
		(connect_pads
			(clearance 0)
		)
		(min_thickness 0.25)
		(keepout
			(tracks not_allowed)
			(vias allowed)
			(pads allowed)
			(copperpour not_allowed)
			(footprints allowed)
		)
		(placement
			(enabled no)
			(sheetname "")
		)
		(fill
			(thermal_gap 0.5)
			(thermal_bridge_width 0.5)
			(island_removal_mode 0)
		)
		(polygon
			(pts
				(arc
					(start 42.23893 -11.91768)
					(mid 42.261248 -11.971562)
					(end 42.31513 -11.99388)
				)
				(arc
					(start 43.59656 -11.99388)
					(mid 43.650442 -11.971562)
					(end 43.67276 -11.91768)
				)
				(arc
					(start 43.67276 -10.49528)
					(mid 43.650442 -10.441398)
					(end 43.59656 -10.41908)
				)
				(arc
					(start 42.31513 -10.41908)
					(mid 42.261248 -10.441398)
					(end 42.23893 -10.49528)
				)
			)
		)
	)
	(zone
		(layer "In1.Cu")
		(hatch none 0.5)
		(connect_pads
			(clearance 0)
		)
		(min_thickness 0.25)
		(keepout
			(tracks not_allowed)
			(vias allowed)
			(pads allowed)
			(copperpour not_allowed)
			(footprints allowed)
		)
		(placement
			(enabled no)
			(sheetname "")
		)
		(fill
			(thermal_gap 0.5)
			(thermal_bridge_width 0.5)
			(island_removal_mode 0)
		)
		(polygon
			(pts
				(arc
					(start 236.03458 -56.561228)
					(mid 235.980698 -56.53891)
					(end 235.95838 -56.485028)
				)
				(arc
					(start 235.95838 -55.656988)
					(mid 235.980698 -55.603106)
					(end 236.03458 -55.580788)
				)
				(arc
					(start 237.1598 -55.580788)
					(mid 237.213682 -55.603106)
					(end 237.236 -55.656988)
				)
				(arc
					(start 237.236 -56.485028)
					(mid 237.213682 -56.53891)
					(end 237.1598 -56.561228)
				)
			)
		)
	)
	(zone
		(layer "In1.Cu")
		(hatch none 0.5)
		(connect_pads
			(clearance 0)
		)
		(min_thickness 0.25)
		(keepout
			(tracks not_allowed)
			(vias allowed)
			(pads allowed)
			(copperpour not_allowed)
			(footprints allowed)
		)
		(placement
			(enabled no)
			(sheetname "")
		)
		(fill
			(thermal_gap 0.5)
			(thermal_bridge_width 0.5)
			(island_removal_mode 0)
		)
		(polygon
			(pts
				(arc
					(start 341.76589 -69.64426)
					(mid 341.743572 -69.590378)
					(end 341.68969 -69.56806)
				)
				(arc
					(start 341.35949 -69.56806)
					(mid 341.305608 -69.590378)
					(end 341.28329 -69.64426)
				)
				(arc
					(start 341.28329 -69.89826)
					(mid 341.305608 -69.952142)
					(end 341.35949 -69.97446)
				)
				(arc
					(start 341.68969 -69.97446)
					(mid 341.743572 -69.952142)
					(end 341.76589 -69.89826)
				)
			)
		)
	)
	(zone
		(layer "In1.Cu")
		(hatch none 0.5)
		(connect_pads
			(clearance 0)
		)
		(min_thickness 0.25)
		(keepout
			(tracks not_allowed)
			(vias allowed)
			(pads allowed)
			(copperpour not_allowed)
			(footprints allowed)
		)
		(placement
			(enabled no)
			(sheetname "")
		)
		(fill
			(thermal_gap 0.5)
			(thermal_bridge_width 0.5)
			(island_removal_mode 0)
		)
		(polygon
			(pts
				(arc
					(start 346.03309 -68.97624)
					(mid 346.010772 -68.922358)
					(end 345.95689 -68.90004)
				)
				(arc
					(start 345.62669 -68.90004)
					(mid 345.572808 -68.922358)
					(end 345.55049 -68.97624)
				)
				(arc
					(start 345.55049 -69.23024)
					(mid 345.572808 -69.284122)
					(end 345.62669 -69.30644)
				)
				(arc
					(start 345.95689 -69.30644)
					(mid 346.010772 -69.284122)
					(end 346.03309 -69.23024)
				)
			)
		)
	)
	(zone
		(layer "In1.Cu")
		(hatch none 0.5)
		(connect_pads
			(clearance 0)
		)
		(min_thickness 0.25)
		(keepout
			(tracks not_allowed)
			(vias allowed)
			(pads allowed)
			(copperpour not_allowed)
			(footprints allowed)
		)
		(placement
			(enabled no)
			(sheetname "")
		)
		(fill
			(thermal_gap 0.5)
			(thermal_bridge_width 0.5)
			(island_removal_mode 0)
		)
		(polygon
			(pts
				(arc
					(start 405.465788 -7.672324)
					(mid 405.44347 -7.618442)
					(end 405.389588 -7.596124)
				)
				(arc
					(start 404.108158 -7.596124)
					(mid 404.054276 -7.618442)
					(end 404.031958 -7.672324)
				)
				(arc
					(start 404.031958 -9.094724)
					(mid 404.054276 -9.148606)
					(end 404.108158 -9.170924)
				)
				(arc
					(start 405.389588 -9.170924)
					(mid 405.44347 -9.148606)
					(end 405.465788 -9.094724)
				)
			)
		)
	)
	(zone
		(layer "In1.Cu")
		(hatch none 0.5)
		(connect_pads
			(clearance 0)
		)
		(min_thickness 0.25)
		(keepout
			(tracks not_allowed)
			(vias allowed)
			(pads allowed)
			(copperpour not_allowed)
			(footprints allowed)
		)
		(placement
			(enabled no)
			(sheetname "")
		)
		(fill
			(thermal_gap 0.5)
			(thermal_bridge_width 0.5)
			(island_removal_mode 0)
		)
		(polygon
			(pts
				(arc
					(start 427.58614 -7.672324)
					(mid 427.563822 -7.618442)
					(end 427.50994 -7.596124)
				)
				(arc
					(start 426.22851 -7.596124)
					(mid 426.174628 -7.618442)
					(end 426.15231 -7.672324)
				)
				(arc
					(start 426.15231 -9.094724)
					(mid 426.174628 -9.148606)
					(end 426.22851 -9.170924)
				)
				(arc
					(start 427.50994 -9.170924)
					(mid 427.563822 -9.148606)
					(end 427.58614 -9.094724)
				)
			)
		)
	)
	(zone
		(layer "In1.Cu")
		(hatch none 0.5)
		(connect_pads
			(clearance 0)
		)
		(min_thickness 0.25)
		(keepout
			(tracks not_allowed)
			(vias allowed)
			(pads allowed)
			(copperpour not_allowed)
			(footprints allowed)
		)
		(placement
			(enabled no)
			(sheetname "")
		)
		(fill
			(thermal_gap 0.5)
			(thermal_bridge_width 0.5)
			(island_removal_mode 0)
		)
		(polygon
			(pts
				(arc
					(start 396.46606 -7.672324)
					(mid 396.443742 -7.618442)
					(end 396.38986 -7.596124)
				)
				(arc
					(start 395.10843 -7.596124)
					(mid 395.054548 -7.618442)
					(end 395.03223 -7.672324)
				)
				(arc
					(start 395.03223 -9.094724)
					(mid 395.054548 -9.148606)
					(end 395.10843 -9.170924)
				)
				(arc
					(start 396.38986 -9.170924)
					(mid 396.443742 -9.148606)
					(end 396.46606 -9.094724)
				)
			)
		)
	)
	(zone
		(layer "In1.Cu")
		(hatch none 0.5)
		(connect_pads
			(clearance 0)
		)
		(min_thickness 0.25)
		(keepout
			(tracks not_allowed)
			(vias allowed)
			(pads allowed)
			(copperpour not_allowed)
			(footprints allowed)
		)
		(placement
			(enabled no)
			(sheetname "")
		)
		(fill
			(thermal_gap 0.5)
			(thermal_bridge_width 0.5)
			(island_removal_mode 0)
		)
		(polygon
			(pts
				(xy 158.00578 -40.577008) (xy 158.00578 -39.837868) (xy 158.76524 -39.837868) (xy 158.76524 -40.577008)
			)
		)
	)
	(zone
		(layer "In1.Cu")
		(hatch none 0.5)
		(connect_pads
			(clearance 0)
		)
		(min_thickness 0.25)
		(keepout
			(tracks not_allowed)
			(vias allowed)
			(pads allowed)
			(copperpour not_allowed)
			(footprints allowed)
		)
		(placement
			(enabled no)
			(sheetname "")
		)
		(fill
			(thermal_gap 0.5)
			(thermal_bridge_width 0.5)
			(island_removal_mode 0)
		)
		(polygon
			(pts
				(arc
					(start 320.425318 -408.860244)
					(mid 320.447636 -408.914126)
					(end 320.501518 -408.936444)
				)
				(arc
					(start 320.697098 -408.936444)
					(mid 320.718974 -408.933312)
					(end 320.739008 -408.923998)
				)
				(arc
					(start 321.032632 -408.731466)
					(mid 321.074288 -408.719064)
					(end 321.115944 -408.731466)
				)
				(arc
					(start 321.410838 -408.923998)
					(mid 321.430762 -408.933234)
					(end 321.452494 -408.936444)
				)
				(arc
					(start 321.647058 -408.936444)
					(mid 321.70094 -408.914126)
					(end 321.723258 -408.860244)
				)
				(arc
					(start 321.723258 -408.174444)
					(mid 321.70094 -408.120562)
					(end 321.647058 -408.098244)
				)
				(arc
					(start 321.452494 -408.098244)
					(mid 321.43075 -408.101412)
					(end 321.410838 -408.11069)
				)
				(arc
					(start 321.114674 -408.303476)
					(mid 321.07299 -408.315698)
					(end 321.031362 -408.303222)
				)
				(arc
					(start 320.737738 -408.11069)
					(mid 320.717814 -408.101454)
					(end 320.696082 -408.098244)
				)
				(arc
					(start 320.501518 -408.098244)
					(mid 320.447636 -408.120562)
					(end 320.425318 -408.174444)
				)
			)
		)
	)
	(zone
		(layer "In1.Cu")
		(hatch none 0.5)
		(connect_pads
			(clearance 0)
		)
		(min_thickness 0.25)
		(keepout
			(tracks not_allowed)
			(vias allowed)
			(pads allowed)
			(copperpour not_allowed)
			(footprints allowed)
		)
		(placement
			(enabled no)
			(sheetname "")
		)
		(fill
			(thermal_gap 0.5)
			(thermal_bridge_width 0.5)
			(island_removal_mode 0)
		)
		(polygon
			(pts
				(arc
					(start 91.994228 -408.860244)
					(mid 92.016546 -408.914126)
					(end 92.070428 -408.936444)
				)
				(arc
					(start 92.266008 -408.936444)
					(mid 92.287884 -408.933312)
					(end 92.307918 -408.923998)
				)
				(arc
					(start 92.601542 -408.731466)
					(mid 92.643198 -408.719064)
					(end 92.684854 -408.731466)
				)
				(arc
					(start 92.979748 -408.923998)
					(mid 92.999672 -408.933234)
					(end 93.021404 -408.936444)
				)
				(arc
					(start 93.215968 -408.936444)
					(mid 93.26985 -408.914126)
					(end 93.292168 -408.860244)
				)
				(arc
					(start 93.292168 -408.174444)
					(mid 93.26985 -408.120562)
					(end 93.215968 -408.098244)
				)
				(arc
					(start 93.021404 -408.098244)
					(mid 92.99966 -408.101412)
					(end 92.979748 -408.11069)
				)
				(arc
					(start 92.683584 -408.303476)
					(mid 92.6419 -408.315698)
					(end 92.600272 -408.303222)
				)
				(arc
					(start 92.306648 -408.11069)
					(mid 92.286724 -408.101454)
					(end 92.264992 -408.098244)
				)
				(arc
					(start 92.070428 -408.098244)
					(mid 92.016546 -408.120562)
					(end 91.994228 -408.174444)
				)
			)
		)
	)
	(zone
		(layer "In1.Cu")
		(hatch none 0.5)
		(connect_pads
			(clearance 0)
		)
		(min_thickness 0.25)
		(keepout
			(tracks not_allowed)
			(vias allowed)
			(pads allowed)
			(copperpour not_allowed)
			(footprints allowed)
		)
		(placement
			(enabled no)
			(sheetname "")
		)
		(fill
			(thermal_gap 0.5)
			(thermal_bridge_width 0.5)
			(island_removal_mode 0)
		)
		(polygon
			(pts
				(arc
					(start 51.287172 -7.672324)
					(mid 51.264854 -7.618442)
					(end 51.210972 -7.596124)
				)
				(arc
					(start 49.929542 -7.596124)
					(mid 49.87566 -7.618442)
					(end 49.853342 -7.672324)
				)
				(arc
					(start 49.853342 -9.094724)
					(mid 49.87566 -9.148606)
					(end 49.929542 -9.170924)
				)
				(arc
					(start 51.210972 -9.170924)
					(mid 51.264854 -9.148606)
					(end 51.287172 -9.094724)
				)
			)
		)
	)
	(zone
		(layer "In1.Cu")
		(hatch none 0.5)
		(connect_pads
			(clearance 0)
		)
		(min_thickness 0.25)
		(keepout
			(tracks not_allowed)
			(vias allowed)
			(pads allowed)
			(copperpour not_allowed)
			(footprints allowed)
		)
		(placement
			(enabled no)
			(sheetname "")
		)
		(fill
			(thermal_gap 0.5)
			(thermal_bridge_width 0.5)
			(island_removal_mode 0)
		)
		(polygon
			(pts
				(arc
					(start 40.439086 -11.91768)
					(mid 40.461404 -11.971562)
					(end 40.515286 -11.99388)
				)
				(arc
					(start 41.796716 -11.99388)
					(mid 41.850598 -11.971562)
					(end 41.872916 -11.91768)
				)
				(arc
					(start 41.872916 -10.49528)
					(mid 41.850598 -10.441398)
					(end 41.796716 -10.41908)
				)
				(arc
					(start 40.515286 -10.41908)
					(mid 40.461404 -10.441398)
					(end 40.439086 -10.49528)
				)
			)
		)
	)
	(zone
		(layer "In1.Cu")
		(hatch none 0.5)
		(connect_pads
			(clearance 0)
		)
		(min_thickness 0.25)
		(keepout
			(tracks not_allowed)
			(vias allowed)
			(pads allowed)
			(copperpour not_allowed)
			(footprints allowed)
		)
		(placement
			(enabled no)
			(sheetname "")
		)
		(fill
			(thermal_gap 0.5)
			(thermal_bridge_width 0.5)
			(island_removal_mode 0)
		)
		(polygon
			(pts
				(arc
					(start 308.172358 -408.860244)
					(mid 308.194676 -408.914126)
					(end 308.248558 -408.936444)
				)
				(arc
					(start 308.444138 -408.936444)
					(mid 308.466014 -408.933312)
					(end 308.486048 -408.923998)
				)
				(arc
					(start 308.779672 -408.731466)
					(mid 308.821328 -408.719064)
					(end 308.862984 -408.731466)
				)
				(arc
					(start 309.157878 -408.923998)
					(mid 309.177802 -408.933234)
					(end 309.199534 -408.936444)
				)
				(arc
					(start 309.394098 -408.936444)
					(mid 309.44798 -408.914126)
					(end 309.470298 -408.860244)
				)
				(arc
					(start 309.470298 -408.174444)
					(mid 309.44798 -408.120562)
					(end 309.394098 -408.098244)
				)
				(arc
					(start 309.199534 -408.098244)
					(mid 309.17779 -408.101412)
					(end 309.157878 -408.11069)
				)
				(arc
					(start 308.861714 -408.303476)
					(mid 308.82003 -408.315698)
					(end 308.778402 -408.303222)
				)
				(arc
					(start 308.484778 -408.11069)
					(mid 308.464854 -408.101454)
					(end 308.443122 -408.098244)
				)
				(arc
					(start 308.248558 -408.098244)
					(mid 308.194676 -408.120562)
					(end 308.172358 -408.174444)
				)
			)
		)
	)
	(zone
		(layer "In1.Cu")
		(hatch none 0.5)
		(connect_pads
			(clearance 0)
		)
		(min_thickness 0.25)
		(keepout
			(tracks not_allowed)
			(vias allowed)
			(pads allowed)
			(copperpour not_allowed)
			(footprints allowed)
		)
		(placement
			(enabled no)
			(sheetname "")
		)
		(fill
			(thermal_gap 0.5)
			(thermal_bridge_width 0.5)
			(island_removal_mode 0)
		)
		(polygon
			(pts
				(arc
					(start 418.175948 -7.672324)
					(mid 418.15363 -7.618442)
					(end 418.099748 -7.596124)
				)
				(arc
					(start 416.818318 -7.596124)
					(mid 416.764436 -7.618442)
					(end 416.742118 -7.672324)
				)
				(arc
					(start 416.742118 -9.094724)
					(mid 416.764436 -9.148606)
					(end 416.818318 -9.170924)
				)
				(arc
					(start 418.099748 -9.170924)
					(mid 418.15363 -9.148606)
					(end 418.175948 -9.094724)
				)
			)
		)
	)
	(zone
		(layer "In1.Cu")
		(hatch none 0.5)
		(connect_pads
			(clearance 0)
		)
		(min_thickness 0.25)
		(keepout
			(tracks not_allowed)
			(vias allowed)
			(pads allowed)
			(copperpour not_allowed)
			(footprints allowed)
		)
		(placement
			(enabled no)
			(sheetname "")
		)
		(fill
			(thermal_gap 0.5)
			(thermal_bridge_width 0.5)
			(island_removal_mode 0)
		)
		(polygon
			(pts
				(arc
					(start 417.15436 -402.713952)
					(mid 417.176678 -402.767834)
					(end 417.23056 -402.790152)
				)
				(arc
					(start 417.42614 -402.790152)
					(mid 417.448016 -402.78702)
					(end 417.46805 -402.777706)
				)
				(arc
					(start 417.761674 -402.585174)
					(mid 417.80333 -402.572772)
					(end 417.844986 -402.585174)
				)
				(arc
					(start 418.13988 -402.777706)
					(mid 418.159804 -402.786942)
					(end 418.181536 -402.790152)
				)
				(arc
					(start 418.3761 -402.790152)
					(mid 418.429982 -402.767834)
					(end 418.4523 -402.713952)
				)
				(arc
					(start 418.4523 -402.028152)
					(mid 418.429982 -401.97427)
					(end 418.3761 -401.951952)
				)
				(arc
					(start 418.181536 -401.951952)
					(mid 418.159792 -401.95512)
					(end 418.13988 -401.964398)
				)
				(arc
					(start 417.843716 -402.157184)
					(mid 417.802032 -402.169406)
					(end 417.760404 -402.15693)
				)
				(arc
					(start 417.46678 -401.964398)
					(mid 417.446856 -401.955162)
					(end 417.425124 -401.951952)
				)
				(arc
					(start 417.23056 -401.951952)
					(mid 417.176678 -401.97427)
					(end 417.15436 -402.028152)
				)
			)
		)
	)
	(zone
		(layer "In1.Cu")
		(hatch none 0.5)
		(connect_pads
			(clearance 0)
		)
		(min_thickness 0.25)
		(keepout
			(tracks not_allowed)
			(vias allowed)
			(pads allowed)
			(copperpour not_allowed)
			(footprints allowed)
		)
		(placement
			(enabled no)
			(sheetname "")
		)
		(fill
			(thermal_gap 0.5)
			(thermal_bridge_width 0.5)
			(island_removal_mode 0)
		)
		(polygon
			(pts
				(arc
					(start 396.827756 -11.91768)
					(mid 396.850074 -11.971562)
					(end 396.903956 -11.99388)
				)
				(arc
					(start 398.185386 -11.99388)
					(mid 398.239268 -11.971562)
					(end 398.261586 -11.91768)
				)
				(arc
					(start 398.261586 -10.49528)
					(mid 398.239268 -10.441398)
					(end 398.185386 -10.41908)
				)
				(arc
					(start 396.903956 -10.41908)
					(mid 396.850074 -10.441398)
					(end 396.827756 -10.49528)
				)
			)
		)
	)
	(zone
		(layer "In1.Cu")
		(hatch none 0.5)
		(connect_pads
			(clearance 0)
		)
		(min_thickness 0.25)
		(keepout
			(tracks not_allowed)
			(vias allowed)
			(pads allowed)
			(copperpour not_allowed)
			(footprints allowed)
		)
		(placement
			(enabled no)
			(sheetname "")
		)
		(fill
			(thermal_gap 0.5)
			(thermal_bridge_width 0.5)
			(island_removal_mode 0)
		)
		(polygon
			(pts
				(arc
					(start 141.380464 -402.713952)
					(mid 141.402782 -402.767834)
					(end 141.456664 -402.790152)
				)
				(arc
					(start 141.652244 -402.790152)
					(mid 141.67412 -402.78702)
					(end 141.694154 -402.777706)
				)
				(arc
					(start 141.987778 -402.585174)
					(mid 142.029434 -402.572772)
					(end 142.07109 -402.585174)
				)
				(arc
					(start 142.365984 -402.777706)
					(mid 142.385908 -402.786942)
					(end 142.40764 -402.790152)
				)
				(arc
					(start 142.602204 -402.790152)
					(mid 142.656086 -402.767834)
					(end 142.678404 -402.713952)
				)
				(arc
					(start 142.678404 -402.028152)
					(mid 142.656086 -401.97427)
					(end 142.602204 -401.951952)
				)
				(arc
					(start 142.40764 -401.951952)
					(mid 142.385896 -401.95512)
					(end 142.365984 -401.964398)
				)
				(arc
					(start 142.06982 -402.157184)
					(mid 142.028136 -402.169406)
					(end 141.986508 -402.15693)
				)
				(arc
					(start 141.692884 -401.964398)
					(mid 141.67296 -401.955162)
					(end 141.651228 -401.951952)
				)
				(arc
					(start 141.456664 -401.951952)
					(mid 141.402782 -401.97427)
					(end 141.380464 -402.028152)
				)
			)
		)
	)
	(zone
		(layer "In1.Cu")
		(hatch none 0.5)
		(connect_pads
			(clearance 0)
		)
		(min_thickness 0.25)
		(keepout
			(tracks not_allowed)
			(vias allowed)
			(pads allowed)
			(copperpour not_allowed)
			(footprints allowed)
		)
		(placement
			(enabled no)
			(sheetname "")
		)
		(fill
			(thermal_gap 0.5)
			(thermal_bridge_width 0.5)
			(island_removal_mode 0)
		)
		(polygon
			(pts
				(arc
					(start 167.885872 -12.952222)
					(mid 167.863554 -12.89834)
					(end 167.809672 -12.876022)
				)
				(arc
					(start 166.528242 -12.876022)
					(mid 166.47436 -12.89834)
					(end 166.452042 -12.952222)
				)
				(arc
					(start 166.452042 -14.374622)
					(mid 166.47436 -14.428504)
					(end 166.528242 -14.450822)
				)
				(arc
					(start 167.809672 -14.450822)
					(mid 167.863554 -14.428504)
					(end 167.885872 -14.374622)
				)
			)
		)
	)
	(zone
		(layer "In1.Cu")
		(hatch none 0.5)
		(connect_pads
			(clearance 0)
		)
		(min_thickness 0.25)
		(keepout
			(tracks not_allowed)
			(vias allowed)
			(pads allowed)
			(copperpour not_allowed)
			(footprints allowed)
		)
		(placement
			(enabled no)
			(sheetname "")
		)
		(fill
			(thermal_gap 0.5)
			(thermal_bridge_width 0.5)
			(island_removal_mode 0)
		)
		(polygon
			(pts
				(arc
					(start 395.412214 -16.431514)
					(mid 395.434532 -16.485396)
					(end 395.488414 -16.507714)
				)
				(arc
					(start 395.683994 -16.507714)
					(mid 395.70587 -16.504582)
					(end 395.725904 -16.495268)
				)
				(arc
					(start 396.019528 -16.302736)
					(mid 396.061184 -16.290334)
					(end 396.10284 -16.302736)
				)
				(arc
					(start 396.397734 -16.495268)
					(mid 396.417658 -16.504504)
					(end 396.43939 -16.507714)
				)
				(arc
					(start 396.633954 -16.507714)
					(mid 396.687836 -16.485396)
					(end 396.710154 -16.431514)
				)
				(arc
					(start 396.710154 -15.745714)
					(mid 396.687836 -15.691832)
					(end 396.633954 -15.669514)
				)
				(arc
					(start 396.43939 -15.669514)
					(mid 396.417646 -15.672682)
					(end 396.397734 -15.68196)
				)
				(arc
					(start 396.10157 -15.874746)
					(mid 396.059886 -15.886968)
					(end 396.018258 -15.874492)
				)
				(arc
					(start 395.724634 -15.68196)
					(mid 395.70471 -15.672724)
					(end 395.682978 -15.669514)
				)
				(arc
					(start 395.488414 -15.669514)
					(mid 395.434532 -15.691832)
					(end 395.412214 -15.745714)
				)
			)
		)
	)
	(zone
		(layer "In1.Cu")
		(hatch none 0.5)
		(connect_pads
			(clearance 0)
		)
		(min_thickness 0.25)
		(keepout
			(tracks not_allowed)
			(vias allowed)
			(pads allowed)
			(copperpour not_allowed)
			(footprints allowed)
		)
		(placement
			(enabled no)
			(sheetname "")
		)
		(fill
			(thermal_gap 0.5)
			(thermal_bridge_width 0.5)
			(island_removal_mode 0)
		)
		(polygon
			(pts
				(arc
					(start 46.356524 -17.966436)
					(mid 46.378842 -18.020318)
					(end 46.432724 -18.042636)
				)
				(arc
					(start 46.628304 -18.042636)
					(mid 46.65018 -18.039504)
					(end 46.670214 -18.03019)
				)
				(arc
					(start 46.963838 -17.837658)
					(mid 47.005494 -17.825256)
					(end 47.04715 -17.837658)
				)
				(arc
					(start 47.342044 -18.03019)
					(mid 47.361968 -18.039426)
					(end 47.3837 -18.042636)
				)
				(arc
					(start 47.578264 -18.042636)
					(mid 47.632146 -18.020318)
					(end 47.654464 -17.966436)
				)
				(arc
					(start 47.654464 -17.280636)
					(mid 47.632146 -17.226754)
					(end 47.578264 -17.204436)
				)
				(arc
					(start 47.3837 -17.204436)
					(mid 47.361956 -17.207604)
					(end 47.342044 -17.216882)
				)
				(arc
					(start 47.04588 -17.409668)
					(mid 47.004196 -17.42189)
					(end 46.962568 -17.409414)
				)
				(arc
					(start 46.668944 -17.216882)
					(mid 46.64902 -17.207646)
					(end 46.627288 -17.204436)
				)
				(arc
					(start 46.432724 -17.204436)
					(mid 46.378842 -17.226754)
					(end 46.356524 -17.280636)
				)
			)
		)
	)
	(zone
		(layer "In1.Cu")
		(hatch none 0.5)
		(connect_pads
			(clearance 0)
		)
		(min_thickness 0.25)
		(keepout
			(tracks not_allowed)
			(vias allowed)
			(pads allowed)
			(copperpour not_allowed)
			(footprints allowed)
		)
		(placement
			(enabled no)
			(sheetname "")
		)
		(fill
			(thermal_gap 0.5)
			(thermal_bridge_width 0.5)
			(island_removal_mode 0)
		)
		(polygon
			(pts
				(arc
					(start 24.534114 -396.258288)
					(mid 24.495073 -396.266045)
					(end 24.462232 -396.288514)
				)
				(arc
					(start 24.462232 -396.288514)
					(mid 24.44219 -396.319202)
					(end 24.434546 -396.355062)
				)
				(xy 24.434546 -396.497302) (xy 24.4348 -396.497302)
				(arc
					(start 24.4348 -397.424656)
					(mid 24.46399 -397.488162)
					(end 24.528018 -397.516096)
				)
				(arc
					(start 24.83485 -397.516096)
					(mid 24.873891 -397.508339)
					(end 24.906732 -397.48587)
				)
				(arc
					(start 24.906732 -397.48587)
					(mid 24.926774 -397.455182)
					(end 24.934418 -397.419322)
				)
				(xy 24.934418 -396.388082) (xy 24.934164 -396.388082)
				(arc
					(start 24.934164 -396.349728)
					(mid 24.904974 -396.286222)
					(end 24.840946 -396.258288)
				)
			)
		)
	)
	(zone
		(layer "In1.Cu")
		(hatch none 0.5)
		(connect_pads
			(clearance 0)
		)
		(min_thickness 0.25)
		(keepout
			(tracks not_allowed)
			(vias allowed)
			(pads allowed)
			(copperpour not_allowed)
			(footprints allowed)
		)
		(placement
			(enabled no)
			(sheetname "")
		)
		(fill
			(thermal_gap 0.5)
			(thermal_bridge_width 0.5)
			(island_removal_mode 0)
		)
		(polygon
			(pts
				(arc
					(start 138.317224 -402.713952)
					(mid 138.339542 -402.767834)
					(end 138.393424 -402.790152)
				)
				(arc
					(start 138.589004 -402.790152)
					(mid 138.61088 -402.78702)
					(end 138.630914 -402.777706)
				)
				(arc
					(start 138.924538 -402.585174)
					(mid 138.966194 -402.572772)
					(end 139.00785 -402.585174)
				)
				(arc
					(start 139.302744 -402.777706)
					(mid 139.322668 -402.786942)
					(end 139.3444 -402.790152)
				)
				(arc
					(start 139.538964 -402.790152)
					(mid 139.592846 -402.767834)
					(end 139.615164 -402.713952)
				)
				(arc
					(start 139.615164 -402.028152)
					(mid 139.592846 -401.97427)
					(end 139.538964 -401.951952)
				)
				(arc
					(start 139.3444 -401.951952)
					(mid 139.322656 -401.95512)
					(end 139.302744 -401.964398)
				)
				(arc
					(start 139.00658 -402.157184)
					(mid 138.964896 -402.169406)
					(end 138.923268 -402.15693)
				)
				(arc
					(start 138.629644 -401.964398)
					(mid 138.60972 -401.955162)
					(end 138.587988 -401.951952)
				)
				(arc
					(start 138.393424 -401.951952)
					(mid 138.339542 -401.97427)
					(end 138.317224 -402.028152)
				)
			)
		)
	)
	(zone
		(layer "In1.Cu")
		(hatch none 0.5)
		(connect_pads
			(clearance 0)
		)
		(min_thickness 0.25)
		(keepout
			(tracks not_allowed)
			(vias allowed)
			(pads allowed)
			(copperpour not_allowed)
			(footprints allowed)
		)
		(placement
			(enabled no)
			(sheetname "")
		)
		(fill
			(thermal_gap 0.5)
			(thermal_bridge_width 0.5)
			(island_removal_mode 0)
		)
		(polygon
			(pts
				(arc
					(start 156.25064 -42.91711)
					(mid 155.48864 -42.91711)
					(end 156.25064 -42.91711)
				)
			)
		)
	)
	(zone
		(layer "In1.Cu")
		(hatch none 0.5)
		(connect_pads
			(clearance 0)
		)
		(min_thickness 0.25)
		(keepout
			(tracks not_allowed)
			(vias allowed)
			(pads allowed)
			(copperpour not_allowed)
			(footprints allowed)
		)
		(placement
			(enabled no)
			(sheetname "")
		)
		(fill
			(thermal_gap 0.5)
			(thermal_bridge_width 0.5)
			(island_removal_mode 0)
		)
		(polygon
			(pts
				(arc
					(start 309.889398 -402.713952)
					(mid 309.911716 -402.767834)
					(end 309.965598 -402.790152)
				)
				(arc
					(start 310.161178 -402.790152)
					(mid 310.183054 -402.78702)
					(end 310.203088 -402.777706)
				)
				(arc
					(start 310.496712 -402.585174)
					(mid 310.538368 -402.572772)
					(end 310.580024 -402.585174)
				)
				(arc
					(start 310.874918 -402.777706)
					(mid 310.894842 -402.786942)
					(end 310.916574 -402.790152)
				)
				(arc
					(start 311.111138 -402.790152)
					(mid 311.16502 -402.767834)
					(end 311.187338 -402.713952)
				)
				(arc
					(start 311.187338 -402.028152)
					(mid 311.16502 -401.97427)
					(end 311.111138 -401.951952)
				)
				(arc
					(start 310.916574 -401.951952)
					(mid 310.89483 -401.95512)
					(end 310.874918 -401.964398)
				)
				(arc
					(start 310.578754 -402.157184)
					(mid 310.53707 -402.169406)
					(end 310.495442 -402.15693)
				)
				(arc
					(start 310.201818 -401.964398)
					(mid 310.181894 -401.955162)
					(end 310.160162 -401.951952)
				)
				(arc
					(start 309.965598 -401.951952)
					(mid 309.911716 -401.97427)
					(end 309.889398 -402.028152)
				)
			)
		)
	)
	(zone
		(layer "In1.Cu")
		(hatch none 0.5)
		(connect_pads
			(clearance 0)
		)
		(min_thickness 0.25)
		(keepout
			(tracks not_allowed)
			(vias allowed)
			(pads allowed)
			(copperpour not_allowed)
			(footprints allowed)
		)
		(placement
			(enabled no)
			(sheetname "")
		)
		(fill
			(thermal_gap 0.5)
			(thermal_bridge_width 0.5)
			(island_removal_mode 0)
		)
		(polygon
			(pts
				(arc
					(start 27.728926 -11.91768)
					(mid 27.751244 -11.971562)
					(end 27.805126 -11.99388)
				)
				(arc
					(start 29.086556 -11.99388)
					(mid 29.140438 -11.971562)
					(end 29.162756 -11.91768)
				)
				(arc
					(start 29.162756 -10.49528)
					(mid 29.140438 -10.441398)
					(end 29.086556 -10.41908)
				)
				(arc
					(start 27.805126 -10.41908)
					(mid 27.751244 -10.441398)
					(end 27.728926 -10.49528)
				)
			)
		)
	)
	(zone
		(layer "In1.Cu")
		(hatch none 0.5)
		(connect_pads
			(clearance 0)
		)
		(min_thickness 0.25)
		(keepout
			(tracks not_allowed)
			(vias allowed)
			(pads allowed)
			(copperpour not_allowed)
			(footprints allowed)
		)
		(placement
			(enabled no)
			(sheetname "")
		)
		(fill
			(thermal_gap 0.5)
			(thermal_bridge_width 0.5)
			(island_removal_mode 0)
		)
		(polygon
			(pts
				(arc
					(start 401.000214 -16.431514)
					(mid 401.022532 -16.485396)
					(end 401.076414 -16.507714)
				)
				(arc
					(start 401.271994 -16.507714)
					(mid 401.29387 -16.504582)
					(end 401.313904 -16.495268)
				)
				(arc
					(start 401.607528 -16.302736)
					(mid 401.649184 -16.290334)
					(end 401.69084 -16.302736)
				)
				(arc
					(start 401.985734 -16.495268)
					(mid 402.005658 -16.504504)
					(end 402.02739 -16.507714)
				)
				(arc
					(start 402.221954 -16.507714)
					(mid 402.275836 -16.485396)
					(end 402.298154 -16.431514)
				)
				(arc
					(start 402.298154 -15.745714)
					(mid 402.275836 -15.691832)
					(end 402.221954 -15.669514)
				)
				(arc
					(start 402.02739 -15.669514)
					(mid 402.005646 -15.672682)
					(end 401.985734 -15.68196)
				)
				(arc
					(start 401.68957 -15.874746)
					(mid 401.647886 -15.886968)
					(end 401.606258 -15.874492)
				)
				(arc
					(start 401.312634 -15.68196)
					(mid 401.29271 -15.672724)
					(end 401.270978 -15.669514)
				)
				(arc
					(start 401.076414 -15.669514)
					(mid 401.022532 -15.691832)
					(end 401.000214 -15.745714)
				)
			)
		)
	)
	(zone
		(layer "In1.Cu")
		(hatch none 0.5)
		(connect_pads
			(clearance 0)
		)
		(min_thickness 0.25)
		(keepout
			(tracks not_allowed)
			(vias allowed)
			(pads allowed)
			(copperpour not_allowed)
			(footprints allowed)
		)
		(placement
			(enabled no)
			(sheetname "")
		)
		(fill
			(thermal_gap 0.5)
			(thermal_bridge_width 0.5)
			(island_removal_mode 0)
		)
		(polygon
			(pts
				(arc
					(start 348.620334 -67.97548)
					(mid 348.566452 -67.997798)
					(end 348.544134 -68.05168)
				)
				(arc
					(start 348.544134 -68.38188)
					(mid 348.566452 -68.435762)
					(end 348.620334 -68.45808)
				)
				(arc
					(start 348.874334 -68.45808)
					(mid 348.928216 -68.435762)
					(end 348.950534 -68.38188)
				)
				(arc
					(start 348.950534 -68.05168)
					(mid 348.928216 -67.997798)
					(end 348.874334 -67.97548)
				)
			)
		)
	)
	(zone
		(layer "In1.Cu")
		(hatch none 0.5)
		(connect_pads
			(clearance 0)
		)
		(min_thickness 0.25)
		(keepout
			(tracks not_allowed)
			(vias allowed)
			(pads allowed)
			(copperpour not_allowed)
			(footprints allowed)
		)
		(placement
			(enabled no)
			(sheetname "")
		)
		(fill
			(thermal_gap 0.5)
			(thermal_bridge_width 0.5)
			(island_removal_mode 0)
		)
		(polygon
			(pts
				(arc
					(start 53.448966 -11.91768)
					(mid 53.471284 -11.971562)
					(end 53.525166 -11.99388)
				)
				(arc
					(start 54.806596 -11.99388)
					(mid 54.860478 -11.971562)
					(end 54.882796 -11.91768)
				)
				(arc
					(start 54.882796 -10.49528)
					(mid 54.860478 -10.441398)
					(end 54.806596 -10.41908)
				)
				(arc
					(start 53.525166 -10.41908)
					(mid 53.471284 -10.441398)
					(end 53.448966 -10.49528)
				)
			)
		)
	)
	(zone
		(layer "In1.Cu")
		(hatch none 0.5)
		(connect_pads
			(clearance 0)
		)
		(min_thickness 0.25)
		(keepout
			(tracks not_allowed)
			(vias allowed)
			(pads allowed)
			(copperpour not_allowed)
			(footprints allowed)
		)
		(placement
			(enabled no)
			(sheetname "")
		)
		(fill
			(thermal_gap 0.5)
			(thermal_bridge_width 0.5)
			(island_removal_mode 0)
		)
		(polygon
			(pts
				(arc
					(start 70.551548 -408.860244)
					(mid 70.573866 -408.914126)
					(end 70.627748 -408.936444)
				)
				(arc
					(start 70.823328 -408.936444)
					(mid 70.845204 -408.933312)
					(end 70.865238 -408.923998)
				)
				(arc
					(start 71.158862 -408.731466)
					(mid 71.200518 -408.719064)
					(end 71.242174 -408.731466)
				)
				(arc
					(start 71.537068 -408.923998)
					(mid 71.556992 -408.933234)
					(end 71.578724 -408.936444)
				)
				(arc
					(start 71.773288 -408.936444)
					(mid 71.82717 -408.914126)
					(end 71.849488 -408.860244)
				)
				(arc
					(start 71.849488 -408.174444)
					(mid 71.82717 -408.120562)
					(end 71.773288 -408.098244)
				)
				(arc
					(start 71.578724 -408.098244)
					(mid 71.55698 -408.101412)
					(end 71.537068 -408.11069)
				)
				(arc
					(start 71.240904 -408.303476)
					(mid 71.19922 -408.315698)
					(end 71.157592 -408.303222)
				)
				(arc
					(start 70.863968 -408.11069)
					(mid 70.844044 -408.101454)
					(end 70.822312 -408.098244)
				)
				(arc
					(start 70.627748 -408.098244)
					(mid 70.573866 -408.120562)
					(end 70.551548 -408.174444)
				)
			)
		)
	)
	(zone
		(layer "In1.Cu")
		(hatch none 0.5)
		(connect_pads
			(clearance 0)
		)
		(min_thickness 0.25)
		(keepout
			(tracks not_allowed)
			(vias allowed)
			(pads allowed)
			(copperpour not_allowed)
			(footprints allowed)
		)
		(placement
			(enabled no)
			(sheetname "")
		)
		(fill
			(thermal_gap 0.5)
			(thermal_bridge_width 0.5)
			(island_removal_mode 0)
		)
		(polygon
			(pts
				(arc
					(start 32.080708 -16.442436)
					(mid 32.103026 -16.496318)
					(end 32.156908 -16.518636)
				)
				(arc
					(start 32.352488 -16.518636)
					(mid 32.374364 -16.515504)
					(end 32.394398 -16.50619)
				)
				(arc
					(start 32.688022 -16.313658)
					(mid 32.729678 -16.301256)
					(end 32.771334 -16.313658)
				)
				(arc
					(start 33.066228 -16.50619)
					(mid 33.086152 -16.515426)
					(end 33.107884 -16.518636)
				)
				(arc
					(start 33.302448 -16.518636)
					(mid 33.35633 -16.496318)
					(end 33.378648 -16.442436)
				)
				(arc
					(start 33.378648 -15.756636)
					(mid 33.35633 -15.702754)
					(end 33.302448 -15.680436)
				)
				(arc
					(start 33.107884 -15.680436)
					(mid 33.08614 -15.683604)
					(end 33.066228 -15.692882)
				)
				(arc
					(start 32.770064 -15.885668)
					(mid 32.72838 -15.89789)
					(end 32.686752 -15.885414)
				)
				(arc
					(start 32.393128 -15.692882)
					(mid 32.373204 -15.683646)
					(end 32.351472 -15.680436)
				)
				(arc
					(start 32.156908 -15.680436)
					(mid 32.103026 -15.702754)
					(end 32.080708 -15.756636)
				)
			)
		)
	)
	(zone
		(layer "In1.Cu")
		(hatch none 0.5)
		(connect_pads
			(clearance 0)
		)
		(min_thickness 0.25)
		(keepout
			(tracks not_allowed)
			(vias allowed)
			(pads allowed)
			(copperpour not_allowed)
			(footprints allowed)
		)
		(placement
			(enabled no)
			(sheetname "")
		)
		(fill
			(thermal_gap 0.5)
			(thermal_bridge_width 0.5)
			(island_removal_mode 0)
		)
		(polygon
			(pts
				(arc
					(start 231.43464 -54.761384)
					(mid 231.380758 -54.739066)
					(end 231.35844 -54.685184)
				)
				(arc
					(start 231.35844 -53.857144)
					(mid 231.380758 -53.803262)
					(end 231.43464 -53.780944)
				)
				(arc
					(start 232.55986 -53.780944)
					(mid 232.613742 -53.803262)
					(end 232.63606 -53.857144)
				)
				(arc
					(start 232.63606 -54.685184)
					(mid 232.613742 -54.739066)
					(end 232.55986 -54.761384)
				)
			)
		)
	)
	(zone
		(layer "In1.Cu")
		(hatch none 0.5)
		(connect_pads
			(clearance 0)
		)
		(min_thickness 0.25)
		(keepout
			(tracks not_allowed)
			(vias allowed)
			(pads allowed)
			(copperpour not_allowed)
			(footprints allowed)
		)
		(placement
			(enabled no)
			(sheetname "")
		)
		(fill
			(thermal_gap 0.5)
			(thermal_bridge_width 0.5)
			(island_removal_mode 0)
		)
		(polygon
			(pts
				(arc
					(start 121.283984 -408.860244)
					(mid 121.306302 -408.914126)
					(end 121.360184 -408.936444)
				)
				(arc
					(start 121.555764 -408.936444)
					(mid 121.57764 -408.933312)
					(end 121.597674 -408.923998)
				)
				(arc
					(start 121.891298 -408.731466)
					(mid 121.932954 -408.719064)
					(end 121.97461 -408.731466)
				)
				(arc
					(start 122.269504 -408.923998)
					(mid 122.289428 -408.933234)
					(end 122.31116 -408.936444)
				)
				(arc
					(start 122.505724 -408.936444)
					(mid 122.559606 -408.914126)
					(end 122.581924 -408.860244)
				)
				(arc
					(start 122.581924 -408.174444)
					(mid 122.559606 -408.120562)
					(end 122.505724 -408.098244)
				)
				(arc
					(start 122.31116 -408.098244)
					(mid 122.289416 -408.101412)
					(end 122.269504 -408.11069)
				)
				(arc
					(start 121.97334 -408.303476)
					(mid 121.931656 -408.315698)
					(end 121.890028 -408.303222)
				)
				(arc
					(start 121.596404 -408.11069)
					(mid 121.57648 -408.101454)
					(end 121.554748 -408.098244)
				)
				(arc
					(start 121.360184 -408.098244)
					(mid 121.306302 -408.120562)
					(end 121.283984 -408.174444)
				)
			)
		)
	)
	(zone
		(layer "In1.Cu")
		(hatch none 0.5)
		(connect_pads
			(clearance 0)
		)
		(min_thickness 0.25)
		(keepout
			(tracks not_allowed)
			(vias allowed)
			(pads allowed)
			(copperpour not_allowed)
			(footprints allowed)
		)
		(placement
			(enabled no)
			(sheetname "")
		)
		(fill
			(thermal_gap 0.5)
			(thermal_bridge_width 0.5)
			(island_removal_mode 0)
		)
		(polygon
			(pts
				(arc
					(start 51.97856 -17.966436)
					(mid 52.000878 -18.020318)
					(end 52.05476 -18.042636)
				)
				(arc
					(start 52.25034 -18.042636)
					(mid 52.272216 -18.039504)
					(end 52.29225 -18.03019)
				)
				(arc
					(start 52.585874 -17.837658)
					(mid 52.62753 -17.825256)
					(end 52.669186 -17.837658)
				)
				(arc
					(start 52.96408 -18.03019)
					(mid 52.984004 -18.039426)
					(end 53.005736 -18.042636)
				)
				(arc
					(start 53.2003 -18.042636)
					(mid 53.254182 -18.020318)
					(end 53.2765 -17.966436)
				)
				(arc
					(start 53.2765 -17.280636)
					(mid 53.254182 -17.226754)
					(end 53.2003 -17.204436)
				)
				(arc
					(start 53.005736 -17.204436)
					(mid 52.983992 -17.207604)
					(end 52.96408 -17.216882)
				)
				(arc
					(start 52.667916 -17.409668)
					(mid 52.626232 -17.42189)
					(end 52.584604 -17.409414)
				)
				(arc
					(start 52.29098 -17.216882)
					(mid 52.271056 -17.207646)
					(end 52.249324 -17.204436)
				)
				(arc
					(start 52.05476 -17.204436)
					(mid 52.000878 -17.226754)
					(end 51.97856 -17.280636)
				)
			)
		)
	)
	(zone
		(layer "In1.Cu")
		(hatch none 0.5)
		(connect_pads
			(clearance 0)
		)
		(min_thickness 0.25)
		(keepout
			(tracks not_allowed)
			(vias allowed)
			(pads allowed)
			(copperpour not_allowed)
			(footprints allowed)
		)
		(placement
			(enabled no)
			(sheetname "")
		)
		(fill
			(thermal_gap 0.5)
			(thermal_bridge_width 0.5)
			(island_removal_mode 0)
		)
		(polygon
			(pts
				(arc
					(start 23.917402 -386.407152)
					(mid 23.956443 -386.399395)
					(end 23.989284 -386.376926)
				)
				(arc
					(start 23.989284 -386.376926)
					(mid 24.009326 -386.346238)
					(end 24.01697 -386.310378)
				)
				(xy 24.01697 -386.168138) (xy 24.016716 -386.168138)
				(arc
					(start 24.016716 -385.240784)
					(mid 23.987526 -385.177278)
					(end 23.923498 -385.149344)
				)
				(arc
					(start 23.616666 -385.149344)
					(mid 23.577625 -385.157101)
					(end 23.544784 -385.17957)
				)
				(arc
					(start 23.544784 -385.17957)
					(mid 23.524742 -385.210258)
					(end 23.517098 -385.246118)
				)
				(xy 23.517098 -386.277358) (xy 23.517352 -386.277358)
				(arc
					(start 23.517352 -386.315712)
					(mid 23.546542 -386.379218)
					(end 23.61057 -386.407152)
				)
			)
		)
	)
	(zone
		(layer "In1.Cu")
		(hatch none 0.5)
		(connect_pads
			(clearance 0)
		)
		(min_thickness 0.25)
		(keepout
			(tracks not_allowed)
			(vias allowed)
			(pads allowed)
			(copperpour not_allowed)
			(footprints allowed)
		)
		(placement
			(enabled no)
			(sheetname "")
		)
		(fill
			(thermal_gap 0.5)
			(thermal_bridge_width 0.5)
			(island_removal_mode 0)
		)
		(polygon
			(pts
				(arc
					(start 418.07003 -16.431514)
					(mid 418.092348 -16.485396)
					(end 418.14623 -16.507714)
				)
				(arc
					(start 418.34181 -16.507714)
					(mid 418.363686 -16.504582)
					(end 418.38372 -16.495268)
				)
				(arc
					(start 418.677344 -16.302736)
					(mid 418.719 -16.290334)
					(end 418.760656 -16.302736)
				)
				(arc
					(start 419.05555 -16.495268)
					(mid 419.075474 -16.504504)
					(end 419.097206 -16.507714)
				)
				(arc
					(start 419.29177 -16.507714)
					(mid 419.345652 -16.485396)
					(end 419.36797 -16.431514)
				)
				(arc
					(start 419.36797 -15.745714)
					(mid 419.345652 -15.691832)
					(end 419.29177 -15.669514)
				)
				(arc
					(start 419.097206 -15.669514)
					(mid 419.075462 -15.672682)
					(end 419.05555 -15.68196)
				)
				(arc
					(start 418.759386 -15.874746)
					(mid 418.717702 -15.886968)
					(end 418.676074 -15.874492)
				)
				(arc
					(start 418.38245 -15.68196)
					(mid 418.362526 -15.672724)
					(end 418.340794 -15.669514)
				)
				(arc
					(start 418.14623 -15.669514)
					(mid 418.092348 -15.691832)
					(end 418.07003 -15.745714)
				)
			)
		)
	)
	(zone
		(layer "In1.Cu")
		(hatch none 0.5)
		(connect_pads
			(clearance 0)
		)
		(min_thickness 0.25)
		(keepout
			(tracks not_allowed)
			(vias allowed)
			(pads allowed)
			(copperpour not_allowed)
			(footprints allowed)
		)
		(placement
			(enabled no)
			(sheetname "")
		)
		(fill
			(thermal_gap 0.5)
			(thermal_bridge_width 0.5)
			(island_removal_mode 0)
		)
		(polygon
			(pts
				(arc
					(start 18.110708 -17.966436)
					(mid 18.133026 -18.020318)
					(end 18.186908 -18.042636)
				)
				(arc
					(start 18.382488 -18.042636)
					(mid 18.404364 -18.039504)
					(end 18.424398 -18.03019)
				)
				(arc
					(start 18.718022 -17.837658)
					(mid 18.759678 -17.825256)
					(end 18.801334 -17.837658)
				)
				(arc
					(start 19.096228 -18.03019)
					(mid 19.116152 -18.039426)
					(end 19.137884 -18.042636)
				)
				(arc
					(start 19.332448 -18.042636)
					(mid 19.38633 -18.020318)
					(end 19.408648 -17.966436)
				)
				(arc
					(start 19.408648 -17.280636)
					(mid 19.38633 -17.226754)
					(end 19.332448 -17.204436)
				)
				(arc
					(start 19.137884 -17.204436)
					(mid 19.11614 -17.207604)
					(end 19.096228 -17.216882)
				)
				(arc
					(start 18.800064 -17.409668)
					(mid 18.75838 -17.42189)
					(end 18.716752 -17.409414)
				)
				(arc
					(start 18.423128 -17.216882)
					(mid 18.403204 -17.207646)
					(end 18.381472 -17.204436)
				)
				(arc
					(start 18.186908 -17.204436)
					(mid 18.133026 -17.226754)
					(end 18.110708 -17.280636)
				)
			)
		)
	)
	(zone
		(layer "In1.Cu")
		(hatch none 0.5)
		(connect_pads
			(clearance 0)
		)
		(min_thickness 0.25)
		(keepout
			(tracks not_allowed)
			(vias allowed)
			(pads allowed)
			(copperpour not_allowed)
			(footprints allowed)
		)
		(placement
			(enabled no)
			(sheetname "")
		)
		(fill
			(thermal_gap 0.5)
			(thermal_bridge_width 0.5)
			(island_removal_mode 0)
		)
		(polygon
			(pts
				(arc
					(start 423.65803 -16.431514)
					(mid 423.680348 -16.485396)
					(end 423.73423 -16.507714)
				)
				(arc
					(start 423.92981 -16.507714)
					(mid 423.951686 -16.504582)
					(end 423.97172 -16.495268)
				)
				(arc
					(start 424.265344 -16.302736)
					(mid 424.307 -16.290334)
					(end 424.348656 -16.302736)
				)
				(arc
					(start 424.64355 -16.495268)
					(mid 424.663474 -16.504504)
					(end 424.685206 -16.507714)
				)
				(arc
					(start 424.87977 -16.507714)
					(mid 424.933652 -16.485396)
					(end 424.95597 -16.431514)
				)
				(arc
					(start 424.95597 -15.745714)
					(mid 424.933652 -15.691832)
					(end 424.87977 -15.669514)
				)
				(arc
					(start 424.685206 -15.669514)
					(mid 424.663462 -15.672682)
					(end 424.64355 -15.68196)
				)
				(arc
					(start 424.347386 -15.874746)
					(mid 424.305702 -15.886968)
					(end 424.264074 -15.874492)
				)
				(arc
					(start 423.97045 -15.68196)
					(mid 423.950526 -15.672724)
					(end 423.928794 -15.669514)
				)
				(arc
					(start 423.73423 -15.669514)
					(mid 423.680348 -15.691832)
					(end 423.65803 -15.745714)
				)
			)
		)
	)
	(zone
		(layer "In1.Cu")
		(hatch none 0.5)
		(connect_pads
			(clearance 0)
		)
		(min_thickness 0.25)
		(keepout
			(tracks not_allowed)
			(vias allowed)
			(pads allowed)
			(copperpour not_allowed)
			(footprints allowed)
		)
		(placement
			(enabled no)
			(sheetname "")
		)
		(fill
			(thermal_gap 0.5)
			(thermal_bridge_width 0.5)
			(island_removal_mode 0)
		)
		(polygon
			(pts
				(arc
					(start 347.994478 -408.860244)
					(mid 348.016796 -408.914126)
					(end 348.070678 -408.936444)
				)
				(arc
					(start 348.266258 -408.936444)
					(mid 348.288134 -408.933312)
					(end 348.308168 -408.923998)
				)
				(arc
					(start 348.601792 -408.731466)
					(mid 348.643448 -408.719064)
					(end 348.685104 -408.731466)
				)
				(arc
					(start 348.979998 -408.923998)
					(mid 348.999922 -408.933234)
					(end 349.021654 -408.936444)
				)
				(arc
					(start 349.216218 -408.936444)
					(mid 349.2701 -408.914126)
					(end 349.292418 -408.860244)
				)
				(arc
					(start 349.292418 -408.174444)
					(mid 349.2701 -408.120562)
					(end 349.216218 -408.098244)
				)
				(arc
					(start 349.021654 -408.098244)
					(mid 348.99991 -408.101412)
					(end 348.979998 -408.11069)
				)
				(arc
					(start 348.683834 -408.303476)
					(mid 348.64215 -408.315698)
					(end 348.600522 -408.303222)
				)
				(arc
					(start 348.306898 -408.11069)
					(mid 348.286974 -408.101454)
					(end 348.265242 -408.098244)
				)
				(arc
					(start 348.070678 -408.098244)
					(mid 348.016796 -408.120562)
					(end 347.994478 -408.174444)
				)
			)
		)
	)
	(zone
		(layer "In1.Cu")
		(hatch none 0.5)
		(connect_pads
			(clearance 0)
		)
		(min_thickness 0.25)
		(keepout
			(tracks not_allowed)
			(vias allowed)
			(pads allowed)
			(copperpour not_allowed)
			(footprints allowed)
		)
		(placement
			(enabled no)
			(sheetname "")
		)
		(fill
			(thermal_gap 0.5)
			(thermal_bridge_width 0.5)
			(island_removal_mode 0)
		)
		(polygon
			(pts
				(arc
					(start 84.521548 -402.713952)
					(mid 84.543866 -402.767834)
					(end 84.597748 -402.790152)
				)
				(arc
					(start 84.793328 -402.790152)
					(mid 84.815204 -402.78702)
					(end 84.835238 -402.777706)
				)
				(arc
					(start 85.128862 -402.585174)
					(mid 85.170518 -402.572772)
					(end 85.212174 -402.585174)
				)
				(arc
					(start 85.507068 -402.777706)
					(mid 85.526992 -402.786942)
					(end 85.548724 -402.790152)
				)
				(arc
					(start 85.743288 -402.790152)
					(mid 85.79717 -402.767834)
					(end 85.819488 -402.713952)
				)
				(arc
					(start 85.819488 -402.028152)
					(mid 85.79717 -401.97427)
					(end 85.743288 -401.951952)
				)
				(arc
					(start 85.548724 -401.951952)
					(mid 85.52698 -401.95512)
					(end 85.507068 -401.964398)
				)
				(arc
					(start 85.210904 -402.157184)
					(mid 85.16922 -402.169406)
					(end 85.127592 -402.15693)
				)
				(arc
					(start 84.833968 -401.964398)
					(mid 84.814044 -401.955162)
					(end 84.792312 -401.951952)
				)
				(arc
					(start 84.597748 -401.951952)
					(mid 84.543866 -401.97427)
					(end 84.521548 -402.028152)
				)
			)
		)
	)
	(zone
		(layer "In1.Cu")
		(hatch none 0.5)
		(connect_pads
			(clearance 0)
		)
		(min_thickness 0.25)
		(keepout
			(tracks not_allowed)
			(vias allowed)
			(pads allowed)
			(copperpour not_allowed)
			(footprints allowed)
		)
		(placement
			(enabled no)
			(sheetname "")
		)
		(fill
			(thermal_gap 0.5)
			(thermal_bridge_width 0.5)
			(island_removal_mode 0)
		)
		(polygon
			(pts
				(arc
					(start 162.823144 -402.713952)
					(mid 162.845462 -402.767834)
					(end 162.899344 -402.790152)
				)
				(arc
					(start 163.094924 -402.790152)
					(mid 163.1168 -402.78702)
					(end 163.136834 -402.777706)
				)
				(arc
					(start 163.430458 -402.585174)
					(mid 163.472114 -402.572772)
					(end 163.51377 -402.585174)
				)
				(arc
					(start 163.808664 -402.777706)
					(mid 163.828588 -402.786942)
					(end 163.85032 -402.790152)
				)
				(arc
					(start 164.044884 -402.790152)
					(mid 164.098766 -402.767834)
					(end 164.121084 -402.713952)
				)
				(arc
					(start 164.121084 -402.028152)
					(mid 164.098766 -401.97427)
					(end 164.044884 -401.951952)
				)
				(arc
					(start 163.85032 -401.951952)
					(mid 163.828576 -401.95512)
					(end 163.808664 -401.964398)
				)
				(arc
					(start 163.5125 -402.157184)
					(mid 163.470816 -402.169406)
					(end 163.429188 -402.15693)
				)
				(arc
					(start 163.135564 -401.964398)
					(mid 163.11564 -401.955162)
					(end 163.093908 -401.951952)
				)
				(arc
					(start 162.899344 -401.951952)
					(mid 162.845462 -401.97427)
					(end 162.823144 -402.028152)
				)
			)
		)
	)
	(zone
		(layer "In1.Cu")
		(hatch none 0.5)
		(connect_pads
			(clearance 0)
		)
		(min_thickness 0.25)
		(keepout
			(tracks not_allowed)
			(vias allowed)
			(pads allowed)
			(copperpour not_allowed)
			(footprints allowed)
		)
		(placement
			(enabled no)
			(sheetname "")
		)
		(fill
			(thermal_gap 0.5)
			(thermal_bridge_width 0.5)
			(island_removal_mode 0)
		)
		(polygon
			(pts
				(arc
					(start 50.825908 -402.713952)
					(mid 50.848226 -402.767834)
					(end 50.902108 -402.790152)
				)
				(arc
					(start 51.097688 -402.790152)
					(mid 51.119564 -402.78702)
					(end 51.139598 -402.777706)
				)
				(arc
					(start 51.433222 -402.585174)
					(mid 51.474878 -402.572772)
					(end 51.516534 -402.585174)
				)
				(arc
					(start 51.811428 -402.777706)
					(mid 51.831352 -402.786942)
					(end 51.853084 -402.790152)
				)
				(arc
					(start 52.047648 -402.790152)
					(mid 52.10153 -402.767834)
					(end 52.123848 -402.713952)
				)
				(arc
					(start 52.123848 -402.028152)
					(mid 52.10153 -401.97427)
					(end 52.047648 -401.951952)
				)
				(arc
					(start 51.853084 -401.951952)
					(mid 51.83134 -401.95512)
					(end 51.811428 -401.964398)
				)
				(arc
					(start 51.515264 -402.157184)
					(mid 51.47358 -402.169406)
					(end 51.431952 -402.15693)
				)
				(arc
					(start 51.138328 -401.964398)
					(mid 51.118404 -401.955162)
					(end 51.096672 -401.951952)
				)
				(arc
					(start 50.902108 -401.951952)
					(mid 50.848226 -401.97427)
					(end 50.825908 -402.028152)
				)
			)
		)
	)
	(zone
		(layer "In1.Cu")
		(hatch none 0.5)
		(connect_pads
			(clearance 0)
		)
		(min_thickness 0.25)
		(keepout
			(tracks not_allowed)
			(vias allowed)
			(pads allowed)
			(copperpour not_allowed)
			(footprints allowed)
		)
		(placement
			(enabled no)
			(sheetname "")
		)
		(fill
			(thermal_gap 0.5)
			(thermal_bridge_width 0.5)
			(island_removal_mode 0)
		)
		(polygon
			(pts
				(arc
					(start 25.567132 -7.672324)
					(mid 25.544814 -7.618442)
					(end 25.490932 -7.596124)
				)
				(arc
					(start 24.209502 -7.596124)
					(mid 24.15562 -7.618442)
					(end 24.133302 -7.672324)
				)
				(arc
					(start 24.133302 -9.094724)
					(mid 24.15562 -9.148606)
					(end 24.209502 -9.170924)
				)
				(arc
					(start 25.490932 -9.170924)
					(mid 25.544814 -9.148606)
					(end 25.567132 -9.094724)
				)
			)
		)
	)
	(zone
		(layer "In1.Cu")
		(hatch none 0.5)
		(connect_pads
			(clearance 0)
		)
		(min_thickness 0.25)
		(keepout
			(tracks not_allowed)
			(vias allowed)
			(pads allowed)
			(copperpour not_allowed)
			(footprints allowed)
		)
		(placement
			(enabled no)
			(sheetname "")
		)
		(fill
			(thermal_gap 0.5)
			(thermal_bridge_width 0.5)
			(island_removal_mode 0)
		)
		(polygon
			(pts
				(arc
					(start 393.227814 -11.91768)
					(mid 393.250132 -11.971562)
					(end 393.304014 -11.99388)
				)
				(arc
					(start 394.585444 -11.99388)
					(mid 394.639326 -11.971562)
					(end 394.661644 -11.91768)
				)
				(arc
					(start 394.661644 -10.49528)
					(mid 394.639326 -10.441398)
					(end 394.585444 -10.41908)
				)
				(arc
					(start 393.304014 -10.41908)
					(mid 393.250132 -10.441398)
					(end 393.227814 -10.49528)
				)
			)
		)
	)
	(zone
		(layer "In1.Cu")
		(hatch none 0.5)
		(connect_pads
			(clearance 0)
		)
		(min_thickness 0.25)
		(keepout
			(tracks not_allowed)
			(vias allowed)
			(pads allowed)
			(copperpour not_allowed)
			(footprints allowed)
		)
		(placement
			(enabled no)
			(sheetname "")
		)
		(fill
			(thermal_gap 0.5)
			(thermal_bridge_width 0.5)
			(island_removal_mode 0)
		)
		(polygon
			(pts
				(arc
					(start 20.904708 -16.442436)
					(mid 20.927026 -16.496318)
					(end 20.980908 -16.518636)
				)
				(arc
					(start 21.176488 -16.518636)
					(mid 21.198364 -16.515504)
					(end 21.218398 -16.50619)
				)
				(arc
					(start 21.512022 -16.313658)
					(mid 21.553678 -16.301256)
					(end 21.595334 -16.313658)
				)
				(arc
					(start 21.890228 -16.50619)
					(mid 21.910152 -16.515426)
					(end 21.931884 -16.518636)
				)
				(arc
					(start 22.126448 -16.518636)
					(mid 22.18033 -16.496318)
					(end 22.202648 -16.442436)
				)
				(arc
					(start 22.202648 -15.756636)
					(mid 22.18033 -15.702754)
					(end 22.126448 -15.680436)
				)
				(arc
					(start 21.931884 -15.680436)
					(mid 21.91014 -15.683604)
					(end 21.890228 -15.692882)
				)
				(arc
					(start 21.594064 -15.885668)
					(mid 21.55238 -15.89789)
					(end 21.510752 -15.885414)
				)
				(arc
					(start 21.217128 -15.692882)
					(mid 21.197204 -15.683646)
					(end 21.175472 -15.680436)
				)
				(arc
					(start 20.980908 -15.680436)
					(mid 20.927026 -15.702754)
					(end 20.904708 -15.756636)
				)
			)
		)
	)
	(zone
		(layer "In1.Cu")
		(hatch none 0.5)
		(connect_pads
			(clearance 0)
		)
		(min_thickness 0.25)
		(keepout
			(tracks not_allowed)
			(vias allowed)
			(pads allowed)
			(copperpour not_allowed)
			(footprints allowed)
		)
		(placement
			(enabled no)
			(sheetname "")
		)
		(fill
			(thermal_gap 0.5)
			(thermal_bridge_width 0.5)
			(island_removal_mode 0)
		)
		(polygon
			(pts
				(arc
					(start 176.38268 -50.936144)
					(mid 176.328798 -50.913826)
					(end 176.30648 -50.859944)
				)
				(arc
					(start 176.30648 -50.227484)
					(mid 176.328798 -50.173602)
					(end 176.38268 -50.151284)
				)
				(arc
					(start 177.83556 -50.151284)
					(mid 177.889442 -50.173602)
					(end 177.91176 -50.227484)
				)
				(arc
					(start 177.91176 -50.859944)
					(mid 177.889442 -50.913826)
					(end 177.83556 -50.936144)
				)
			)
		)
	)
	(zone
		(layer "In1.Cu")
		(hatch none 0.5)
		(connect_pads
			(clearance 0)
		)
		(min_thickness 0.25)
		(keepout
			(tracks not_allowed)
			(vias allowed)
			(pads allowed)
			(copperpour not_allowed)
			(footprints allowed)
		)
		(placement
			(enabled no)
			(sheetname "")
		)
		(fill
			(thermal_gap 0.5)
			(thermal_bridge_width 0.5)
			(island_removal_mode 0)
		)
		(polygon
			(pts
				(arc
					(start 126.064264 -402.713952)
					(mid 126.086582 -402.767834)
					(end 126.140464 -402.790152)
				)
				(arc
					(start 126.336044 -402.790152)
					(mid 126.35792 -402.78702)
					(end 126.377954 -402.777706)
				)
				(arc
					(start 126.671578 -402.585174)
					(mid 126.713234 -402.572772)
					(end 126.75489 -402.585174)
				)
				(arc
					(start 127.049784 -402.777706)
					(mid 127.069708 -402.786942)
					(end 127.09144 -402.790152)
				)
				(arc
					(start 127.286004 -402.790152)
					(mid 127.339886 -402.767834)
					(end 127.362204 -402.713952)
				)
				(arc
					(start 127.362204 -402.028152)
					(mid 127.339886 -401.97427)
					(end 127.286004 -401.951952)
				)
				(arc
					(start 127.09144 -401.951952)
					(mid 127.069696 -401.95512)
					(end 127.049784 -401.964398)
				)
				(arc
					(start 126.75362 -402.157184)
					(mid 126.711936 -402.169406)
					(end 126.670308 -402.15693)
				)
				(arc
					(start 126.376684 -401.964398)
					(mid 126.35676 -401.955162)
					(end 126.335028 -401.951952)
				)
				(arc
					(start 126.140464 -401.951952)
					(mid 126.086582 -401.97427)
					(end 126.064264 -402.028152)
				)
			)
		)
	)
	(zone
		(layer "In1.Cu")
		(hatch none 0.5)
		(connect_pads
			(clearance 0)
		)
		(min_thickness 0.25)
		(keepout
			(tracks not_allowed)
			(vias allowed)
			(pads allowed)
			(copperpour not_allowed)
			(footprints allowed)
		)
		(placement
			(enabled no)
			(sheetname "")
		)
		(fill
			(thermal_gap 0.5)
			(thermal_bridge_width 0.5)
			(island_removal_mode 0)
		)
		(polygon
			(pts
				(arc
					(start 328.126852 -4.150106)
					(mid 328.14917 -4.096224)
					(end 328.203052 -4.073906)
				)
				(arc
					(start 328.815192 -4.073906)
					(mid 328.869074 -4.096224)
					(end 328.891392 -4.150106)
				)
				(arc
					(start 328.891392 -5.247386)
					(mid 328.869074 -5.301268)
					(end 328.815192 -5.323586)
				)
				(arc
					(start 328.203052 -5.323586)
					(mid 328.14917 -5.301268)
					(end 328.126852 -5.247386)
				)
			)
		)
	)
	(zone
		(layer "In1.Cu")
		(hatch none 0.5)
		(connect_pads
			(clearance 0)
		)
		(min_thickness 0.25)
		(keepout
			(tracks not_allowed)
			(vias allowed)
			(pads allowed)
			(copperpour not_allowed)
			(footprints allowed)
		)
		(placement
			(enabled no)
			(sheetname "")
		)
		(fill
			(thermal_gap 0.5)
			(thermal_bridge_width 0.5)
			(island_removal_mode 0)
		)
		(polygon
			(pts
				(arc
					(start 15.438374 -106.164634)
					(mid 15.477415 -106.156877)
					(end 15.510256 -106.134408)
				)
				(arc
					(start 15.510256 -106.134408)
					(mid 15.530298 -106.10372)
					(end 15.537942 -106.06786)
				)
				(xy 15.537942 -105.92562) (xy 15.537688 -105.92562)
				(arc
					(start 15.537688 -104.998266)
					(mid 15.508498 -104.93476)
					(end 15.44447 -104.906826)
				)
				(arc
					(start 15.137638 -104.906826)
					(mid 15.098597 -104.914583)
					(end 15.065756 -104.937052)
				)
				(arc
					(start 15.065756 -104.937052)
					(mid 15.045714 -104.96774)
					(end 15.03807 -105.0036)
				)
				(xy 15.03807 -106.03484) (xy 15.038324 -106.03484)
				(arc
					(start 15.038324 -106.073194)
					(mid 15.067514 -106.1367)
					(end 15.131542 -106.164634)
				)
			)
		)
	)
	(zone
		(layer "In1.Cu")
		(hatch none 0.5)
		(connect_pads
			(clearance 0)
		)
		(min_thickness 0.25)
		(keepout
			(tracks not_allowed)
			(vias allowed)
			(pads allowed)
			(copperpour not_allowed)
			(footprints allowed)
		)
		(placement
			(enabled no)
			(sheetname "")
		)
		(fill
			(thermal_gap 0.5)
			(thermal_bridge_width 0.5)
			(island_removal_mode 0)
		)
		(polygon
			(pts
				(arc
					(start 119.937784 -402.713952)
					(mid 119.960102 -402.767834)
					(end 120.013984 -402.790152)
				)
				(arc
					(start 120.209564 -402.790152)
					(mid 120.23144 -402.78702)
					(end 120.251474 -402.777706)
				)
				(arc
					(start 120.545098 -402.585174)
					(mid 120.586754 -402.572772)
					(end 120.62841 -402.585174)
				)
				(arc
					(start 120.923304 -402.777706)
					(mid 120.943228 -402.786942)
					(end 120.96496 -402.790152)
				)
				(arc
					(start 121.159524 -402.790152)
					(mid 121.213406 -402.767834)
					(end 121.235724 -402.713952)
				)
				(arc
					(start 121.235724 -402.028152)
					(mid 121.213406 -401.97427)
					(end 121.159524 -401.951952)
				)
				(arc
					(start 120.96496 -401.951952)
					(mid 120.943216 -401.95512)
					(end 120.923304 -401.964398)
				)
				(arc
					(start 120.62714 -402.157184)
					(mid 120.585456 -402.169406)
					(end 120.543828 -402.15693)
				)
				(arc
					(start 120.250204 -401.964398)
					(mid 120.23028 -401.955162)
					(end 120.208548 -401.951952)
				)
				(arc
					(start 120.013984 -401.951952)
					(mid 119.960102 -401.97427)
					(end 119.937784 -402.028152)
				)
			)
		)
	)
	(zone
		(layer "In1.Cu")
		(hatch none 0.5)
		(connect_pads
			(clearance 0)
		)
		(min_thickness 0.25)
		(keepout
			(tracks not_allowed)
			(vias allowed)
			(pads allowed)
			(copperpour not_allowed)
			(footprints allowed)
		)
		(placement
			(enabled no)
			(sheetname "")
		)
		(fill
			(thermal_gap 0.5)
			(thermal_bridge_width 0.5)
			(island_removal_mode 0)
		)
		(polygon
			(pts
				(arc
					(start 20.167092 -7.672324)
					(mid 20.144774 -7.618442)
					(end 20.090892 -7.596124)
				)
				(arc
					(start 18.809462 -7.596124)
					(mid 18.75558 -7.618442)
					(end 18.733262 -7.672324)
				)
				(arc
					(start 18.733262 -9.094724)
					(mid 18.75558 -9.148606)
					(end 18.809462 -9.170924)
				)
				(arc
					(start 20.090892 -9.170924)
					(mid 20.144774 -9.148606)
					(end 20.167092 -9.094724)
				)
			)
		)
	)
	(zone
		(layer "In1.Cu")
		(hatch none 0.5)
		(connect_pads
			(clearance 0)
		)
		(min_thickness 0.25)
		(keepout
			(tracks not_allowed)
			(vias allowed)
			(pads allowed)
			(copperpour not_allowed)
			(footprints allowed)
		)
		(placement
			(enabled no)
			(sheetname "")
		)
		(fill
			(thermal_gap 0.5)
			(thermal_bridge_width 0.5)
			(island_removal_mode 0)
		)
		(polygon
			(pts
				(arc
					(start 22.328886 -11.91768)
					(mid 22.351204 -11.971562)
					(end 22.405086 -11.99388)
				)
				(arc
					(start 23.686516 -11.99388)
					(mid 23.740398 -11.971562)
					(end 23.762716 -11.91768)
				)
				(arc
					(start 23.762716 -10.49528)
					(mid 23.740398 -10.441398)
					(end 23.686516 -10.41908)
				)
				(arc
					(start 22.405086 -10.41908)
					(mid 22.351204 -10.441398)
					(end 22.328886 -10.49528)
				)
			)
		)
	)
	(zone
		(layer "In1.Cu")
		(hatch none 0.5)
		(connect_pads
			(clearance 0)
		)
		(min_thickness 0.25)
		(keepout
			(tracks not_allowed)
			(vias allowed)
			(pads allowed)
			(copperpour not_allowed)
			(footprints allowed)
		)
		(placement
			(enabled no)
			(sheetname "")
		)
		(fill
			(thermal_gap 0.5)
			(thermal_bridge_width 0.5)
			(island_removal_mode 0)
		)
		(polygon
			(pts
				(arc
					(start 15.438374 -105.364534)
					(mid 15.477415 -105.356777)
					(end 15.510256 -105.334308)
				)
				(arc
					(start 15.510256 -105.334308)
					(mid 15.530298 -105.30362)
					(end 15.537942 -105.26776)
				)
				(xy 15.537942 -105.12552) (xy 15.537688 -105.12552)
				(arc
					(start 15.537688 -104.198166)
					(mid 15.508498 -104.13466)
					(end 15.44447 -104.106726)
				)
				(arc
					(start 15.137638 -104.106726)
					(mid 15.098597 -104.114483)
					(end 15.065756 -104.136952)
				)
				(arc
					(start 15.065756 -104.136952)
					(mid 15.045714 -104.16764)
					(end 15.03807 -104.2035)
				)
				(xy 15.03807 -105.23474) (xy 15.038324 -105.23474)
				(arc
					(start 15.038324 -105.273094)
					(mid 15.067514 -105.3366)
					(end 15.131542 -105.364534)
				)
			)
		)
	)
	(zone
		(layer "In1.Cu")
		(hatch none 0.5)
		(connect_pads
			(clearance 0)
		)
		(min_thickness 0.25)
		(keepout
			(tracks not_allowed)
			(vias allowed)
			(pads allowed)
			(copperpour not_allowed)
			(footprints allowed)
		)
		(placement
			(enabled no)
			(sheetname "")
		)
		(fill
			(thermal_gap 0.5)
			(thermal_bridge_width 0.5)
			(island_removal_mode 0)
		)
		(polygon
			(pts
				(arc
					(start 43.562524 -16.442436)
					(mid 43.584842 -16.496318)
					(end 43.638724 -16.518636)
				)
				(arc
					(start 43.834304 -16.518636)
					(mid 43.85618 -16.515504)
					(end 43.876214 -16.50619)
				)
				(arc
					(start 44.169838 -16.313658)
					(mid 44.211494 -16.301256)
					(end 44.25315 -16.313658)
				)
				(arc
					(start 44.548044 -16.50619)
					(mid 44.567968 -16.515426)
					(end 44.5897 -16.518636)
				)
				(arc
					(start 44.784264 -16.518636)
					(mid 44.838146 -16.496318)
					(end 44.860464 -16.442436)
				)
				(arc
					(start 44.860464 -15.756636)
					(mid 44.838146 -15.702754)
					(end 44.784264 -15.680436)
				)
				(arc
					(start 44.5897 -15.680436)
					(mid 44.567956 -15.683604)
					(end 44.548044 -15.692882)
				)
				(arc
					(start 44.25188 -15.885668)
					(mid 44.210196 -15.89789)
					(end 44.168568 -15.885414)
				)
				(arc
					(start 43.874944 -15.692882)
					(mid 43.85502 -15.683646)
					(end 43.833288 -15.680436)
				)
				(arc
					(start 43.638724 -15.680436)
					(mid 43.584842 -15.702754)
					(end 43.562524 -15.756636)
				)
			)
		)
	)
	(zone
		(layer "In1.Cu")
		(hatch none 0.5)
		(connect_pads
			(clearance 0)
		)
		(min_thickness 0.25)
		(keepout
			(tracks not_allowed)
			(vias allowed)
			(pads allowed)
			(copperpour not_allowed)
			(footprints allowed)
		)
		(placement
			(enabled no)
			(sheetname "")
		)
		(fill
			(thermal_gap 0.5)
			(thermal_bridge_width 0.5)
			(island_removal_mode 0)
		)
		(polygon
			(pts
				(arc
					(start 47.762668 -402.713952)
					(mid 47.784986 -402.767834)
					(end 47.838868 -402.790152)
				)
				(arc
					(start 48.034448 -402.790152)
					(mid 48.056324 -402.78702)
					(end 48.076358 -402.777706)
				)
				(arc
					(start 48.369982 -402.585174)
					(mid 48.411638 -402.572772)
					(end 48.453294 -402.585174)
				)
				(arc
					(start 48.748188 -402.777706)
					(mid 48.768112 -402.786942)
					(end 48.789844 -402.790152)
				)
				(arc
					(start 48.984408 -402.790152)
					(mid 49.03829 -402.767834)
					(end 49.060608 -402.713952)
				)
				(arc
					(start 49.060608 -402.028152)
					(mid 49.03829 -401.97427)
					(end 48.984408 -401.951952)
				)
				(arc
					(start 48.789844 -401.951952)
					(mid 48.7681 -401.95512)
					(end 48.748188 -401.964398)
				)
				(arc
					(start 48.452024 -402.157184)
					(mid 48.41034 -402.169406)
					(end 48.368712 -402.15693)
				)
				(arc
					(start 48.075088 -401.964398)
					(mid 48.055164 -401.955162)
					(end 48.033432 -401.951952)
				)
				(arc
					(start 47.838868 -401.951952)
					(mid 47.784986 -401.97427)
					(end 47.762668 -402.028152)
				)
			)
		)
	)
	(zone
		(layer "In1.Cu")
		(hatch none 0.5)
		(connect_pads
			(clearance 0)
		)
		(min_thickness 0.25)
		(keepout
			(tracks not_allowed)
			(vias allowed)
			(pads allowed)
			(copperpour not_allowed)
			(footprints allowed)
		)
		(placement
			(enabled no)
			(sheetname "")
		)
		(fill
			(thermal_gap 0.5)
			(thermal_bridge_width 0.5)
			(island_removal_mode 0)
		)
		(polygon
			(pts
				(arc
					(start 407.265886 -7.672324)
					(mid 407.243568 -7.618442)
					(end 407.189686 -7.596124)
				)
				(arc
					(start 405.908256 -7.596124)
					(mid 405.854374 -7.618442)
					(end 405.832056 -7.672324)
				)
				(arc
					(start 405.832056 -9.094724)
					(mid 405.854374 -9.148606)
					(end 405.908256 -9.170924)
				)
				(arc
					(start 407.189686 -9.170924)
					(mid 407.243568 -9.148606)
					(end 407.265886 -9.094724)
				)
			)
		)
	)
	(zone
		(layer "In1.Cu")
		(hatch none 0.5)
		(connect_pads
			(clearance 0)
		)
		(min_thickness 0.25)
		(keepout
			(tracks not_allowed)
			(vias allowed)
			(pads allowed)
			(copperpour not_allowed)
			(footprints allowed)
		)
		(placement
			(enabled no)
			(sheetname "")
		)
		(fill
			(thermal_gap 0.5)
			(thermal_bridge_width 0.5)
			(island_removal_mode 0)
		)
		(polygon
			(pts
				(arc
					(start 322.142358 -402.713952)
					(mid 322.164676 -402.767834)
					(end 322.218558 -402.790152)
				)
				(arc
					(start 322.414138 -402.790152)
					(mid 322.436014 -402.78702)
					(end 322.456048 -402.777706)
				)
				(arc
					(start 322.749672 -402.585174)
					(mid 322.791328 -402.572772)
					(end 322.832984 -402.585174)
				)
				(arc
					(start 323.127878 -402.777706)
					(mid 323.147802 -402.786942)
					(end 323.169534 -402.790152)
				)
				(arc
					(start 323.364098 -402.790152)
					(mid 323.41798 -402.767834)
					(end 323.440298 -402.713952)
				)
				(arc
					(start 323.440298 -402.028152)
					(mid 323.41798 -401.97427)
					(end 323.364098 -401.951952)
				)
				(arc
					(start 323.169534 -401.951952)
					(mid 323.14779 -401.95512)
					(end 323.127878 -401.964398)
				)
				(arc
					(start 322.831714 -402.157184)
					(mid 322.79003 -402.169406)
					(end 322.748402 -402.15693)
				)
				(arc
					(start 322.454778 -401.964398)
					(mid 322.434854 -401.955162)
					(end 322.413122 -401.951952)
				)
				(arc
					(start 322.218558 -401.951952)
					(mid 322.164676 -401.97427)
					(end 322.142358 -402.028152)
				)
			)
		)
	)
	(zone
		(layer "In1.Cu")
		(hatch none 0.5)
		(connect_pads
			(clearance 0)
		)
		(min_thickness 0.25)
		(keepout
			(tracks not_allowed)
			(vias allowed)
			(pads allowed)
			(copperpour not_allowed)
			(footprints allowed)
		)
		(placement
			(enabled no)
			(sheetname "")
		)
		(fill
			(thermal_gap 0.5)
			(thermal_bridge_width 0.5)
			(island_removal_mode 0)
		)
		(polygon
			(pts
				(arc
					(start 54.887114 -7.672324)
					(mid 54.864796 -7.618442)
					(end 54.810914 -7.596124)
				)
				(arc
					(start 53.529484 -7.596124)
					(mid 53.475602 -7.618442)
					(end 53.453284 -7.672324)
				)
				(arc
					(start 53.453284 -9.094724)
					(mid 53.475602 -9.148606)
					(end 53.529484 -9.170924)
				)
				(arc
					(start 54.810914 -9.170924)
					(mid 54.864796 -9.148606)
					(end 54.887114 -9.094724)
				)
			)
		)
	)
	(zone
		(layer "In1.Cu")
		(hatch none 0.5)
		(connect_pads
			(clearance 0)
		)
		(min_thickness 0.25)
		(keepout
			(tracks not_allowed)
			(vias allowed)
			(pads allowed)
			(copperpour not_allowed)
			(footprints allowed)
		)
		(placement
			(enabled no)
			(sheetname "")
		)
		(fill
			(thermal_gap 0.5)
			(thermal_bridge_width 0.5)
			(island_removal_mode 0)
		)
		(polygon
			(pts
				(arc
					(start 306.826158 -402.713952)
					(mid 306.848476 -402.767834)
					(end 306.902358 -402.790152)
				)
				(arc
					(start 307.097938 -402.790152)
					(mid 307.119814 -402.78702)
					(end 307.139848 -402.777706)
				)
				(arc
					(start 307.433472 -402.585174)
					(mid 307.475128 -402.572772)
					(end 307.516784 -402.585174)
				)
				(arc
					(start 307.811678 -402.777706)
					(mid 307.831602 -402.786942)
					(end 307.853334 -402.790152)
				)
				(arc
					(start 308.047898 -402.790152)
					(mid 308.10178 -402.767834)
					(end 308.124098 -402.713952)
				)
				(arc
					(start 308.124098 -402.028152)
					(mid 308.10178 -401.97427)
					(end 308.047898 -401.951952)
				)
				(arc
					(start 307.853334 -401.951952)
					(mid 307.83159 -401.95512)
					(end 307.811678 -401.964398)
				)
				(arc
					(start 307.515514 -402.157184)
					(mid 307.47383 -402.169406)
					(end 307.432202 -402.15693)
				)
				(arc
					(start 307.138578 -401.964398)
					(mid 307.118654 -401.955162)
					(end 307.096922 -401.951952)
				)
				(arc
					(start 306.902358 -401.951952)
					(mid 306.848476 -401.97427)
					(end 306.826158 -402.028152)
				)
			)
		)
	)
	(zone
		(layer "In1.Cu")
		(hatch none 0.5)
		(connect_pads
			(clearance 0)
		)
		(min_thickness 0.25)
		(keepout
			(tracks not_allowed)
			(vias allowed)
			(pads allowed)
			(copperpour not_allowed)
			(footprints allowed)
		)
		(placement
			(enabled no)
			(sheetname "")
		)
		(fill
			(thermal_gap 0.5)
			(thermal_bridge_width 0.5)
			(island_removal_mode 0)
		)
		(polygon
			(pts
				(arc
					(start 37.668708 -16.442436)
					(mid 37.691026 -16.496318)
					(end 37.744908 -16.518636)
				)
				(arc
					(start 37.940488 -16.518636)
					(mid 37.962364 -16.515504)
					(end 37.982398 -16.50619)
				)
				(arc
					(start 38.276022 -16.313658)
					(mid 38.317678 -16.301256)
					(end 38.359334 -16.313658)
				)
				(arc
					(start 38.654228 -16.50619)
					(mid 38.674152 -16.515426)
					(end 38.695884 -16.518636)
				)
				(arc
					(start 38.890448 -16.518636)
					(mid 38.94433 -16.496318)
					(end 38.966648 -16.442436)
				)
				(arc
					(start 38.966648 -15.756636)
					(mid 38.94433 -15.702754)
					(end 38.890448 -15.680436)
				)
				(arc
					(start 38.695884 -15.680436)
					(mid 38.67414 -15.683604)
					(end 38.654228 -15.692882)
				)
				(arc
					(start 38.358064 -15.885668)
					(mid 38.31638 -15.89789)
					(end 38.274752 -15.885414)
				)
				(arc
					(start 37.981128 -15.692882)
					(mid 37.961204 -15.683646)
					(end 37.939472 -15.680436)
				)
				(arc
					(start 37.744908 -15.680436)
					(mid 37.691026 -15.702754)
					(end 37.668708 -15.756636)
				)
			)
		)
	)
	(zone
		(layer "In1.Cu")
		(hatch none 0.5)
		(connect_pads
			(clearance 0)
		)
		(min_thickness 0.25)
		(keepout
			(tracks not_allowed)
			(vias allowed)
			(pads allowed)
			(copperpour not_allowed)
			(footprints allowed)
		)
		(placement
			(enabled no)
			(sheetname "")
		)
		(fill
			(thermal_gap 0.5)
			(thermal_bridge_width 0.5)
			(island_removal_mode 0)
		)
		(polygon
			(pts
				(arc
					(start 414.937956 -11.91768)
					(mid 414.960274 -11.971562)
					(end 415.014156 -11.99388)
				)
				(arc
					(start 416.295586 -11.99388)
					(mid 416.349468 -11.971562)
					(end 416.371786 -11.91768)
				)
				(arc
					(start 416.371786 -10.49528)
					(mid 416.349468 -10.441398)
					(end 416.295586 -10.41908)
				)
				(arc
					(start 415.014156 -10.41908)
					(mid 414.960274 -10.441398)
					(end 414.937956 -10.49528)
				)
			)
		)
	)
	(zone
		(layer "In1.Cu")
		(hatch none 0.5)
		(connect_pads
			(clearance 0)
		)
		(min_thickness 0.25)
		(keepout
			(tracks not_allowed)
			(vias allowed)
			(pads allowed)
			(copperpour not_allowed)
			(footprints allowed)
		)
		(placement
			(enabled no)
			(sheetname "")
		)
		(fill
			(thermal_gap 0.5)
			(thermal_bridge_width 0.5)
			(island_removal_mode 0)
		)
		(polygon
			(pts
				(arc
					(start 231.43464 -56.561228)
					(mid 231.380758 -56.53891)
					(end 231.35844 -56.485028)
				)
				(arc
					(start 231.35844 -55.656988)
					(mid 231.380758 -55.603106)
					(end 231.43464 -55.580788)
				)
				(arc
					(start 232.55986 -55.580788)
					(mid 232.613742 -55.603106)
					(end 232.63606 -55.656988)
				)
				(arc
					(start 232.63606 -56.485028)
					(mid 232.613742 -56.53891)
					(end 232.55986 -56.561228)
				)
			)
		)
	)
	(zone
		(layer "In1.Cu")
		(hatch none 0.5)
		(connect_pads
			(clearance 0)
		)
		(min_thickness 0.25)
		(keepout
			(tracks not_allowed)
			(vias allowed)
			(pads allowed)
			(copperpour not_allowed)
			(footprints allowed)
		)
		(placement
			(enabled no)
			(sheetname "")
		)
		(fill
			(thermal_gap 0.5)
			(thermal_bridge_width 0.5)
			(island_removal_mode 0)
		)
		(polygon
			(pts
				(arc
					(start 261.845044 -0.162306)
					(mid 261.822726 -0.216188)
					(end 261.768844 -0.238506)
				)
				(arc
					(start 261.156704 -0.238506)
					(mid 261.102822 -0.216188)
					(end 261.080504 -0.162306)
				)
				(arc
					(start 261.080504 0.934974)
					(mid 261.102822 0.988856)
					(end 261.156704 1.011174)
				)
				(arc
					(start 261.768844 1.011174)
					(mid 261.822726 0.988856)
					(end 261.845044 0.934974)
				)
			)
		)
	)
	(zone
		(layer "In1.Cu")
		(hatch none 0.5)
		(connect_pads
			(clearance 0)
		)
		(min_thickness 0.25)
		(keepout
			(tracks not_allowed)
			(vias allowed)
			(pads allowed)
			(copperpour not_allowed)
			(footprints allowed)
		)
		(placement
			(enabled no)
			(sheetname "")
		)
		(fill
			(thermal_gap 0.5)
			(thermal_bridge_width 0.5)
			(island_removal_mode 0)
		)
		(polygon
			(pts
				(arc
					(start 335.741518 -408.860244)
					(mid 335.763836 -408.914126)
					(end 335.817718 -408.936444)
				)
				(arc
					(start 336.013298 -408.936444)
					(mid 336.035174 -408.933312)
					(end 336.055208 -408.923998)
				)
				(arc
					(start 336.348832 -408.731466)
					(mid 336.390488 -408.719064)
					(end 336.432144 -408.731466)
				)
				(arc
					(start 336.727038 -408.923998)
					(mid 336.746962 -408.933234)
					(end 336.768694 -408.936444)
				)
				(arc
					(start 336.963258 -408.936444)
					(mid 337.01714 -408.914126)
					(end 337.039458 -408.860244)
				)
				(arc
					(start 337.039458 -408.174444)
					(mid 337.01714 -408.120562)
					(end 336.963258 -408.098244)
				)
				(arc
					(start 336.768694 -408.098244)
					(mid 336.74695 -408.101412)
					(end 336.727038 -408.11069)
				)
				(arc
					(start 336.430874 -408.303476)
					(mid 336.38919 -408.315698)
					(end 336.347562 -408.303222)
				)
				(arc
					(start 336.053938 -408.11069)
					(mid 336.034014 -408.101454)
					(end 336.012282 -408.098244)
				)
				(arc
					(start 335.817718 -408.098244)
					(mid 335.763836 -408.120562)
					(end 335.741518 -408.174444)
				)
			)
		)
	)
	(zone
		(layer "In1.Cu")
		(hatch none 0.5)
		(connect_pads
			(clearance 0)
		)
		(min_thickness 0.25)
		(keepout
			(tracks not_allowed)
			(vias allowed)
			(pads allowed)
			(copperpour not_allowed)
			(footprints allowed)
		)
		(placement
			(enabled no)
			(sheetname "")
		)
		(fill
			(thermal_gap 0.5)
			(thermal_bridge_width 0.5)
			(island_removal_mode 0)
		)
		(polygon
			(pts
				(arc
					(start 29.286708 -17.966436)
					(mid 29.309026 -18.020318)
					(end 29.362908 -18.042636)
				)
				(arc
					(start 29.558488 -18.042636)
					(mid 29.580364 -18.039504)
					(end 29.600398 -18.03019)
				)
				(arc
					(start 29.894022 -17.837658)
					(mid 29.935678 -17.825256)
					(end 29.977334 -17.837658)
				)
				(arc
					(start 30.272228 -18.03019)
					(mid 30.292152 -18.039426)
					(end 30.313884 -18.042636)
				)
				(arc
					(start 30.508448 -18.042636)
					(mid 30.56233 -18.020318)
					(end 30.584648 -17.966436)
				)
				(arc
					(start 30.584648 -17.280636)
					(mid 30.56233 -17.226754)
					(end 30.508448 -17.204436)
				)
				(arc
					(start 30.313884 -17.204436)
					(mid 30.29214 -17.207604)
					(end 30.272228 -17.216882)
				)
				(arc
					(start 29.976064 -17.409668)
					(mid 29.93438 -17.42189)
					(end 29.892752 -17.409414)
				)
				(arc
					(start 29.599128 -17.216882)
					(mid 29.579204 -17.207646)
					(end 29.557472 -17.204436)
				)
				(arc
					(start 29.362908 -17.204436)
					(mid 29.309026 -17.226754)
					(end 29.286708 -17.280636)
				)
			)
		)
	)
	(zone
		(layer "In1.Cu")
		(hatch none 0.5)
		(connect_pads
			(clearance 0)
		)
		(min_thickness 0.25)
		(keepout
			(tracks not_allowed)
			(vias allowed)
			(pads allowed)
			(copperpour not_allowed)
			(footprints allowed)
		)
		(placement
			(enabled no)
			(sheetname "")
		)
		(fill
			(thermal_gap 0.5)
			(thermal_bridge_width 0.5)
			(island_removal_mode 0)
		)
		(polygon
			(pts
				(arc
					(start 432.074066 -17.955514)
					(mid 432.096384 -18.009396)
					(end 432.150266 -18.031714)
				)
				(arc
					(start 432.345846 -18.031714)
					(mid 432.367722 -18.028582)
					(end 432.387756 -18.019268)
				)
				(arc
					(start 432.68138 -17.826736)
					(mid 432.723036 -17.814334)
					(end 432.764692 -17.826736)
				)
				(arc
					(start 433.059586 -18.019268)
					(mid 433.07951 -18.028504)
					(end 433.101242 -18.031714)
				)
				(arc
					(start 433.295806 -18.031714)
					(mid 433.349688 -18.009396)
					(end 433.372006 -17.955514)
				)
				(arc
					(start 433.372006 -17.269714)
					(mid 433.349688 -17.215832)
					(end 433.295806 -17.193514)
				)
				(arc
					(start 433.101242 -17.193514)
					(mid 433.079498 -17.196682)
					(end 433.059586 -17.20596)
				)
				(arc
					(start 432.763422 -17.398746)
					(mid 432.721738 -17.410968)
					(end 432.68011 -17.398492)
				)
				(arc
					(start 432.386486 -17.20596)
					(mid 432.366562 -17.196724)
					(end 432.34483 -17.193514)
				)
				(arc
					(start 432.150266 -17.193514)
					(mid 432.096384 -17.215832)
					(end 432.074066 -17.269714)
				)
			)
		)
	)
	(zone
		(layer "In1.Cu")
		(hatch none 0.5)
		(connect_pads
			(clearance 0)
		)
		(min_thickness 0.25)
		(keepout
			(tracks not_allowed)
			(vias allowed)
			(pads allowed)
			(copperpour not_allowed)
			(footprints allowed)
		)
		(placement
			(enabled no)
			(sheetname "")
		)
		(fill
			(thermal_gap 0.5)
			(thermal_bridge_width 0.5)
			(island_removal_mode 0)
		)
		(polygon
			(pts
				(arc
					(start 415.27603 -17.955514)
					(mid 415.298348 -18.009396)
					(end 415.35223 -18.031714)
				)
				(arc
					(start 415.54781 -18.031714)
					(mid 415.569686 -18.028582)
					(end 415.58972 -18.019268)
				)
				(arc
					(start 415.883344 -17.826736)
					(mid 415.925 -17.814334)
					(end 415.966656 -17.826736)
				)
				(arc
					(start 416.26155 -18.019268)
					(mid 416.281474 -18.028504)
					(end 416.303206 -18.031714)
				)
				(arc
					(start 416.49777 -18.031714)
					(mid 416.551652 -18.009396)
					(end 416.57397 -17.955514)
				)
				(arc
					(start 416.57397 -17.269714)
					(mid 416.551652 -17.215832)
					(end 416.49777 -17.193514)
				)
				(arc
					(start 416.303206 -17.193514)
					(mid 416.281462 -17.196682)
					(end 416.26155 -17.20596)
				)
				(arc
					(start 415.965386 -17.398746)
					(mid 415.923702 -17.410968)
					(end 415.882074 -17.398492)
				)
				(arc
					(start 415.58845 -17.20596)
					(mid 415.568526 -17.196724)
					(end 415.546794 -17.193514)
				)
				(arc
					(start 415.35223 -17.193514)
					(mid 415.298348 -17.215832)
					(end 415.27603 -17.269714)
				)
			)
		)
	)
	(zone
		(layer "In1.Cu")
		(hatch none 0.5)
		(connect_pads
			(clearance 0)
		)
		(min_thickness 0.25)
		(keepout
			(tracks not_allowed)
			(vias allowed)
			(pads allowed)
			(copperpour not_allowed)
			(footprints allowed)
		)
		(placement
			(enabled no)
			(sheetname "")
		)
		(fill
			(thermal_gap 0.5)
			(thermal_bridge_width 0.5)
			(island_removal_mode 0)
		)
		(polygon
			(pts
				(arc
					(start 400.12112 -408.860244)
					(mid 400.143438 -408.914126)
					(end 400.19732 -408.936444)
				)
				(arc
					(start 400.3929 -408.936444)
					(mid 400.414776 -408.933312)
					(end 400.43481 -408.923998)
				)
				(arc
					(start 400.728434 -408.731466)
					(mid 400.77009 -408.719064)
					(end 400.811746 -408.731466)
				)
				(arc
					(start 401.10664 -408.923998)
					(mid 401.126564 -408.933234)
					(end 401.148296 -408.936444)
				)
				(arc
					(start 401.34286 -408.936444)
					(mid 401.396742 -408.914126)
					(end 401.41906 -408.860244)
				)
				(arc
					(start 401.41906 -408.174444)
					(mid 401.396742 -408.120562)
					(end 401.34286 -408.098244)
				)
				(arc
					(start 401.148296 -408.098244)
					(mid 401.126552 -408.101412)
					(end 401.10664 -408.11069)
				)
				(arc
					(start 400.810476 -408.303476)
					(mid 400.768792 -408.315698)
					(end 400.727164 -408.303222)
				)
				(arc
					(start 400.43354 -408.11069)
					(mid 400.413616 -408.101454)
					(end 400.391884 -408.098244)
				)
				(arc
					(start 400.19732 -408.098244)
					(mid 400.143438 -408.120562)
					(end 400.12112 -408.174444)
				)
			)
		)
	)
	(zone
		(layer "In1.Cu")
		(hatch none 0.5)
		(connect_pads
			(clearance 0)
		)
		(min_thickness 0.25)
		(keepout
			(tracks not_allowed)
			(vias allowed)
			(pads allowed)
			(copperpour not_allowed)
			(footprints allowed)
		)
		(placement
			(enabled no)
			(sheetname "")
		)
		(fill
			(thermal_gap 0.5)
			(thermal_bridge_width 0.5)
			(island_removal_mode 0)
		)
		(polygon
			(pts
				(arc
					(start 305.109118 -408.860244)
					(mid 305.131436 -408.914126)
					(end 305.185318 -408.936444)
				)
				(arc
					(start 305.380898 -408.936444)
					(mid 305.402774 -408.933312)
					(end 305.422808 -408.923998)
				)
				(arc
					(start 305.716432 -408.731466)
					(mid 305.758088 -408.719064)
					(end 305.799744 -408.731466)
				)
				(arc
					(start 306.094638 -408.923998)
					(mid 306.114562 -408.933234)
					(end 306.136294 -408.936444)
				)
				(arc
					(start 306.330858 -408.936444)
					(mid 306.38474 -408.914126)
					(end 306.407058 -408.860244)
				)
				(arc
					(start 306.407058 -408.174444)
					(mid 306.38474 -408.120562)
					(end 306.330858 -408.098244)
				)
				(arc
					(start 306.136294 -408.098244)
					(mid 306.11455 -408.101412)
					(end 306.094638 -408.11069)
				)
				(arc
					(start 305.798474 -408.303476)
					(mid 305.75679 -408.315698)
					(end 305.715162 -408.303222)
				)
				(arc
					(start 305.421538 -408.11069)
					(mid 305.401614 -408.101454)
					(end 305.379882 -408.098244)
				)
				(arc
					(start 305.185318 -408.098244)
					(mid 305.131436 -408.120562)
					(end 305.109118 -408.174444)
				)
			)
		)
	)
	(zone
		(layer "In1.Cu")
		(hatch none 0.5)
		(connect_pads
			(clearance 0)
		)
		(min_thickness 0.25)
		(keepout
			(tracks not_allowed)
			(vias allowed)
			(pads allowed)
			(copperpour not_allowed)
			(footprints allowed)
		)
		(placement
			(enabled no)
			(sheetname "")
		)
		(fill
			(thermal_gap 0.5)
			(thermal_bridge_width 0.5)
			(island_removal_mode 0)
		)
		(polygon
			(pts
				(arc
					(start 429.280066 -16.431514)
					(mid 429.302384 -16.485396)
					(end 429.356266 -16.507714)
				)
				(arc
					(start 429.551846 -16.507714)
					(mid 429.573722 -16.504582)
					(end 429.593756 -16.495268)
				)
				(arc
					(start 429.88738 -16.302736)
					(mid 429.929036 -16.290334)
					(end 429.970692 -16.302736)
				)
				(arc
					(start 430.265586 -16.495268)
					(mid 430.28551 -16.504504)
					(end 430.307242 -16.507714)
				)
				(arc
					(start 430.501806 -16.507714)
					(mid 430.555688 -16.485396)
					(end 430.578006 -16.431514)
				)
				(arc
					(start 430.578006 -15.745714)
					(mid 430.555688 -15.691832)
					(end 430.501806 -15.669514)
				)
				(arc
					(start 430.307242 -15.669514)
					(mid 430.285498 -15.672682)
					(end 430.265586 -15.68196)
				)
				(arc
					(start 429.969422 -15.874746)
					(mid 429.927738 -15.886968)
					(end 429.88611 -15.874492)
				)
				(arc
					(start 429.592486 -15.68196)
					(mid 429.572562 -15.672724)
					(end 429.55083 -15.669514)
				)
				(arc
					(start 429.356266 -15.669514)
					(mid 429.302384 -15.691832)
					(end 429.280066 -15.745714)
				)
			)
		)
	)
	(zone
		(layer "In1.Cu")
		(hatch none 0.5)
		(connect_pads
			(clearance 0)
		)
		(min_thickness 0.25)
		(keepout
			(tracks not_allowed)
			(vias allowed)
			(pads allowed)
			(copperpour not_allowed)
			(footprints allowed)
		)
		(placement
			(enabled no)
			(sheetname "")
		)
		(fill
			(thermal_gap 0.5)
			(thermal_bridge_width 0.5)
			(island_removal_mode 0)
		)
		(polygon
			(pts
				(arc
					(start 261.845044 -5.242306)
					(mid 261.822726 -5.296188)
					(end 261.768844 -5.318506)
				)
				(arc
					(start 261.156704 -5.318506)
					(mid 261.102822 -5.296188)
					(end 261.080504 -5.242306)
				)
				(arc
					(start 261.080504 -4.145026)
					(mid 261.102822 -4.091144)
					(end 261.156704 -4.068826)
				)
				(arc
					(start 261.768844 -4.068826)
					(mid 261.822726 -4.091144)
					(end 261.845044 -4.145026)
				)
			)
		)
	)
	(zone
		(layer "In1.Cu")
		(hatch none 0.5)
		(connect_pads
			(clearance 0)
		)
		(min_thickness 0.25)
		(keepout
			(tracks not_allowed)
			(vias allowed)
			(pads allowed)
			(copperpour not_allowed)
			(footprints allowed)
		)
		(placement
			(enabled no)
			(sheetname "")
		)
		(fill
			(thermal_gap 0.5)
			(thermal_bridge_width 0.5)
			(island_removal_mode 0)
		)
		(polygon
			(pts
				(arc
					(start 414.576006 -7.672324)
					(mid 414.553688 -7.618442)
					(end 414.499806 -7.596124)
				)
				(arc
					(start 413.218376 -7.596124)
					(mid 413.164494 -7.618442)
					(end 413.142176 -7.672324)
				)
				(arc
					(start 413.142176 -9.094724)
					(mid 413.164494 -9.148606)
					(end 413.218376 -9.170924)
				)
				(arc
					(start 414.499806 -9.170924)
					(mid 414.553688 -9.148606)
					(end 414.576006 -9.094724)
				)
			)
		)
	)
	(zone
		(layer "In1.Cu")
		(hatch none 0.5)
		(connect_pads
			(clearance 0)
		)
		(min_thickness 0.25)
		(keepout
			(tracks not_allowed)
			(vias allowed)
			(pads allowed)
			(copperpour not_allowed)
			(footprints allowed)
		)
		(placement
			(enabled no)
			(sheetname "")
		)
		(fill
			(thermal_gap 0.5)
			(thermal_bridge_width 0.5)
			(island_removal_mode 0)
		)
		(polygon
			(pts
				(arc
					(start 236.03458 -58.361326)
					(mid 235.980698 -58.339008)
					(end 235.95838 -58.285126)
				)
				(arc
					(start 235.95838 -57.457086)
					(mid 235.980698 -57.403204)
					(end 236.03458 -57.380886)
				)
				(arc
					(start 237.1598 -57.380886)
					(mid 237.213682 -57.403204)
					(end 237.236 -57.457086)
				)
				(arc
					(start 237.236 -58.285126)
					(mid 237.213682 -58.339008)
					(end 237.1598 -58.361326)
				)
			)
		)
	)
	(zone
		(layer "In1.Cu")
		(hatch none 0.5)
		(connect_pads
			(clearance 0)
		)
		(min_thickness 0.25)
		(keepout
			(tracks not_allowed)
			(vias allowed)
			(pads allowed)
			(copperpour not_allowed)
			(footprints allowed)
		)
		(placement
			(enabled no)
			(sheetname "")
		)
		(fill
			(thermal_gap 0.5)
			(thermal_bridge_width 0.5)
			(island_removal_mode 0)
		)
		(polygon
			(pts
				(arc
					(start 135.253984 -402.713952)
					(mid 135.276302 -402.767834)
					(end 135.330184 -402.790152)
				)
				(arc
					(start 135.525764 -402.790152)
					(mid 135.54764 -402.78702)
					(end 135.567674 -402.777706)
				)
				(arc
					(start 135.861298 -402.585174)
					(mid 135.902954 -402.572772)
					(end 135.94461 -402.585174)
				)
				(arc
					(start 136.239504 -402.777706)
					(mid 136.259428 -402.786942)
					(end 136.28116 -402.790152)
				)
				(arc
					(start 136.475724 -402.790152)
					(mid 136.529606 -402.767834)
					(end 136.551924 -402.713952)
				)
				(arc
					(start 136.551924 -402.028152)
					(mid 136.529606 -401.97427)
					(end 136.475724 -401.951952)
				)
				(arc
					(start 136.28116 -401.951952)
					(mid 136.259416 -401.95512)
					(end 136.239504 -401.964398)
				)
				(arc
					(start 135.94334 -402.157184)
					(mid 135.901656 -402.169406)
					(end 135.860028 -402.15693)
				)
				(arc
					(start 135.566404 -401.964398)
					(mid 135.54648 -401.955162)
					(end 135.524748 -401.951952)
				)
				(arc
					(start 135.330184 -401.951952)
					(mid 135.276302 -401.97427)
					(end 135.253984 -402.028152)
				)
			)
		)
	)
	(zone
		(layer "In1.Cu")
		(hatch none 0.5)
		(connect_pads
			(clearance 0)
		)
		(min_thickness 0.25)
		(keepout
			(tracks not_allowed)
			(vias allowed)
			(pads allowed)
			(copperpour not_allowed)
			(footprints allowed)
		)
		(placement
			(enabled no)
			(sheetname "")
		)
		(fill
			(thermal_gap 0.5)
			(thermal_bridge_width 0.5)
			(island_removal_mode 0)
		)
		(polygon
			(pts
				(arc
					(start 169.68597 -12.952222)
					(mid 169.663652 -12.89834)
					(end 169.60977 -12.876022)
				)
				(arc
					(start 168.32834 -12.876022)
					(mid 168.274458 -12.89834)
					(end 168.25214 -12.952222)
				)
				(arc
					(start 168.25214 -14.374622)
					(mid 168.274458 -14.428504)
					(end 168.32834 -14.450822)
				)
				(arc
					(start 169.60977 -14.450822)
					(mid 169.663652 -14.428504)
					(end 169.68597 -14.374622)
				)
			)
		)
	)
	(zone
		(layer "In1.Cu")
		(hatch none 0.5)
		(connect_pads
			(clearance 0)
		)
		(min_thickness 0.25)
		(keepout
			(tracks not_allowed)
			(vias allowed)
			(pads allowed)
			(copperpour not_allowed)
			(footprints allowed)
		)
		(placement
			(enabled no)
			(sheetname "")
		)
		(fill
			(thermal_gap 0.5)
			(thermal_bridge_width 0.5)
			(island_removal_mode 0)
		)
		(polygon
			(pts
				(arc
					(start 154.979624 -408.860244)
					(mid 155.001942 -408.914126)
					(end 155.055824 -408.936444)
				)
				(arc
					(start 155.251404 -408.936444)
					(mid 155.27328 -408.933312)
					(end 155.293314 -408.923998)
				)
				(arc
					(start 155.586938 -408.731466)
					(mid 155.628594 -408.719064)
					(end 155.67025 -408.731466)
				)
				(arc
					(start 155.965144 -408.923998)
					(mid 155.985068 -408.933234)
					(end 156.0068 -408.936444)
				)
				(arc
					(start 156.201364 -408.936444)
					(mid 156.255246 -408.914126)
					(end 156.277564 -408.860244)
				)
				(arc
					(start 156.277564 -408.174444)
					(mid 156.255246 -408.120562)
					(end 156.201364 -408.098244)
				)
				(arc
					(start 156.0068 -408.098244)
					(mid 155.985056 -408.101412)
					(end 155.965144 -408.11069)
				)
				(arc
					(start 155.66898 -408.303476)
					(mid 155.627296 -408.315698)
					(end 155.585668 -408.303222)
				)
				(arc
					(start 155.292044 -408.11069)
					(mid 155.27212 -408.101454)
					(end 155.250388 -408.098244)
				)
				(arc
					(start 155.055824 -408.098244)
					(mid 155.001942 -408.120562)
					(end 154.979624 -408.174444)
				)
			)
		)
	)
	(zone
		(layer "In1.Cu")
		(hatch none 0.5)
		(connect_pads
			(clearance 0)
		)
		(min_thickness 0.25)
		(keepout
			(tracks not_allowed)
			(vias allowed)
			(pads allowed)
			(copperpour not_allowed)
			(footprints allowed)
		)
		(placement
			(enabled no)
			(sheetname "")
		)
		(fill
			(thermal_gap 0.5)
			(thermal_bridge_width 0.5)
			(island_removal_mode 0)
		)
		(polygon
			(pts
				(arc
					(start 34.874708 -17.966436)
					(mid 34.897026 -18.020318)
					(end 34.950908 -18.042636)
				)
				(arc
					(start 35.146488 -18.042636)
					(mid 35.168364 -18.039504)
					(end 35.188398 -18.03019)
				)
				(arc
					(start 35.482022 -17.837658)
					(mid 35.523678 -17.825256)
					(end 35.565334 -17.837658)
				)
				(arc
					(start 35.860228 -18.03019)
					(mid 35.880152 -18.039426)
					(end 35.901884 -18.042636)
				)
				(arc
					(start 36.096448 -18.042636)
					(mid 36.15033 -18.020318)
					(end 36.172648 -17.966436)
				)
				(arc
					(start 36.172648 -17.280636)
					(mid 36.15033 -17.226754)
					(end 36.096448 -17.204436)
				)
				(arc
					(start 35.901884 -17.204436)
					(mid 35.88014 -17.207604)
					(end 35.860228 -17.216882)
				)
				(arc
					(start 35.564064 -17.409668)
					(mid 35.52238 -17.42189)
					(end 35.480752 -17.409414)
				)
				(arc
					(start 35.187128 -17.216882)
					(mid 35.167204 -17.207646)
					(end 35.145472 -17.204436)
				)
				(arc
					(start 34.950908 -17.204436)
					(mid 34.897026 -17.226754)
					(end 34.874708 -17.280636)
				)
			)
		)
	)
	(zone
		(layer "In1.Cu")
		(hatch none 0.5)
		(connect_pads
			(clearance 0)
		)
		(min_thickness 0.25)
		(keepout
			(tracks not_allowed)
			(vias allowed)
			(pads allowed)
			(copperpour not_allowed)
			(footprints allowed)
		)
		(placement
			(enabled no)
			(sheetname "")
		)
		(fill
			(thermal_gap 0.5)
			(thermal_bridge_width 0.5)
			(island_removal_mode 0)
		)
		(polygon
			(pts
				(xy 391.651744 -9.044432) (xy 391.651744 -7.601712) (xy 392.642344 -7.601712) (xy 392.642344 -9.044432)
			)
		)
	)
	(zone
		(layer "In1.Cu")
		(hatch none 0.5)
		(connect_pads
			(clearance 0)
		)
		(min_thickness 0.25)
		(keepout
			(tracks not_allowed)
			(vias allowed)
			(pads allowed)
			(copperpour not_allowed)
			(footprints allowed)
		)
		(placement
			(enabled no)
			(sheetname "")
		)
		(fill
			(thermal_gap 0.5)
			(thermal_bridge_width 0.5)
			(island_removal_mode 0)
		)
		(polygon
			(pts
				(arc
					(start 156.696664 -402.713952)
					(mid 156.718982 -402.767834)
					(end 156.772864 -402.790152)
				)
				(arc
					(start 156.968444 -402.790152)
					(mid 156.99032 -402.78702)
					(end 157.010354 -402.777706)
				)
				(arc
					(start 157.303978 -402.585174)
					(mid 157.345634 -402.572772)
					(end 157.38729 -402.585174)
				)
				(arc
					(start 157.682184 -402.777706)
					(mid 157.702108 -402.786942)
					(end 157.72384 -402.790152)
				)
				(arc
					(start 157.918404 -402.790152)
					(mid 157.972286 -402.767834)
					(end 157.994604 -402.713952)
				)
				(arc
					(start 157.994604 -402.028152)
					(mid 157.972286 -401.97427)
					(end 157.918404 -401.951952)
				)
				(arc
					(start 157.72384 -401.951952)
					(mid 157.702096 -401.95512)
					(end 157.682184 -401.964398)
				)
				(arc
					(start 157.38602 -402.157184)
					(mid 157.344336 -402.169406)
					(end 157.302708 -402.15693)
				)
				(arc
					(start 157.009084 -401.964398)
					(mid 156.98916 -401.955162)
					(end 156.967428 -401.951952)
				)
				(arc
					(start 156.772864 -401.951952)
					(mid 156.718982 -401.97427)
					(end 156.696664 -402.028152)
				)
			)
		)
	)
	(zone
		(layer "In1.Cu")
		(hatch none 0.5)
		(connect_pads
			(clearance 0)
		)
		(min_thickness 0.25)
		(keepout
			(tracks not_allowed)
			(vias allowed)
			(pads allowed)
			(copperpour not_allowed)
			(footprints allowed)
		)
		(placement
			(enabled no)
			(sheetname "")
		)
		(fill
			(thermal_gap 0.5)
			(thermal_bridge_width 0.5)
			(island_removal_mode 0)
		)
		(polygon
			(pts
				(arc
					(start 424.347894 -11.91768)
					(mid 424.370212 -11.971562)
					(end 424.424094 -11.99388)
				)
				(arc
					(start 425.705524 -11.99388)
					(mid 425.759406 -11.971562)
					(end 425.781724 -11.91768)
				)
				(arc
					(start 425.781724 -10.49528)
					(mid 425.759406 -10.441398)
					(end 425.705524 -10.41908)
				)
				(arc
					(start 424.424094 -10.41908)
					(mid 424.370212 -10.441398)
					(end 424.347894 -10.49528)
				)
			)
		)
	)
	(zone
		(layer "In1.Cu")
		(hatch none 0.5)
		(connect_pads
			(clearance 0)
		)
		(min_thickness 0.25)
		(keepout
			(tracks not_allowed)
			(vias allowed)
			(pads allowed)
			(copperpour not_allowed)
			(footprints allowed)
		)
		(placement
			(enabled no)
			(sheetname "")
		)
		(fill
			(thermal_gap 0.5)
			(thermal_bridge_width 0.5)
			(island_removal_mode 0)
		)
		(polygon
			(pts
				(arc
					(start 405.827738 -11.91768)
					(mid 405.850056 -11.971562)
					(end 405.903938 -11.99388)
				)
				(arc
					(start 407.185368 -11.99388)
					(mid 407.23925 -11.971562)
					(end 407.261568 -11.91768)
				)
				(arc
					(start 407.261568 -10.49528)
					(mid 407.23925 -10.441398)
					(end 407.185368 -10.41908)
				)
				(arc
					(start 405.903938 -10.41908)
					(mid 405.850056 -10.441398)
					(end 405.827738 -10.49528)
				)
			)
		)
	)
	(zone
		(layer "In1.Cu")
		(hatch none 0.5)
		(connect_pads
			(clearance 0)
		)
		(min_thickness 0.25)
		(keepout
			(tracks not_allowed)
			(vias allowed)
			(pads allowed)
			(copperpour not_allowed)
			(footprints allowed)
		)
		(placement
			(enabled no)
			(sheetname "")
		)
		(fill
			(thermal_gap 0.5)
			(thermal_bridge_width 0.5)
			(island_removal_mode 0)
		)
		(polygon
			(pts
				(arc
					(start 23.698708 -17.966436)
					(mid 23.721026 -18.020318)
					(end 23.774908 -18.042636)
				)
				(arc
					(start 23.970488 -18.042636)
					(mid 23.992364 -18.039504)
					(end 24.012398 -18.03019)
				)
				(arc
					(start 24.306022 -17.837658)
					(mid 24.347678 -17.825256)
					(end 24.389334 -17.837658)
				)
				(arc
					(start 24.684228 -18.03019)
					(mid 24.704152 -18.039426)
					(end 24.725884 -18.042636)
				)
				(arc
					(start 24.920448 -18.042636)
					(mid 24.97433 -18.020318)
					(end 24.996648 -17.966436)
				)
				(arc
					(start 24.996648 -17.280636)
					(mid 24.97433 -17.226754)
					(end 24.920448 -17.204436)
				)
				(arc
					(start 24.725884 -17.204436)
					(mid 24.70414 -17.207604)
					(end 24.684228 -17.216882)
				)
				(arc
					(start 24.388064 -17.409668)
					(mid 24.34638 -17.42189)
					(end 24.304752 -17.409414)
				)
				(arc
					(start 24.011128 -17.216882)
					(mid 23.991204 -17.207646)
					(end 23.969472 -17.204436)
				)
				(arc
					(start 23.774908 -17.204436)
					(mid 23.721026 -17.226754)
					(end 23.698708 -17.280636)
				)
			)
		)
	)
	(zone
		(layer "In1.Cu")
		(hatch none 0.5)
		(connect_pads
			(clearance 0)
		)
		(min_thickness 0.25)
		(keepout
			(tracks not_allowed)
			(vias allowed)
			(pads allowed)
			(copperpour not_allowed)
			(footprints allowed)
		)
		(placement
			(enabled no)
			(sheetname "")
		)
		(fill
			(thermal_gap 0.5)
			(thermal_bridge_width 0.5)
			(island_removal_mode 0)
		)
		(polygon
			(pts
				(arc
					(start 398.206214 -17.955514)
					(mid 398.228532 -18.009396)
					(end 398.282414 -18.031714)
				)
				(arc
					(start 398.477994 -18.031714)
					(mid 398.49987 -18.028582)
					(end 398.519904 -18.019268)
				)
				(arc
					(start 398.813528 -17.826736)
					(mid 398.855184 -17.814334)
					(end 398.89684 -17.826736)
				)
				(arc
					(start 399.191734 -18.019268)
					(mid 399.211658 -18.028504)
					(end 399.23339 -18.031714)
				)
				(arc
					(start 399.427954 -18.031714)
					(mid 399.481836 -18.009396)
					(end 399.504154 -17.955514)
				)
				(arc
					(start 399.504154 -17.269714)
					(mid 399.481836 -17.215832)
					(end 399.427954 -17.193514)
				)
				(arc
					(start 399.23339 -17.193514)
					(mid 399.211646 -17.196682)
					(end 399.191734 -17.20596)
				)
				(arc
					(start 398.89557 -17.398746)
					(mid 398.853886 -17.410968)
					(end 398.812258 -17.398492)
				)
				(arc
					(start 398.518634 -17.20596)
					(mid 398.49871 -17.196724)
					(end 398.476978 -17.193514)
				)
				(arc
					(start 398.282414 -17.193514)
					(mid 398.228532 -17.215832)
					(end 398.206214 -17.269714)
				)
			)
		)
	)
	(zone
		(layer "In1.Cu")
		(hatch none 0.5)
		(connect_pads
			(clearance 0)
		)
		(min_thickness 0.25)
		(keepout
			(tracks not_allowed)
			(vias allowed)
			(pads allowed)
			(copperpour not_allowed)
			(footprints allowed)
		)
		(placement
			(enabled no)
			(sheetname "")
		)
		(fill
			(thermal_gap 0.5)
			(thermal_bridge_width 0.5)
			(island_removal_mode 0)
		)
		(polygon
			(pts
				(arc
					(start 131.727702 -17.197578)
					(mid 131.75002 -17.25146)
					(end 131.803902 -17.273778)
				)
				(arc
					(start 133.085332 -17.273778)
					(mid 133.139214 -17.25146)
					(end 133.161532 -17.197578)
				)
				(arc
					(start 133.161532 -15.775178)
					(mid 133.139214 -15.721296)
					(end 133.085332 -15.698978)
				)
				(arc
					(start 131.803902 -15.698978)
					(mid 131.75002 -15.721296)
					(end 131.727702 -15.775178)
				)
			)
		)
	)
	(zone
		(layer "In1.Cu")
		(hatch none 0.5)
		(connect_pads
			(clearance 0)
		)
		(min_thickness 0.25)
		(keepout
			(tracks not_allowed)
			(vias allowed)
			(pads allowed)
			(copperpour not_allowed)
			(footprints allowed)
		)
		(placement
			(enabled no)
			(sheetname "")
		)
		(fill
			(thermal_gap 0.5)
			(thermal_bridge_width 0.5)
			(island_removal_mode 0)
		)
		(polygon
			(pts
				(arc
					(start 397.05788 -408.860244)
					(mid 397.080198 -408.914126)
					(end 397.13408 -408.936444)
				)
				(arc
					(start 397.32966 -408.936444)
					(mid 397.351536 -408.933312)
					(end 397.37157 -408.923998)
				)
				(arc
					(start 397.665194 -408.731466)
					(mid 397.70685 -408.719064)
					(end 397.748506 -408.731466)
				)
				(arc
					(start 398.0434 -408.923998)
					(mid 398.063324 -408.933234)
					(end 398.085056 -408.936444)
				)
				(arc
					(start 398.27962 -408.936444)
					(mid 398.333502 -408.914126)
					(end 398.35582 -408.860244)
				)
				(arc
					(start 398.35582 -408.174444)
					(mid 398.333502 -408.120562)
					(end 398.27962 -408.098244)
				)
				(arc
					(start 398.085056 -408.098244)
					(mid 398.063312 -408.101412)
					(end 398.0434 -408.11069)
				)
				(arc
					(start 397.747236 -408.303476)
					(mid 397.705552 -408.315698)
					(end 397.663924 -408.303222)
				)
				(arc
					(start 397.3703 -408.11069)
					(mid 397.350376 -408.101454)
					(end 397.328644 -408.098244)
				)
				(arc
					(start 397.13408 -408.098244)
					(mid 397.080198 -408.120562)
					(end 397.05788 -408.174444)
				)
			)
		)
	)
	(zone
		(layer "In1.Cu")
		(hatch none 0.5)
		(connect_pads
			(clearance 0)
		)
		(min_thickness 0.25)
		(keepout
			(tracks not_allowed)
			(vias allowed)
			(pads allowed)
			(copperpour not_allowed)
			(footprints allowed)
		)
		(placement
			(enabled no)
			(sheetname "")
		)
		(fill
			(thermal_gap 0.5)
			(thermal_bridge_width 0.5)
			(island_removal_mode 0)
		)
		(polygon
			(pts
				(arc
					(start 17.80921 -106.166666)
					(mid 17.848251 -106.158909)
					(end 17.881092 -106.13644)
				)
				(arc
					(start 17.881092 -106.13644)
					(mid 17.901134 -106.105752)
					(end 17.908778 -106.069892)
				)
				(xy 17.908778 -105.927652) (xy 17.908524 -105.927652)
				(arc
					(start 17.908524 -105.000298)
					(mid 17.879334 -104.936792)
					(end 17.815306 -104.908858)
				)
				(arc
					(start 17.508474 -104.908858)
					(mid 17.469433 -104.916615)
					(end 17.436592 -104.939084)
				)
				(arc
					(start 17.436592 -104.939084)
					(mid 17.41655 -104.969772)
					(end 17.408906 -105.005632)
				)
				(xy 17.408906 -106.036872) (xy 17.40916 -106.036872)
				(arc
					(start 17.40916 -106.075226)
					(mid 17.43835 -106.138732)
					(end 17.502378 -106.166666)
				)
			)
		)
	)
	(zone
		(layer "In1.Cu")
		(hatch none 0.5)
		(connect_pads
			(clearance 0)
		)
		(min_thickness 0.25)
		(keepout
			(tracks not_allowed)
			(vias allowed)
			(pads allowed)
			(copperpour not_allowed)
			(footprints allowed)
		)
		(placement
			(enabled no)
			(sheetname "")
		)
		(fill
			(thermal_gap 0.5)
			(thermal_bridge_width 0.5)
			(island_removal_mode 0)
		)
		(polygon
			(pts
				(arc
					(start 416.7378 -11.91768)
					(mid 416.760118 -11.971562)
					(end 416.814 -11.99388)
				)
				(arc
					(start 418.09543 -11.99388)
					(mid 418.149312 -11.971562)
					(end 418.17163 -11.91768)
				)
				(arc
					(start 418.17163 -10.49528)
					(mid 418.149312 -10.441398)
					(end 418.09543 -10.41908)
				)
				(arc
					(start 416.814 -10.41908)
					(mid 416.760118 -10.441398)
					(end 416.7378 -10.49528)
				)
			)
		)
	)
	(zone
		(layer "In1.Cu")
		(hatch none 0.5)
		(connect_pads
			(clearance 0)
		)
		(min_thickness 0.25)
		(keepout
			(tracks not_allowed)
			(vias allowed)
			(pads allowed)
			(copperpour not_allowed)
			(footprints allowed)
		)
		(placement
			(enabled no)
			(sheetname "")
		)
		(fill
			(thermal_gap 0.5)
			(thermal_bridge_width 0.5)
			(island_removal_mode 0)
		)
		(polygon
			(pts
				(arc
					(start 19.348958 -386.494528)
					(mid 19.387999 -386.486771)
					(end 19.42084 -386.464302)
				)
				(arc
					(start 19.42084 -386.464302)
					(mid 19.440882 -386.433614)
					(end 19.448526 -386.397754)
				)
				(xy 19.448526 -386.255514) (xy 19.448272 -386.255514)
				(arc
					(start 19.448272 -385.32816)
					(mid 19.419082 -385.264654)
					(end 19.355054 -385.23672)
				)
				(arc
					(start 19.048222 -385.23672)
					(mid 19.009181 -385.244477)
					(end 18.97634 -385.266946)
				)
				(arc
					(start 18.97634 -385.266946)
					(mid 18.956298 -385.297634)
					(end 18.948654 -385.333494)
				)
				(xy 18.948654 -386.364734) (xy 18.948908 -386.364734)
				(arc
					(start 18.948908 -386.403088)
					(mid 18.978098 -386.466594)
					(end 19.042126 -386.494528)
				)
			)
		)
	)
	(zone
		(layer "In1.Cu")
		(hatch none 0.5)
		(connect_pads
			(clearance 0)
		)
		(min_thickness 0.25)
		(keepout
			(tracks not_allowed)
			(vias allowed)
			(pads allowed)
			(copperpour not_allowed)
			(footprints allowed)
		)
		(placement
			(enabled no)
			(sheetname "")
		)
		(fill
			(thermal_gap 0.5)
			(thermal_bridge_width 0.5)
			(island_removal_mode 0)
		)
		(polygon
			(pts
				(arc
					(start 418.537898 -11.91768)
					(mid 418.560216 -11.971562)
					(end 418.614098 -11.99388)
				)
				(arc
					(start 419.895528 -11.99388)
					(mid 419.94941 -11.971562)
					(end 419.971728 -11.91768)
				)
				(arc
					(start 419.971728 -10.49528)
					(mid 419.94941 -10.441398)
					(end 419.895528 -10.41908)
				)
				(arc
					(start 418.614098 -10.41908)
					(mid 418.560216 -10.441398)
					(end 418.537898 -10.49528)
				)
			)
		)
	)
	(zone
		(layer "In1.Cu")
		(hatch none 0.5)
		(connect_pads
			(clearance 0)
		)
		(min_thickness 0.25)
		(keepout
			(tracks not_allowed)
			(vias allowed)
			(pads allowed)
			(copperpour not_allowed)
			(footprints allowed)
		)
		(placement
			(enabled no)
			(sheetname "")
		)
		(fill
			(thermal_gap 0.5)
			(thermal_bridge_width 0.5)
			(island_removal_mode 0)
		)
		(polygon
			(pts
				(xy 13.92682 -101.915468) (xy 13.92682 -101.183948) (xy 14.69136 -101.183948) (xy 14.69136 -101.915468)
			)
		)
	)
	(zone
		(layer "In1.Cu")
		(hatch none 0.5)
		(connect_pads
			(clearance 0)
		)
		(min_thickness 0.25)
		(keepout
			(tracks not_allowed)
			(vias allowed)
			(pads allowed)
			(copperpour not_allowed)
			(footprints allowed)
		)
		(placement
			(enabled no)
			(sheetname "")
		)
		(fill
			(thermal_gap 0.5)
			(thermal_bridge_width 0.5)
			(island_removal_mode 0)
		)
		(polygon
			(pts
				(xy 186.07532 -17.269968) (xy 186.07532 -15.834868) (xy 187.0583 -15.834868) (xy 187.0583 -17.269968)
			)
		)
	)
	(zone
		(layer "In1.Cu")
		(hatch none 0.5)
		(connect_pads
			(clearance 0)
		)
		(min_thickness 0.25)
		(keepout
			(tracks not_allowed)
			(vias allowed)
			(pads allowed)
			(copperpour not_allowed)
			(footprints allowed)
		)
		(placement
			(enabled no)
			(sheetname "")
		)
		(fill
			(thermal_gap 0.5)
			(thermal_bridge_width 0.5)
			(island_removal_mode 0)
		)
		(polygon
			(pts
				(arc
					(start 60.015628 -402.713952)
					(mid 60.037946 -402.767834)
					(end 60.091828 -402.790152)
				)
				(arc
					(start 60.287408 -402.790152)
					(mid 60.309284 -402.78702)
					(end 60.329318 -402.777706)
				)
				(arc
					(start 60.622942 -402.585174)
					(mid 60.664598 -402.572772)
					(end 60.706254 -402.585174)
				)
				(arc
					(start 61.001148 -402.777706)
					(mid 61.021072 -402.786942)
					(end 61.042804 -402.790152)
				)
				(arc
					(start 61.237368 -402.790152)
					(mid 61.29125 -402.767834)
					(end 61.313568 -402.713952)
				)
				(arc
					(start 61.313568 -402.028152)
					(mid 61.29125 -401.97427)
					(end 61.237368 -401.951952)
				)
				(arc
					(start 61.042804 -401.951952)
					(mid 61.02106 -401.95512)
					(end 61.001148 -401.964398)
				)
				(arc
					(start 60.704984 -402.157184)
					(mid 60.6633 -402.169406)
					(end 60.621672 -402.15693)
				)
				(arc
					(start 60.328048 -401.964398)
					(mid 60.308124 -401.955162)
					(end 60.286392 -401.951952)
				)
				(arc
					(start 60.091828 -401.951952)
					(mid 60.037946 -401.97427)
					(end 60.015628 -402.028152)
				)
			)
		)
	)
	(zone
		(layer "In1.Cu")
		(hatch none 0.5)
		(connect_pads
			(clearance 0)
		)
		(min_thickness 0.25)
		(keepout
			(tracks not_allowed)
			(vias allowed)
			(pads allowed)
			(copperpour not_allowed)
			(footprints allowed)
		)
		(placement
			(enabled no)
			(sheetname "")
		)
		(fill
			(thermal_gap 0.5)
			(thermal_bridge_width 0.5)
			(island_removal_mode 0)
		)
		(polygon
			(pts
				(arc
					(start 20.635976 -386.495798)
					(mid 20.675017 -386.488041)
					(end 20.707858 -386.465572)
				)
				(arc
					(start 20.707858 -386.465572)
					(mid 20.7279 -386.434884)
					(end 20.735544 -386.399024)
				)
				(xy 20.735544 -386.256784) (xy 20.73529 -386.256784)
				(arc
					(start 20.73529 -385.32943)
					(mid 20.7061 -385.265924)
					(end 20.642072 -385.23799)
				)
				(arc
					(start 20.33524 -385.23799)
					(mid 20.296199 -385.245747)
					(end 20.263358 -385.268216)
				)
				(arc
					(start 20.263358 -385.268216)
					(mid 20.243316 -385.298904)
					(end 20.235672 -385.334764)
				)
				(xy 20.235672 -386.366004) (xy 20.235926 -386.366004)
				(arc
					(start 20.235926 -386.404358)
					(mid 20.265116 -386.467864)
					(end 20.329144 -386.495798)
				)
			)
		)
	)
	(zone
		(layer "In1.Cu")
		(hatch none 0.5)
		(connect_pads
			(clearance 0)
		)
		(min_thickness 0.25)
		(keepout
			(tracks not_allowed)
			(vias allowed)
			(pads allowed)
			(copperpour not_allowed)
			(footprints allowed)
		)
		(placement
			(enabled no)
			(sheetname "")
		)
		(fill
			(thermal_gap 0.5)
			(thermal_bridge_width 0.5)
			(island_removal_mode 0)
		)
		(polygon
			(pts
				(arc
					(start 127.410464 -408.860244)
					(mid 127.432782 -408.914126)
					(end 127.486664 -408.936444)
				)
				(arc
					(start 127.682244 -408.936444)
					(mid 127.70412 -408.933312)
					(end 127.724154 -408.923998)
				)
				(arc
					(start 128.017778 -408.731466)
					(mid 128.059434 -408.719064)
					(end 128.10109 -408.731466)
				)
				(arc
					(start 128.395984 -408.923998)
					(mid 128.415908 -408.933234)
					(end 128.43764 -408.936444)
				)
				(arc
					(start 128.632204 -408.936444)
					(mid 128.686086 -408.914126)
					(end 128.708404 -408.860244)
				)
				(arc
					(start 128.708404 -408.174444)
					(mid 128.686086 -408.120562)
					(end 128.632204 -408.098244)
				)
				(arc
					(start 128.43764 -408.098244)
					(mid 128.415896 -408.101412)
					(end 128.395984 -408.11069)
				)
				(arc
					(start 128.09982 -408.303476)
					(mid 128.058136 -408.315698)
					(end 128.016508 -408.303222)
				)
				(arc
					(start 127.722884 -408.11069)
					(mid 127.70296 -408.101454)
					(end 127.681228 -408.098244)
				)
				(arc
					(start 127.486664 -408.098244)
					(mid 127.432782 -408.120562)
					(end 127.410464 -408.174444)
				)
			)
		)
	)
	(zone
		(layer "In1.Cu")
		(hatch none 0.5)
		(connect_pads
			(clearance 0)
		)
		(min_thickness 0.25)
		(keepout
			(tracks not_allowed)
			(vias allowed)
			(pads allowed)
			(copperpour not_allowed)
			(footprints allowed)
		)
		(placement
			(enabled no)
			(sheetname "")
		)
		(fill
			(thermal_gap 0.5)
			(thermal_bridge_width 0.5)
			(island_removal_mode 0)
		)
		(polygon
			(pts
				(arc
					(start 387.412484 -14.882114)
					(mid 387.451525 -14.874357)
					(end 387.484366 -14.851888)
				)
				(arc
					(start 387.484366 -14.851888)
					(mid 387.504408 -14.8212)
					(end 387.512052 -14.78534)
				)
				(xy 387.512052 -14.6431) (xy 387.511798 -14.6431)
				(arc
					(start 387.511798 -13.715746)
					(mid 387.482608 -13.65224)
					(end 387.41858 -13.624306)
				)
				(arc
					(start 387.111748 -13.624306)
					(mid 387.072707 -13.632063)
					(end 387.039866 -13.654532)
				)
				(arc
					(start 387.039866 -13.654532)
					(mid 387.019824 -13.68522)
					(end 387.01218 -13.72108)
				)
				(xy 387.01218 -14.75232) (xy 387.012434 -14.75232)
				(arc
					(start 387.012434 -14.790674)
					(mid 387.041624 -14.85418)
					(end 387.105652 -14.882114)
				)
			)
		)
	)
	(zone
		(layer "In1.Cu")
		(hatch none 0.5)
		(connect_pads
			(clearance 0)
		)
		(min_thickness 0.25)
		(keepout
			(tracks not_allowed)
			(vias allowed)
			(pads allowed)
			(copperpour not_allowed)
			(footprints allowed)
		)
		(placement
			(enabled no)
			(sheetname "")
		)
		(fill
			(thermal_gap 0.5)
			(thermal_bridge_width 0.5)
			(island_removal_mode 0)
		)
		(polygon
			(pts
				(arc
					(start 41.877234 -7.672324)
					(mid 41.854916 -7.618442)
					(end 41.801034 -7.596124)
				)
				(arc
					(start 40.519604 -7.596124)
					(mid 40.465722 -7.618442)
					(end 40.443404 -7.672324)
				)
				(arc
					(start 40.443404 -9.094724)
					(mid 40.465722 -9.148606)
					(end 40.519604 -9.170924)
				)
				(arc
					(start 41.801034 -9.170924)
					(mid 41.854916 -9.148606)
					(end 41.877234 -9.094724)
				)
			)
		)
	)
	(zone
		(layer "In1.Cu")
		(hatch none 0.5)
		(connect_pads
			(clearance 0)
		)
		(min_thickness 0.25)
		(keepout
			(tracks not_allowed)
			(vias allowed)
			(pads allowed)
			(copperpour not_allowed)
			(footprints allowed)
		)
		(placement
			(enabled no)
			(sheetname "")
		)
		(fill
			(thermal_gap 0.5)
			(thermal_bridge_width 0.5)
			(island_removal_mode 0)
		)
		(polygon
			(pts
				(arc
					(start 20.33524 -384.43789)
					(mid 20.296199 -384.445647)
					(end 20.263358 -384.468116)
				)
				(arc
					(start 20.263358 -384.468116)
					(mid 20.243316 -384.498804)
					(end 20.235672 -384.534664)
				)
				(xy 20.235672 -384.676904) (xy 20.235926 -384.676904)
				(arc
					(start 20.235926 -385.604258)
					(mid 20.265116 -385.667764)
					(end 20.329144 -385.695698)
				)
				(arc
					(start 20.635976 -385.695698)
					(mid 20.675017 -385.687941)
					(end 20.707858 -385.665472)
				)
				(arc
					(start 20.707858 -385.665472)
					(mid 20.7279 -385.634784)
					(end 20.735544 -385.598924)
				)
				(xy 20.735544 -384.567684) (xy 20.73529 -384.567684)
				(arc
					(start 20.73529 -384.52933)
					(mid 20.7061 -384.465824)
					(end 20.642072 -384.43789)
				)
			)
		)
	)
	(zone
		(layer "In1.Cu")
		(hatch none 0.5)
		(connect_pads
			(clearance 0)
		)
		(min_thickness 0.25)
		(keepout
			(tracks not_allowed)
			(vias allowed)
			(pads allowed)
			(copperpour not_allowed)
			(footprints allowed)
		)
		(placement
			(enabled no)
			(sheetname "")
		)
		(fill
			(thermal_gap 0.5)
			(thermal_bridge_width 0.5)
			(island_removal_mode 0)
		)
		(polygon
			(pts
				(arc
					(start 76.678028 -408.860244)
					(mid 76.700346 -408.914126)
					(end 76.754228 -408.936444)
				)
				(arc
					(start 76.949808 -408.936444)
					(mid 76.971684 -408.933312)
					(end 76.991718 -408.923998)
				)
				(arc
					(start 77.285342 -408.731466)
					(mid 77.326998 -408.719064)
					(end 77.368654 -408.731466)
				)
				(arc
					(start 77.663548 -408.923998)
					(mid 77.683472 -408.933234)
					(end 77.705204 -408.936444)
				)
				(arc
					(start 77.899768 -408.936444)
					(mid 77.95365 -408.914126)
					(end 77.975968 -408.860244)
				)
				(arc
					(start 77.975968 -408.174444)
					(mid 77.95365 -408.120562)
					(end 77.899768 -408.098244)
				)
				(arc
					(start 77.705204 -408.098244)
					(mid 77.68346 -408.101412)
					(end 77.663548 -408.11069)
				)
				(arc
					(start 77.367384 -408.303476)
					(mid 77.3257 -408.315698)
					(end 77.284072 -408.303222)
				)
				(arc
					(start 76.990448 -408.11069)
					(mid 76.970524 -408.101454)
					(end 76.948792 -408.098244)
				)
				(arc
					(start 76.754228 -408.098244)
					(mid 76.700346 -408.120562)
					(end 76.678028 -408.174444)
				)
			)
		)
	)
	(zone
		(layer "In1.Cu")
		(hatch none 0.5)
		(connect_pads
			(clearance 0)
		)
		(min_thickness 0.25)
		(keepout
			(tracks not_allowed)
			(vias allowed)
			(pads allowed)
			(copperpour not_allowed)
			(footprints allowed)
		)
		(placement
			(enabled no)
			(sheetname "")
		)
		(fill
			(thermal_gap 0.5)
			(thermal_bridge_width 0.5)
			(island_removal_mode 0)
		)
		(polygon
			(pts
				(arc
					(start 303.762918 -402.713952)
					(mid 303.785236 -402.767834)
					(end 303.839118 -402.790152)
				)
				(arc
					(start 304.034698 -402.790152)
					(mid 304.056574 -402.78702)
					(end 304.076608 -402.777706)
				)
				(arc
					(start 304.370232 -402.585174)
					(mid 304.411888 -402.572772)
					(end 304.453544 -402.585174)
				)
				(arc
					(start 304.748438 -402.777706)
					(mid 304.768362 -402.786942)
					(end 304.790094 -402.790152)
				)
				(arc
					(start 304.984658 -402.790152)
					(mid 305.03854 -402.767834)
					(end 305.060858 -402.713952)
				)
				(arc
					(start 305.060858 -402.028152)
					(mid 305.03854 -401.97427)
					(end 304.984658 -401.951952)
				)
				(arc
					(start 304.790094 -401.951952)
					(mid 304.76835 -401.95512)
					(end 304.748438 -401.964398)
				)
				(arc
					(start 304.452274 -402.157184)
					(mid 304.41059 -402.169406)
					(end 304.368962 -402.15693)
				)
				(arc
					(start 304.075338 -401.964398)
					(mid 304.055414 -401.955162)
					(end 304.033682 -401.951952)
				)
				(arc
					(start 303.839118 -401.951952)
					(mid 303.785236 -401.97427)
					(end 303.762918 -402.028152)
				)
			)
		)
	)
	(zone
		(layer "In1.Cu")
		(hatch none 0.5)
		(connect_pads
			(clearance 0)
		)
		(min_thickness 0.25)
		(keepout
			(tracks not_allowed)
			(vias allowed)
			(pads allowed)
			(copperpour not_allowed)
			(footprints allowed)
		)
		(placement
			(enabled no)
			(sheetname "")
		)
		(fill
			(thermal_gap 0.5)
			(thermal_bridge_width 0.5)
			(island_removal_mode 0)
		)
		(polygon
			(pts
				(arc
					(start 380.39548 -402.713952)
					(mid 380.417798 -402.767834)
					(end 380.47168 -402.790152)
				)
				(arc
					(start 380.66726 -402.790152)
					(mid 380.689136 -402.78702)
					(end 380.70917 -402.777706)
				)
				(arc
					(start 381.002794 -402.585174)
					(mid 381.04445 -402.572772)
					(end 381.086106 -402.585174)
				)
				(arc
					(start 381.381 -402.777706)
					(mid 381.400924 -402.786942)
					(end 381.422656 -402.790152)
				)
				(arc
					(start 381.61722 -402.790152)
					(mid 381.671102 -402.767834)
					(end 381.69342 -402.713952)
				)
				(arc
					(start 381.69342 -402.028152)
					(mid 381.671102 -401.97427)
					(end 381.61722 -401.951952)
				)
				(arc
					(start 381.422656 -401.951952)
					(mid 381.400912 -401.95512)
					(end 381.381 -401.964398)
				)
				(arc
					(start 381.084836 -402.157184)
					(mid 381.043152 -402.169406)
					(end 381.001524 -402.15693)
				)
				(arc
					(start 380.7079 -401.964398)
					(mid 380.687976 -401.955162)
					(end 380.666244 -401.951952)
				)
				(arc
					(start 380.47168 -401.951952)
					(mid 380.417798 -401.97427)
					(end 380.39548 -402.028152)
				)
			)
		)
	)
	(zone
		(layer "In1.Cu")
		(hatch none 0.5)
		(connect_pads
			(clearance 0)
		)
		(min_thickness 0.25)
		(keepout
			(tracks not_allowed)
			(vias allowed)
			(pads allowed)
			(copperpour not_allowed)
			(footprints allowed)
		)
		(placement
			(enabled no)
			(sheetname "")
		)
		(fill
			(thermal_gap 0.5)
			(thermal_bridge_width 0.5)
			(island_removal_mode 0)
		)
		(polygon
			(pts
				(arc
					(start 79.741268 -408.860244)
					(mid 79.763586 -408.914126)
					(end 79.817468 -408.936444)
				)
				(arc
					(start 80.013048 -408.936444)
					(mid 80.034924 -408.933312)
					(end 80.054958 -408.923998)
				)
				(arc
					(start 80.348582 -408.731466)
					(mid 80.390238 -408.719064)
					(end 80.431894 -408.731466)
				)
				(arc
					(start 80.726788 -408.923998)
					(mid 80.746712 -408.933234)
					(end 80.768444 -408.936444)
				)
				(arc
					(start 80.963008 -408.936444)
					(mid 81.01689 -408.914126)
					(end 81.039208 -408.860244)
				)
				(arc
					(start 81.039208 -408.174444)
					(mid 81.01689 -408.120562)
					(end 80.963008 -408.098244)
				)
				(arc
					(start 80.768444 -408.098244)
					(mid 80.7467 -408.101412)
					(end 80.726788 -408.11069)
				)
				(arc
					(start 80.430624 -408.303476)
					(mid 80.38894 -408.315698)
					(end 80.347312 -408.303222)
				)
				(arc
					(start 80.053688 -408.11069)
					(mid 80.033764 -408.101454)
					(end 80.012032 -408.098244)
				)
				(arc
					(start 79.817468 -408.098244)
					(mid 79.763586 -408.120562)
					(end 79.741268 -408.174444)
				)
			)
		)
	)
	(zone
		(layer "In1.Cu")
		(hatch none 0.5)
		(connect_pads
			(clearance 0)
		)
		(min_thickness 0.25)
		(keepout
			(tracks not_allowed)
			(vias allowed)
			(pads allowed)
			(copperpour not_allowed)
			(footprints allowed)
		)
		(placement
			(enabled no)
			(sheetname "")
		)
		(fill
			(thermal_gap 0.5)
			(thermal_bridge_width 0.5)
			(island_removal_mode 0)
		)
		(polygon
			(pts
				(arc
					(start 22.610572 -386.407152)
					(mid 22.649613 -386.399395)
					(end 22.682454 -386.376926)
				)
				(arc
					(start 22.682454 -386.376926)
					(mid 22.702496 -386.346238)
					(end 22.71014 -386.310378)
				)
				(xy 22.71014 -386.168138) (xy 22.709886 -386.168138)
				(arc
					(start 22.709886 -385.240784)
					(mid 22.680696 -385.177278)
					(end 22.616668 -385.149344)
				)
				(arc
					(start 22.309836 -385.149344)
					(mid 22.270795 -385.157101)
					(end 22.237954 -385.17957)
				)
				(arc
					(start 22.237954 -385.17957)
					(mid 22.217912 -385.210258)
					(end 22.210268 -385.246118)
				)
				(xy 22.210268 -386.277358) (xy 22.210522 -386.277358)
				(arc
					(start 22.210522 -386.315712)
					(mid 22.239712 -386.379218)
					(end 22.30374 -386.407152)
				)
			)
		)
	)
	(zone
		(layer "In1.Cu")
		(hatch none 0.5)
		(connect_pads
			(clearance 0)
		)
		(min_thickness 0.25)
		(keepout
			(tracks not_allowed)
			(vias allowed)
			(pads allowed)
			(copperpour not_allowed)
			(footprints allowed)
		)
		(placement
			(enabled no)
			(sheetname "")
		)
		(fill
			(thermal_gap 0.5)
			(thermal_bridge_width 0.5)
			(island_removal_mode 0)
		)
		(polygon
			(pts
				(arc
					(start 412.176214 -16.431514)
					(mid 412.198532 -16.485396)
					(end 412.252414 -16.507714)
				)
				(arc
					(start 412.447994 -16.507714)
					(mid 412.46987 -16.504582)
					(end 412.489904 -16.495268)
				)
				(arc
					(start 412.783528 -16.302736)
					(mid 412.825184 -16.290334)
					(end 412.86684 -16.302736)
				)
				(arc
					(start 413.161734 -16.495268)
					(mid 413.181658 -16.504504)
					(end 413.20339 -16.507714)
				)
				(arc
					(start 413.397954 -16.507714)
					(mid 413.451836 -16.485396)
					(end 413.474154 -16.431514)
				)
				(arc
					(start 413.474154 -15.745714)
					(mid 413.451836 -15.691832)
					(end 413.397954 -15.669514)
				)
				(arc
					(start 413.20339 -15.669514)
					(mid 413.181646 -15.672682)
					(end 413.161734 -15.68196)
				)
				(arc
					(start 412.86557 -15.874746)
					(mid 412.823886 -15.886968)
					(end 412.782258 -15.874492)
				)
				(arc
					(start 412.488634 -15.68196)
					(mid 412.46871 -15.672724)
					(end 412.446978 -15.669514)
				)
				(arc
					(start 412.252414 -15.669514)
					(mid 412.198532 -15.691832)
					(end 412.176214 -15.745714)
				)
			)
		)
	)
	(zone
		(layer "In1.Cu")
		(hatch none 0.5)
		(connect_pads
			(clearance 0)
		)
		(min_thickness 0.25)
		(keepout
			(tracks not_allowed)
			(vias allowed)
			(pads allowed)
			(copperpour not_allowed)
			(footprints allowed)
		)
		(placement
			(enabled no)
			(sheetname "")
		)
		(fill
			(thermal_gap 0.5)
			(thermal_bridge_width 0.5)
			(island_removal_mode 0)
		)
		(polygon
			(pts
				(arc
					(start 387.86816 -408.860244)
					(mid 387.890478 -408.914126)
					(end 387.94436 -408.936444)
				)
				(arc
					(start 388.13994 -408.936444)
					(mid 388.161816 -408.933312)
					(end 388.18185 -408.923998)
				)
				(arc
					(start 388.475474 -408.731466)
					(mid 388.51713 -408.719064)
					(end 388.558786 -408.731466)
				)
				(arc
					(start 388.85368 -408.923998)
					(mid 388.873604 -408.933234)
					(end 388.895336 -408.936444)
				)
				(arc
					(start 389.0899 -408.936444)
					(mid 389.143782 -408.914126)
					(end 389.1661 -408.860244)
				)
				(arc
					(start 389.1661 -408.174444)
					(mid 389.143782 -408.120562)
					(end 389.0899 -408.098244)
				)
				(arc
					(start 388.895336 -408.098244)
					(mid 388.873592 -408.101412)
					(end 388.85368 -408.11069)
				)
				(arc
					(start 388.557516 -408.303476)
					(mid 388.515832 -408.315698)
					(end 388.474204 -408.303222)
				)
				(arc
					(start 388.18058 -408.11069)
					(mid 388.160656 -408.101454)
					(end 388.138924 -408.098244)
				)
				(arc
					(start 387.94436 -408.098244)
					(mid 387.890478 -408.120562)
					(end 387.86816 -408.174444)
				)
			)
		)
	)
	(zone
		(layer "In1.Cu")
		(hatch none 0.5)
		(connect_pads
			(clearance 0)
		)
		(min_thickness 0.25)
		(keepout
			(tracks not_allowed)
			(vias allowed)
			(pads allowed)
			(copperpour not_allowed)
			(footprints allowed)
		)
		(placement
			(enabled no)
			(sheetname "")
		)
		(fill
			(thermal_gap 0.5)
			(thermal_bridge_width 0.5)
			(island_removal_mode 0)
		)
		(polygon
			(pts
				(arc
					(start 15.677134 -20.53844)
					(mid 14.914626 -20.53844)
					(end 15.677134 -20.53844)
				)
			)
		)
	)
	(zone
		(layer "In1.Cu")
		(hatch none 0.5)
		(connect_pads
			(clearance 0)
		)
		(min_thickness 0.25)
		(keepout
			(tracks not_allowed)
			(vias allowed)
			(pads allowed)
			(copperpour not_allowed)
			(footprints allowed)
		)
		(placement
			(enabled no)
			(sheetname "")
		)
		(fill
			(thermal_gap 0.5)
			(thermal_bridge_width 0.5)
			(island_removal_mode 0)
		)
		(polygon
			(pts
				(arc
					(start 15.753588 -103.055928)
					(mid 14.992096 -103.055928)
					(end 15.753588 -103.055928)
				)
			)
		)
	)
	(zone
		(layer "In1.Cu")
		(hatch none 0.5)
		(connect_pads
			(clearance 0)
		)
		(min_thickness 0.25)
		(keepout
			(tracks not_allowed)
			(vias allowed)
			(pads allowed)
			(copperpour not_allowed)
			(footprints allowed)
		)
		(placement
			(enabled no)
			(sheetname "")
		)
		(fill
			(thermal_gap 0.5)
			(thermal_bridge_width 0.5)
			(island_removal_mode 0)
		)
		(polygon
			(pts
				(xy 135.556244 -12.876022) (xy 136.537192 -12.876022) (xy 136.537192 -14.323822) (xy 135.556244 -14.323822)
			)
		)
	)
	(zone
		(layer "In1.Cu")
		(hatch none 0.5)
		(connect_pads
			(clearance 0)
		)
		(min_thickness 0.25)
		(keepout
			(tracks not_allowed)
			(vias allowed)
			(pads allowed)
			(copperpour not_allowed)
			(footprints allowed)
		)
		(placement
			(enabled no)
			(sheetname "")
		)
		(fill
			(thermal_gap 0.5)
			(thermal_bridge_width 0.5)
			(island_removal_mode 0)
		)
		(polygon
			(pts
				(arc
					(start 340.41207 -0.162306)
					(mid 340.389752 -0.216188)
					(end 340.33587 -0.238506)
				)
				(arc
					(start 339.72373 -0.238506)
					(mid 339.669848 -0.216188)
					(end 339.64753 -0.162306)
				)
				(arc
					(start 339.64753 0.934974)
					(mid 339.669848 0.988856)
					(end 339.72373 1.011174)
				)
				(arc
					(start 340.33587 1.011174)
					(mid 340.389752 0.988856)
					(end 340.41207 0.934974)
				)
			)
		)
	)
	(zone
		(layer "In1.Cu")
		(hatch none 0.5)
		(connect_pads
			(clearance 0)
		)
		(min_thickness 0.25)
		(keepout
			(tracks not_allowed)
			(vias allowed)
			(pads allowed)
			(copperpour not_allowed)
			(footprints allowed)
		)
		(placement
			(enabled no)
			(sheetname "")
		)
		(fill
			(thermal_gap 0.5)
			(thermal_bridge_width 0.5)
			(island_removal_mode 0)
		)
		(polygon
			(pts
				(arc
					(start 411.02788 -402.713952)
					(mid 411.050198 -402.767834)
					(end 411.10408 -402.790152)
				)
				(arc
					(start 411.29966 -402.790152)
					(mid 411.321536 -402.78702)
					(end 411.34157 -402.777706)
				)
				(arc
					(start 411.635194 -402.585174)
					(mid 411.67685 -402.572772)
					(end 411.718506 -402.585174)
				)
				(arc
					(start 412.0134 -402.777706)
					(mid 412.033324 -402.786942)
					(end 412.055056 -402.790152)
				)
				(arc
					(start 412.24962 -402.790152)
					(mid 412.303502 -402.767834)
					(end 412.32582 -402.713952)
				)
				(arc
					(start 412.32582 -402.028152)
					(mid 412.303502 -401.97427)
					(end 412.24962 -401.951952)
				)
				(arc
					(start 412.055056 -401.951952)
					(mid 412.033312 -401.95512)
					(end 412.0134 -401.964398)
				)
				(arc
					(start 411.717236 -402.157184)
					(mid 411.675552 -402.169406)
					(end 411.633924 -402.15693)
				)
				(arc
					(start 411.3403 -401.964398)
					(mid 411.320376 -401.955162)
					(end 411.298644 -401.951952)
				)
				(arc
					(start 411.10408 -401.951952)
					(mid 411.050198 -401.97427)
					(end 411.02788 -402.028152)
				)
			)
		)
	)
	(zone
		(layer "In1.Cu")
		(hatch none 0.5)
		(connect_pads
			(clearance 0)
		)
		(min_thickness 0.25)
		(keepout
			(tracks not_allowed)
			(vias allowed)
			(pads allowed)
			(copperpour not_allowed)
			(footprints allowed)
		)
		(placement
			(enabled no)
			(sheetname "")
		)
		(fill
			(thermal_gap 0.5)
			(thermal_bridge_width 0.5)
			(island_removal_mode 0)
		)
		(polygon
			(pts
				(arc
					(start 26.492708 -16.442436)
					(mid 26.515026 -16.496318)
					(end 26.568908 -16.518636)
				)
				(arc
					(start 26.764488 -16.518636)
					(mid 26.786364 -16.515504)
					(end 26.806398 -16.50619)
				)
				(arc
					(start 27.100022 -16.313658)
					(mid 27.141678 -16.301256)
					(end 27.183334 -16.313658)
				)
				(arc
					(start 27.478228 -16.50619)
					(mid 27.498152 -16.515426)
					(end 27.519884 -16.518636)
				)
				(arc
					(start 27.714448 -16.518636)
					(mid 27.76833 -16.496318)
					(end 27.790648 -16.442436)
				)
				(arc
					(start 27.790648 -15.756636)
					(mid 27.76833 -15.702754)
					(end 27.714448 -15.680436)
				)
				(arc
					(start 27.519884 -15.680436)
					(mid 27.49814 -15.683604)
					(end 27.478228 -15.692882)
				)
				(arc
					(start 27.182064 -15.885668)
					(mid 27.14038 -15.89789)
					(end 27.098752 -15.885414)
				)
				(arc
					(start 26.805128 -15.692882)
					(mid 26.785204 -15.683646)
					(end 26.763472 -15.680436)
				)
				(arc
					(start 26.568908 -15.680436)
					(mid 26.515026 -15.702754)
					(end 26.492708 -15.756636)
				)
			)
		)
	)
	(zone
		(layer "In1.Cu")
		(hatch none 0.5)
		(connect_pads
			(clearance 0)
		)
		(min_thickness 0.25)
		(keepout
			(tracks not_allowed)
			(vias allowed)
			(pads allowed)
			(copperpour not_allowed)
			(footprints allowed)
		)
		(placement
			(enabled no)
			(sheetname "")
		)
		(fill
			(thermal_gap 0.5)
			(thermal_bridge_width 0.5)
			(island_removal_mode 0)
		)
		(polygon
			(pts
				(arc
					(start 85.867748 -408.860244)
					(mid 85.890066 -408.914126)
					(end 85.943948 -408.936444)
				)
				(arc
					(start 86.139528 -408.936444)
					(mid 86.161404 -408.933312)
					(end 86.181438 -408.923998)
				)
				(arc
					(start 86.475062 -408.731466)
					(mid 86.516718 -408.719064)
					(end 86.558374 -408.731466)
				)
				(arc
					(start 86.853268 -408.923998)
					(mid 86.873192 -408.933234)
					(end 86.894924 -408.936444)
				)
				(arc
					(start 87.089488 -408.936444)
					(mid 87.14337 -408.914126)
					(end 87.165688 -408.860244)
				)
				(arc
					(start 87.165688 -408.174444)
					(mid 87.14337 -408.120562)
					(end 87.089488 -408.098244)
				)
				(arc
					(start 86.894924 -408.098244)
					(mid 86.87318 -408.101412)
					(end 86.853268 -408.11069)
				)
				(arc
					(start 86.557104 -408.303476)
					(mid 86.51542 -408.315698)
					(end 86.473792 -408.303222)
				)
				(arc
					(start 86.180168 -408.11069)
					(mid 86.160244 -408.101454)
					(end 86.138512 -408.098244)
				)
				(arc
					(start 85.943948 -408.098244)
					(mid 85.890066 -408.120562)
					(end 85.867748 -408.174444)
				)
			)
		)
	)
	(zone
		(layer "In1.Cu")
		(hatch none 0.5)
		(connect_pads
			(clearance 0)
		)
		(min_thickness 0.25)
		(keepout
			(tracks not_allowed)
			(vias allowed)
			(pads allowed)
			(copperpour not_allowed)
			(footprints allowed)
		)
		(placement
			(enabled no)
			(sheetname "")
		)
		(fill
			(thermal_gap 0.5)
			(thermal_bridge_width 0.5)
			(island_removal_mode 0)
		)
		(polygon
			(pts
				(arc
					(start 14.41577 -106.166666)
					(mid 14.454811 -106.158909)
					(end 14.487652 -106.13644)
				)
				(arc
					(start 14.487652 -106.13644)
					(mid 14.507694 -106.105752)
					(end 14.515338 -106.069892)
				)
				(xy 14.515338 -105.927652) (xy 14.515084 -105.927652)
				(arc
					(start 14.515084 -105.000298)
					(mid 14.485894 -104.936792)
					(end 14.421866 -104.908858)
				)
				(arc
					(start 14.115034 -104.908858)
					(mid 14.075993 -104.916615)
					(end 14.043152 -104.939084)
				)
				(arc
					(start 14.043152 -104.939084)
					(mid 14.02311 -104.969772)
					(end 14.015466 -105.005632)
				)
				(xy 14.015466 -106.036872) (xy 14.01572 -106.036872)
				(arc
					(start 14.01572 -106.075226)
					(mid 14.04491 -106.138732)
					(end 14.108938 -106.166666)
				)
			)
		)
	)
	(zone
		(layer "In1.Cu")
		(hatch none 0.5)
		(connect_pads
			(clearance 0)
		)
		(min_thickness 0.25)
		(keepout
			(tracks not_allowed)
			(vias allowed)
			(pads allowed)
			(copperpour not_allowed)
			(footprints allowed)
		)
		(placement
			(enabled no)
			(sheetname "")
		)
		(fill
			(thermal_gap 0.5)
			(thermal_bridge_width 0.5)
			(island_removal_mode 0)
		)
		(polygon
			(pts
				(arc
					(start 38.638988 -11.91768)
					(mid 38.661306 -11.971562)
					(end 38.715188 -11.99388)
				)
				(arc
					(start 39.996618 -11.99388)
					(mid 40.0505 -11.971562)
					(end 40.072818 -11.91768)
				)
				(arc
					(start 40.072818 -10.49528)
					(mid 40.0505 -10.441398)
					(end 39.996618 -10.41908)
				)
				(arc
					(start 38.715188 -10.41908)
					(mid 38.661306 -10.441398)
					(end 38.638988 -10.49528)
				)
			)
		)
	)
	(zone
		(layer "In1.Cu")
		(hatch none 0.5)
		(connect_pads
			(clearance 0)
		)
		(min_thickness 0.25)
		(keepout
			(tracks not_allowed)
			(vias allowed)
			(pads allowed)
			(copperpour not_allowed)
			(footprints allowed)
		)
		(placement
			(enabled no)
			(sheetname "")
		)
		(fill
			(thermal_gap 0.5)
			(thermal_bridge_width 0.5)
			(island_removal_mode 0)
		)
		(polygon
			(pts
				(arc
					(start 419.976046 -7.672324)
					(mid 419.953728 -7.618442)
					(end 419.899846 -7.596124)
				)
				(arc
					(start 418.618416 -7.596124)
					(mid 418.564534 -7.618442)
					(end 418.542216 -7.672324)
				)
				(arc
					(start 418.542216 -9.094724)
					(mid 418.564534 -9.148606)
					(end 418.618416 -9.170924)
				)
				(arc
					(start 419.899846 -9.170924)
					(mid 419.953728 -9.148606)
					(end 419.976046 -9.094724)
				)
			)
		)
	)
	(zone
		(layer "In1.Cu")
		(hatch none 0.5)
		(connect_pads
			(clearance 0)
		)
		(min_thickness 0.25)
		(keepout
			(tracks not_allowed)
			(vias allowed)
			(pads allowed)
			(copperpour not_allowed)
			(footprints allowed)
		)
		(placement
			(enabled no)
			(sheetname "")
		)
		(fill
			(thermal_gap 0.5)
			(thermal_bridge_width 0.5)
			(island_removal_mode 0)
		)
		(polygon
			(pts
				(arc
					(start 431.186082 -7.672324)
					(mid 431.163764 -7.618442)
					(end 431.109882 -7.596124)
				)
				(arc
					(start 429.828452 -7.596124)
					(mid 429.77457 -7.618442)
					(end 429.752252 -7.672324)
				)
				(arc
					(start 429.752252 -9.094724)
					(mid 429.77457 -9.148606)
					(end 429.828452 -9.170924)
				)
				(arc
					(start 431.109882 -9.170924)
					(mid 431.163764 -9.148606)
					(end 431.186082 -9.094724)
				)
			)
		)
	)
	(zone
		(layer "In1.Cu")
		(hatch none 0.5)
		(connect_pads
			(clearance 0)
		)
		(min_thickness 0.25)
		(keepout
			(tracks not_allowed)
			(vias allowed)
			(pads allowed)
			(copperpour not_allowed)
			(footprints allowed)
		)
		(placement
			(enabled no)
			(sheetname "")
		)
		(fill
			(thermal_gap 0.5)
			(thermal_bridge_width 0.5)
			(island_removal_mode 0)
		)
		(polygon
			(pts
				(arc
					(start 425.786042 -7.672324)
					(mid 425.763724 -7.618442)
					(end 425.709842 -7.596124)
				)
				(arc
					(start 424.428412 -7.596124)
					(mid 424.37453 -7.618442)
					(end 424.352212 -7.672324)
				)
				(arc
					(start 424.352212 -9.094724)
					(mid 424.37453 -9.148606)
					(end 424.428412 -9.170924)
				)
				(arc
					(start 425.709842 -9.170924)
					(mid 425.763724 -9.148606)
					(end 425.786042 -9.094724)
				)
			)
		)
	)
	(zone
		(layer "In1.Cu")
		(hatch none 0.5)
		(connect_pads
			(clearance 0)
		)
		(min_thickness 0.25)
		(keepout
			(tracks not_allowed)
			(vias allowed)
			(pads allowed)
			(copperpour not_allowed)
			(footprints allowed)
		)
		(placement
			(enabled no)
			(sheetname "")
		)
		(fill
			(thermal_gap 0.5)
			(thermal_bridge_width 0.5)
			(island_removal_mode 0)
		)
		(polygon
			(pts
				(arc
					(start 404.02764 -11.91768)
					(mid 404.049958 -11.971562)
					(end 404.10384 -11.99388)
				)
				(arc
					(start 405.38527 -11.99388)
					(mid 405.439152 -11.971562)
					(end 405.46147 -11.91768)
				)
				(arc
					(start 405.46147 -10.49528)
					(mid 405.439152 -10.441398)
					(end 405.38527 -10.41908)
				)
				(arc
					(start 404.10384 -10.41908)
					(mid 404.049958 -10.441398)
					(end 404.02764 -10.49528)
				)
			)
		)
	)
	(zone
		(layer "In1.Cu")
		(hatch none 0.5)
		(connect_pads
			(clearance 0)
		)
		(min_thickness 0.25)
		(keepout
			(tracks not_allowed)
			(vias allowed)
			(pads allowed)
			(copperpour not_allowed)
			(footprints allowed)
		)
		(placement
			(enabled no)
			(sheetname "")
		)
		(fill
			(thermal_gap 0.5)
			(thermal_bridge_width 0.5)
			(island_removal_mode 0)
		)
		(polygon
			(pts
				(arc
					(start 148.853144 -408.860244)
					(mid 148.875462 -408.914126)
					(end 148.929344 -408.936444)
				)
				(arc
					(start 149.124924 -408.936444)
					(mid 149.1468 -408.933312)
					(end 149.166834 -408.923998)
				)
				(arc
					(start 149.460458 -408.731466)
					(mid 149.502114 -408.719064)
					(end 149.54377 -408.731466)
				)
				(arc
					(start 149.838664 -408.923998)
					(mid 149.858588 -408.933234)
					(end 149.88032 -408.936444)
				)
				(arc
					(start 150.074884 -408.936444)
					(mid 150.128766 -408.914126)
					(end 150.151084 -408.860244)
				)
				(arc
					(start 150.151084 -408.174444)
					(mid 150.128766 -408.120562)
					(end 150.074884 -408.098244)
				)
				(arc
					(start 149.88032 -408.098244)
					(mid 149.858576 -408.101412)
					(end 149.838664 -408.11069)
				)
				(arc
					(start 149.5425 -408.303476)
					(mid 149.500816 -408.315698)
					(end 149.459188 -408.303222)
				)
				(arc
					(start 149.165564 -408.11069)
					(mid 149.14564 -408.101454)
					(end 149.123908 -408.098244)
				)
				(arc
					(start 148.929344 -408.098244)
					(mid 148.875462 -408.120562)
					(end 148.853144 -408.174444)
				)
			)
		)
	)
	(zone
		(layer "In1.Cu")
		(hatch none 0.5)
		(connect_pads
			(clearance 0)
		)
		(min_thickness 0.25)
		(keepout
			(tracks not_allowed)
			(vias allowed)
			(pads allowed)
			(copperpour not_allowed)
			(footprints allowed)
		)
		(placement
			(enabled no)
			(sheetname "")
		)
		(fill
			(thermal_gap 0.5)
			(thermal_bridge_width 0.5)
			(island_removal_mode 0)
		)
		(polygon
			(pts
				(arc
					(start 427.947836 -11.91768)
					(mid 427.970154 -11.971562)
					(end 428.024036 -11.99388)
				)
				(arc
					(start 429.305466 -11.99388)
					(mid 429.359348 -11.971562)
					(end 429.381666 -11.91768)
				)
				(arc
					(start 429.381666 -10.49528)
					(mid 429.359348 -10.441398)
					(end 429.305466 -10.41908)
				)
				(arc
					(start 428.024036 -10.41908)
					(mid 427.970154 -10.441398)
					(end 427.947836 -10.49528)
				)
			)
		)
	)
	(zone
		(layer "In1.Cu")
		(hatch none 0.5)
		(connect_pads
			(clearance 0)
		)
		(min_thickness 0.25)
		(keepout
			(tracks not_allowed)
			(vias allowed)
			(pads allowed)
			(copperpour not_allowed)
			(footprints allowed)
		)
		(placement
			(enabled no)
			(sheetname "")
		)
		(fill
			(thermal_gap 0.5)
			(thermal_bridge_width 0.5)
			(island_removal_mode 0)
		)
		(polygon
			(pts
				(arc
					(start 176.38268 -52.436014)
					(mid 176.328798 -52.413696)
					(end 176.30648 -52.359814)
				)
				(arc
					(start 176.30648 -51.727354)
					(mid 176.328798 -51.673472)
					(end 176.38268 -51.651154)
				)
				(arc
					(start 177.83556 -51.651154)
					(mid 177.889442 -51.673472)
					(end 177.91176 -51.727354)
				)
				(arc
					(start 177.91176 -52.359814)
					(mid 177.889442 -52.413696)
					(end 177.83556 -52.436014)
				)
			)
		)
	)
	(zone
		(layer "In1.Cu")
		(hatch none 0.5)
		(connect_pads
			(clearance 0)
		)
		(min_thickness 0.25)
		(keepout
			(tracks not_allowed)
			(vias allowed)
			(pads allowed)
			(copperpour not_allowed)
			(footprints allowed)
		)
		(placement
			(enabled no)
			(sheetname "")
		)
		(fill
			(thermal_gap 0.5)
			(thermal_bridge_width 0.5)
			(island_removal_mode 0)
		)
		(polygon
			(pts
				(arc
					(start 398.265904 -7.672324)
					(mid 398.243586 -7.618442)
					(end 398.189704 -7.596124)
				)
				(arc
					(start 396.908274 -7.596124)
					(mid 396.854392 -7.618442)
					(end 396.832074 -7.672324)
				)
				(arc
					(start 396.832074 -9.094724)
					(mid 396.854392 -9.148606)
					(end 396.908274 -9.170924)
				)
				(arc
					(start 398.189704 -9.170924)
					(mid 398.243586 -9.148606)
					(end 398.265904 -9.094724)
				)
			)
		)
	)
	(zone
		(layer "In1.Cu")
		(hatch none 0.5)
		(connect_pads
			(clearance 0)
		)
		(min_thickness 0.25)
		(keepout
			(tracks not_allowed)
			(vias allowed)
			(pads allowed)
			(copperpour not_allowed)
			(footprints allowed)
		)
		(placement
			(enabled no)
			(sheetname "")
		)
		(fill
			(thermal_gap 0.5)
			(thermal_bridge_width 0.5)
			(island_removal_mode 0)
		)
		(polygon
			(pts
				(arc
					(start 25.928828 -11.91768)
					(mid 25.951146 -11.971562)
					(end 26.005028 -11.99388)
				)
				(arc
					(start 27.286458 -11.99388)
					(mid 27.34034 -11.971562)
					(end 27.362658 -11.91768)
				)
				(arc
					(start 27.362658 -10.49528)
					(mid 27.34034 -10.441398)
					(end 27.286458 -10.41908)
				)
				(arc
					(start 26.005028 -10.41908)
					(mid 25.951146 -10.441398)
					(end 25.928828 -10.49528)
				)
			)
		)
	)
	(zone
		(layer "In1.Cu")
		(hatch none 0.5)
		(connect_pads
			(clearance 0)
		)
		(min_thickness 0.25)
		(keepout
			(tracks not_allowed)
			(vias allowed)
			(pads allowed)
			(copperpour not_allowed)
			(footprints allowed)
		)
		(placement
			(enabled no)
			(sheetname "")
		)
		(fill
			(thermal_gap 0.5)
			(thermal_bridge_width 0.5)
			(island_removal_mode 0)
		)
		(polygon
			(pts
				(arc
					(start 341.76589 -70.17766)
					(mid 341.743572 -70.123778)
					(end 341.68969 -70.10146)
				)
				(arc
					(start 341.35949 -70.10146)
					(mid 341.305608 -70.123778)
					(end 341.28329 -70.17766)
				)
				(arc
					(start 341.28329 -70.43166)
					(mid 341.305608 -70.485542)
					(end 341.35949 -70.50786)
				)
				(arc
					(start 341.68969 -70.50786)
					(mid 341.743572 -70.485542)
					(end 341.76589 -70.43166)
				)
			)
		)
	)
	(zone
		(layer "In1.Cu")
		(hatch none 0.5)
		(connect_pads
			(clearance 0)
		)
		(min_thickness 0.25)
		(keepout
			(tracks not_allowed)
			(vias allowed)
			(pads allowed)
			(copperpour not_allowed)
			(footprints allowed)
		)
		(placement
			(enabled no)
			(sheetname "")
		)
		(fill
			(thermal_gap 0.5)
			(thermal_bridge_width 0.5)
			(island_removal_mode 0)
		)
		(polygon
			(pts
				(arc
					(start 20.529042 -11.91768)
					(mid 20.55136 -11.971562)
					(end 20.605242 -11.99388)
				)
				(arc
					(start 21.886672 -11.99388)
					(mid 21.940554 -11.971562)
					(end 21.962872 -11.91768)
				)
				(arc
					(start 21.962872 -10.49528)
					(mid 21.940554 -10.441398)
					(end 21.886672 -10.41908)
				)
				(arc
					(start 20.605242 -10.41908)
					(mid 20.55136 -10.441398)
					(end 20.529042 -10.49528)
				)
			)
		)
	)
	(zone
		(layer "In1.Cu")
		(hatch none 0.5)
		(connect_pads
			(clearance 0)
		)
		(min_thickness 0.25)
		(keepout
			(tracks not_allowed)
			(vias allowed)
			(pads allowed)
			(copperpour not_allowed)
			(footprints allowed)
		)
		(placement
			(enabled no)
			(sheetname "")
		)
		(fill
			(thermal_gap 0.5)
			(thermal_bridge_width 0.5)
			(island_removal_mode 0)
		)
		(polygon
			(pts
				(arc
					(start 261.845044 4.917694)
					(mid 261.822726 4.863812)
					(end 261.768844 4.841494)
				)
				(arc
					(start 261.156704 4.841494)
					(mid 261.102822 4.863812)
					(end 261.080504 4.917694)
				)
				(arc
					(start 261.080504 6.014974)
					(mid 261.102822 6.068856)
					(end 261.156704 6.091174)
				)
				(arc
					(start 261.768844 6.091174)
					(mid 261.822726 6.068856)
					(end 261.845044 6.014974)
				)
			)
		)
	)
	(zone
		(layer "In1.Cu")
		(hatch none 0.5)
		(connect_pads
			(clearance 0)
		)
		(min_thickness 0.25)
		(keepout
			(tracks not_allowed)
			(vias allowed)
			(pads allowed)
			(copperpour not_allowed)
			(footprints allowed)
		)
		(placement
			(enabled no)
			(sheetname "")
		)
		(fill
			(thermal_gap 0.5)
			(thermal_bridge_width 0.5)
			(island_removal_mode 0)
		)
		(polygon
			(pts
				(arc
					(start 53.08727 -7.672324)
					(mid 53.064952 -7.618442)
					(end 53.01107 -7.596124)
				)
				(arc
					(start 51.72964 -7.596124)
					(mid 51.675758 -7.618442)
					(end 51.65344 -7.672324)
				)
				(arc
					(start 51.65344 -9.094724)
					(mid 51.675758 -9.148606)
					(end 51.72964 -9.170924)
				)
				(arc
					(start 53.01107 -9.170924)
					(mid 53.064952 -9.148606)
					(end 53.08727 -9.094724)
				)
			)
		)
	)
	(zone
		(layer "In1.Cu")
		(hatch none 0.5)
		(connect_pads
			(clearance 0)
		)
		(min_thickness 0.25)
		(keepout
			(tracks not_allowed)
			(vias allowed)
			(pads allowed)
			(copperpour not_allowed)
			(footprints allowed)
		)
		(placement
			(enabled no)
			(sheetname "")
		)
		(fill
			(thermal_gap 0.5)
			(thermal_bridge_width 0.5)
			(island_removal_mode 0)
		)
		(polygon
			(pts
				(arc
					(start 43.677078 -7.672324)
					(mid 43.65476 -7.618442)
					(end 43.600878 -7.596124)
				)
				(arc
					(start 42.319448 -7.596124)
					(mid 42.265566 -7.618442)
					(end 42.243248 -7.672324)
				)
				(arc
					(start 42.243248 -9.094724)
					(mid 42.265566 -9.148606)
					(end 42.319448 -9.170924)
				)
				(arc
					(start 43.600878 -9.170924)
					(mid 43.65476 -9.148606)
					(end 43.677078 -9.094724)
				)
			)
		)
	)
	(zone
		(layer "In1.Cu")
		(hatch none 0.5)
		(connect_pads
			(clearance 0)
		)
		(min_thickness 0.25)
		(keepout
			(tracks not_allowed)
			(vias allowed)
			(pads allowed)
			(copperpour not_allowed)
			(footprints allowed)
		)
		(placement
			(enabled no)
			(sheetname "")
		)
		(fill
			(thermal_gap 0.5)
			(thermal_bridge_width 0.5)
			(island_removal_mode 0)
		)
		(polygon
			(pts
				(arc
					(start 49.849024 -11.91768)
					(mid 49.871342 -11.971562)
					(end 49.925224 -11.99388)
				)
				(arc
					(start 51.206654 -11.99388)
					(mid 51.260536 -11.971562)
					(end 51.282854 -11.91768)
				)
				(arc
					(start 51.282854 -10.49528)
					(mid 51.260536 -10.441398)
					(end 51.206654 -10.41908)
				)
				(arc
					(start 49.925224 -10.41908)
					(mid 49.871342 -10.441398)
					(end 49.849024 -10.49528)
				)
			)
		)
	)
	(zone
		(layer "In1.Cu")
		(hatch none 0.5)
		(connect_pads
			(clearance 0)
		)
		(min_thickness 0.25)
		(keepout
			(tracks not_allowed)
			(vias allowed)
			(pads allowed)
			(copperpour not_allowed)
			(footprints allowed)
		)
		(placement
			(enabled no)
			(sheetname "")
		)
		(fill
			(thermal_gap 0.5)
			(thermal_bridge_width 0.5)
			(island_removal_mode 0)
		)
		(polygon
			(pts
				(arc
					(start 426.147992 -11.91768)
					(mid 426.17031 -11.971562)
					(end 426.224192 -11.99388)
				)
				(arc
					(start 427.505622 -11.99388)
					(mid 427.559504 -11.971562)
					(end 427.581822 -11.91768)
				)
				(arc
					(start 427.581822 -10.49528)
					(mid 427.559504 -10.441398)
					(end 427.505622 -10.41908)
				)
				(arc
					(start 426.224192 -10.41908)
					(mid 426.17031 -10.441398)
					(end 426.147992 -10.49528)
				)
			)
		)
	)
	(zone
		(layer "In1.Cu")
		(hatch none 0.5)
		(connect_pads
			(clearance 0)
		)
		(min_thickness 0.25)
		(keepout
			(tracks not_allowed)
			(vias allowed)
			(pads allowed)
			(copperpour not_allowed)
			(footprints allowed)
		)
		(placement
			(enabled no)
			(sheetname "")
		)
		(fill
			(thermal_gap 0.5)
			(thermal_bridge_width 0.5)
			(island_removal_mode 0)
		)
		(polygon
			(pts
				(arc
					(start 29.167074 -7.672324)
					(mid 29.144756 -7.618442)
					(end 29.090874 -7.596124)
				)
				(arc
					(start 27.809444 -7.596124)
					(mid 27.755562 -7.618442)
					(end 27.733244 -7.672324)
				)
				(arc
					(start 27.733244 -9.094724)
					(mid 27.755562 -9.148606)
					(end 27.809444 -9.170924)
				)
				(arc
					(start 29.090874 -9.170924)
					(mid 29.144756 -9.148606)
					(end 29.167074 -9.094724)
				)
			)
		)
	)
	(zone
		(layer "In1.Cu")
		(hatch none 0.5)
		(connect_pads
			(clearance 0)
		)
		(min_thickness 0.25)
		(keepout
			(tracks not_allowed)
			(vias allowed)
			(pads allowed)
			(copperpour not_allowed)
			(footprints allowed)
		)
		(placement
			(enabled no)
			(sheetname "")
		)
		(fill
			(thermal_gap 0.5)
			(thermal_bridge_width 0.5)
			(island_removal_mode 0)
		)
		(polygon
			(pts
				(arc
					(start 420.86403 -17.955514)
					(mid 420.886348 -18.009396)
					(end 420.94023 -18.031714)
				)
				(arc
					(start 421.13581 -18.031714)
					(mid 421.157686 -18.028582)
					(end 421.17772 -18.019268)
				)
				(arc
					(start 421.471344 -17.826736)
					(mid 421.513 -17.814334)
					(end 421.554656 -17.826736)
				)
				(arc
					(start 421.84955 -18.019268)
					(mid 421.869474 -18.028504)
					(end 421.891206 -18.031714)
				)
				(arc
					(start 422.08577 -18.031714)
					(mid 422.139652 -18.009396)
					(end 422.16197 -17.955514)
				)
				(arc
					(start 422.16197 -17.269714)
					(mid 422.139652 -17.215832)
					(end 422.08577 -17.193514)
				)
				(arc
					(start 421.891206 -17.193514)
					(mid 421.869462 -17.196682)
					(end 421.84955 -17.20596)
				)
				(arc
					(start 421.553386 -17.398746)
					(mid 421.511702 -17.410968)
					(end 421.470074 -17.398492)
				)
				(arc
					(start 421.17645 -17.20596)
					(mid 421.156526 -17.196724)
					(end 421.134794 -17.193514)
				)
				(arc
					(start 420.94023 -17.193514)
					(mid 420.886348 -17.215832)
					(end 420.86403 -17.269714)
				)
			)
		)
	)
	(zone
		(layer "In1.Cu")
		(hatch none 0.5)
		(connect_pads
			(clearance 0)
		)
		(min_thickness 0.25)
		(keepout
			(tracks not_allowed)
			(vias allowed)
			(pads allowed)
			(copperpour not_allowed)
			(footprints allowed)
		)
		(placement
			(enabled no)
			(sheetname "")
		)
		(fill
			(thermal_gap 0.5)
			(thermal_bridge_width 0.5)
			(island_removal_mode 0)
		)
		(polygon
			(pts
				(arc
					(start 376.986038 6.009894)
					(mid 377.008356 6.063776)
					(end 377.062238 6.086094)
				)
				(arc
					(start 377.674378 6.086094)
					(mid 377.72826 6.063776)
					(end 377.750578 6.009894)
				)
				(arc
					(start 377.750578 4.912614)
					(mid 377.72826 4.858732)
					(end 377.674378 4.836414)
				)
				(arc
					(start 377.062238 4.836414)
					(mid 377.008356 4.858732)
					(end 376.986038 4.912614)
				)
			)
		)
	)
	(zone
		(layer "In1.Cu")
		(hatch none 0.5)
		(connect_pads
			(clearance 0)
		)
		(min_thickness 0.25)
		(keepout
			(tracks not_allowed)
			(vias allowed)
			(pads allowed)
			(copperpour not_allowed)
			(footprints allowed)
		)
		(placement
			(enabled no)
			(sheetname "")
		)
		(fill
			(thermal_gap 0.5)
			(thermal_bridge_width 0.5)
			(island_removal_mode 0)
		)
		(polygon
			(pts
				(arc
					(start 124.347224 -408.860244)
					(mid 124.369542 -408.914126)
					(end 124.423424 -408.936444)
				)
				(arc
					(start 124.619004 -408.936444)
					(mid 124.64088 -408.933312)
					(end 124.660914 -408.923998)
				)
				(arc
					(start 124.954538 -408.731466)
					(mid 124.996194 -408.719064)
					(end 125.03785 -408.731466)
				)
				(arc
					(start 125.332744 -408.923998)
					(mid 125.352668 -408.933234)
					(end 125.3744 -408.936444)
				)
				(arc
					(start 125.568964 -408.936444)
					(mid 125.622846 -408.914126)
					(end 125.645164 -408.860244)
				)
				(arc
					(start 125.645164 -408.174444)
					(mid 125.622846 -408.120562)
					(end 125.568964 -408.098244)
				)
				(arc
					(start 125.3744 -408.098244)
					(mid 125.352656 -408.101412)
					(end 125.332744 -408.11069)
				)
				(arc
					(start 125.03658 -408.303476)
					(mid 124.994896 -408.315698)
					(end 124.953268 -408.303222)
				)
				(arc
					(start 124.659644 -408.11069)
					(mid 124.63972 -408.101454)
					(end 124.617988 -408.098244)
				)
				(arc
					(start 124.423424 -408.098244)
					(mid 124.369542 -408.120562)
					(end 124.347224 -408.174444)
				)
			)
		)
	)
	(zone
		(layer "In1.Cu")
		(hatch none 0.5)
		(connect_pads
			(clearance 0)
		)
		(min_thickness 0.25)
		(keepout
			(tracks not_allowed)
			(vias allowed)
			(pads allowed)
			(copperpour not_allowed)
			(footprints allowed)
		)
		(placement
			(enabled no)
			(sheetname "")
		)
		(fill
			(thermal_gap 0.5)
			(thermal_bridge_width 0.5)
			(island_removal_mode 0)
		)
		(polygon
			(pts
				(arc
					(start 155.785312 -45.275754)
					(mid 155.824353 -45.267997)
					(end 155.857194 -45.245528)
				)
				(arc
					(start 155.857194 -45.245528)
					(mid 155.877236 -45.21484)
					(end 155.88488 -45.17898)
				)
				(xy 155.88488 -45.03674) (xy 155.884626 -45.03674)
				(arc
					(start 155.884626 -44.109386)
					(mid 155.855436 -44.04588)
					(end 155.791408 -44.017946)
				)
				(arc
					(start 155.484576 -44.017946)
					(mid 155.445535 -44.025703)
					(end 155.412694 -44.048172)
				)
				(arc
					(start 155.412694 -44.048172)
					(mid 155.392652 -44.07886)
					(end 155.385008 -44.11472)
				)
				(xy 155.385008 -45.14596) (xy 155.385262 -45.14596)
				(arc
					(start 155.385262 -45.184314)
					(mid 155.414452 -45.24782)
					(end 155.47848 -45.275754)
				)
			)
		)
	)
	(zone
		(layer "In1.Cu")
		(hatch none 0.5)
		(connect_pads
			(clearance 0)
		)
		(min_thickness 0.25)
		(keepout
			(tracks not_allowed)
			(vias allowed)
			(pads allowed)
			(copperpour not_allowed)
			(footprints allowed)
		)
		(placement
			(enabled no)
			(sheetname "")
		)
		(fill
			(thermal_gap 0.5)
			(thermal_bridge_width 0.5)
			(island_removal_mode 0)
		)
		(polygon
			(pts
				(arc
					(start 398.627854 -11.91768)
					(mid 398.650172 -11.971562)
					(end 398.704054 -11.99388)
				)
				(arc
					(start 399.985484 -11.99388)
					(mid 400.039366 -11.971562)
					(end 400.061684 -11.91768)
				)
				(arc
					(start 400.061684 -10.49528)
					(mid 400.039366 -10.441398)
					(end 399.985484 -10.41908)
				)
				(arc
					(start 398.704054 -10.41908)
					(mid 398.650172 -10.441398)
					(end 398.627854 -10.49528)
				)
			)
		)
	)
	(zone
		(layer "In1.Cu")
		(hatch none 0.5)
		(connect_pads
			(clearance 0)
		)
		(min_thickness 0.25)
		(keepout
			(tracks not_allowed)
			(vias allowed)
			(pads allowed)
			(copperpour not_allowed)
			(footprints allowed)
		)
		(placement
			(enabled no)
			(sheetname "")
		)
		(fill
			(thermal_gap 0.5)
			(thermal_bridge_width 0.5)
			(island_removal_mode 0)
		)
		(polygon
			(pts
				(arc
					(start 61.361828 -408.860244)
					(mid 61.384146 -408.914126)
					(end 61.438028 -408.936444)
				)
				(arc
					(start 61.633608 -408.936444)
					(mid 61.655484 -408.933312)
					(end 61.675518 -408.923998)
				)
				(arc
					(start 61.969142 -408.731466)
					(mid 62.010798 -408.719064)
					(end 62.052454 -408.731466)
				)
				(arc
					(start 62.347348 -408.923998)
					(mid 62.367272 -408.933234)
					(end 62.389004 -408.936444)
				)
				(arc
					(start 62.583568 -408.936444)
					(mid 62.63745 -408.914126)
					(end 62.659768 -408.860244)
				)
				(arc
					(start 62.659768 -408.174444)
					(mid 62.63745 -408.120562)
					(end 62.583568 -408.098244)
				)
				(arc
					(start 62.389004 -408.098244)
					(mid 62.36726 -408.101412)
					(end 62.347348 -408.11069)
				)
				(arc
					(start 62.051184 -408.303476)
					(mid 62.0095 -408.315698)
					(end 61.967872 -408.303222)
				)
				(arc
					(start 61.674248 -408.11069)
					(mid 61.654324 -408.101454)
					(end 61.632592 -408.098244)
				)
				(arc
					(start 61.438028 -408.098244)
					(mid 61.384146 -408.120562)
					(end 61.361828 -408.174444)
				)
			)
		)
	)
	(zone
		(layer "In1.Cu")
		(hatch none 0.5)
		(connect_pads
			(clearance 0)
		)
		(min_thickness 0.25)
		(keepout
			(tracks not_allowed)
			(vias allowed)
			(pads allowed)
			(copperpour not_allowed)
			(footprints allowed)
		)
		(placement
			(enabled no)
			(sheetname "")
		)
		(fill
			(thermal_gap 0.5)
			(thermal_bridge_width 0.5)
			(island_removal_mode 0)
		)
		(polygon
			(pts
				(xy 139.156186 -15.825978) (xy 140.137134 -15.825978) (xy 140.137134 -17.273778) (xy 139.156186 -17.273778)
			)
		)
	)
	(zone
		(layer "In1.Cu")
		(hatch none 0.5)
		(connect_pads
			(clearance 0)
		)
		(min_thickness 0.25)
		(keepout
			(tracks not_allowed)
			(vias allowed)
			(pads allowed)
			(copperpour not_allowed)
			(footprints allowed)
		)
		(placement
			(enabled no)
			(sheetname "")
		)
		(fill
			(thermal_gap 0.5)
			(thermal_bridge_width 0.5)
			(island_removal_mode 0)
		)
		(polygon
			(pts
				(arc
					(start 389.5852 -402.713952)
					(mid 389.607518 -402.767834)
					(end 389.6614 -402.790152)
				)
				(arc
					(start 389.85698 -402.790152)
					(mid 389.878856 -402.78702)
					(end 389.89889 -402.777706)
				)
				(arc
					(start 390.192514 -402.585174)
					(mid 390.23417 -402.572772)
					(end 390.275826 -402.585174)
				)
				(arc
					(start 390.57072 -402.777706)
					(mid 390.590644 -402.786942)
					(end 390.612376 -402.790152)
				)
				(arc
					(start 390.80694 -402.790152)
					(mid 390.860822 -402.767834)
					(end 390.88314 -402.713952)
				)
				(arc
					(start 390.88314 -402.028152)
					(mid 390.860822 -401.97427)
					(end 390.80694 -401.951952)
				)
				(arc
					(start 390.612376 -401.951952)
					(mid 390.590632 -401.95512)
					(end 390.57072 -401.964398)
				)
				(arc
					(start 390.274556 -402.157184)
					(mid 390.232872 -402.169406)
					(end 390.191244 -402.15693)
				)
				(arc
					(start 389.89762 -401.964398)
					(mid 389.877696 -401.955162)
					(end 389.855964 -401.951952)
				)
				(arc
					(start 389.6614 -401.951952)
					(mid 389.607518 -401.97427)
					(end 389.5852 -402.028152)
				)
			)
		)
	)
	(zone
		(layer "In1.Cu")
		(hatch none 0.5)
		(connect_pads
			(clearance 0)
		)
		(min_thickness 0.25)
		(keepout
			(tracks not_allowed)
			(vias allowed)
			(pads allowed)
			(copperpour not_allowed)
			(footprints allowed)
		)
		(placement
			(enabled no)
			(sheetname "")
		)
		(fill
			(thermal_gap 0.5)
			(thermal_bridge_width 0.5)
			(island_removal_mode 0)
		)
		(polygon
			(pts
				(arc
					(start 176.38268 -55.436008)
					(mid 176.328798 -55.41369)
					(end 176.30648 -55.359808)
				)
				(arc
					(start 176.30648 -54.727348)
					(mid 176.328798 -54.673466)
					(end 176.38268 -54.651148)
				)
				(arc
					(start 177.83556 -54.651148)
					(mid 177.889442 -54.673466)
					(end 177.91176 -54.727348)
				)
				(arc
					(start 177.91176 -55.359808)
					(mid 177.889442 -55.41369)
					(end 177.83556 -55.436008)
				)
			)
		)
	)
	(zone
		(layer "In1.Cu")
		(hatch none 0.5)
		(connect_pads
			(clearance 0)
		)
		(min_thickness 0.25)
		(keepout
			(tracks not_allowed)
			(vias allowed)
			(pads allowed)
			(copperpour not_allowed)
			(footprints allowed)
		)
		(placement
			(enabled no)
			(sheetname "")
		)
		(fill
			(thermal_gap 0.5)
			(thermal_bridge_width 0.5)
			(island_removal_mode 0)
		)
		(polygon
			(pts
				(arc
					(start 123.001024 -402.713952)
					(mid 123.023342 -402.767834)
					(end 123.077224 -402.790152)
				)
				(arc
					(start 123.272804 -402.790152)
					(mid 123.29468 -402.78702)
					(end 123.314714 -402.777706)
				)
				(arc
					(start 123.608338 -402.585174)
					(mid 123.649994 -402.572772)
					(end 123.69165 -402.585174)
				)
				(arc
					(start 123.986544 -402.777706)
					(mid 124.006468 -402.786942)
					(end 124.0282 -402.790152)
				)
				(arc
					(start 124.222764 -402.790152)
					(mid 124.276646 -402.767834)
					(end 124.298964 -402.713952)
				)
				(arc
					(start 124.298964 -402.028152)
					(mid 124.276646 -401.97427)
					(end 124.222764 -401.951952)
				)
				(arc
					(start 124.0282 -401.951952)
					(mid 124.006456 -401.95512)
					(end 123.986544 -401.964398)
				)
				(arc
					(start 123.69038 -402.157184)
					(mid 123.648696 -402.169406)
					(end 123.607068 -402.15693)
				)
				(arc
					(start 123.313444 -401.964398)
					(mid 123.29352 -401.955162)
					(end 123.271788 -401.951952)
				)
				(arc
					(start 123.077224 -401.951952)
					(mid 123.023342 -401.97427)
					(end 123.001024 -402.028152)
				)
			)
		)
	)
	(zone
		(layer "In1.Cu")
		(hatch none 0.5)
		(connect_pads
			(clearance 0)
		)
		(min_thickness 0.25)
		(keepout
			(tracks not_allowed)
			(vias allowed)
			(pads allowed)
			(copperpour not_allowed)
			(footprints allowed)
		)
		(placement
			(enabled no)
			(sheetname "")
		)
		(fill
			(thermal_gap 0.5)
			(thermal_bridge_width 0.5)
			(island_removal_mode 0)
		)
		(polygon
			(pts
				(arc
					(start 20.078192 -397.440912)
					(mid 20.117233 -397.433155)
					(end 20.150074 -397.410686)
				)
				(arc
					(start 20.150074 -397.410686)
					(mid 20.170116 -397.379998)
					(end 20.17776 -397.344138)
				)
				(xy 20.17776 -397.201898) (xy 20.177506 -397.201898)
				(arc
					(start 20.177506 -396.274544)
					(mid 20.148316 -396.211038)
					(end 20.084288 -396.183104)
				)
				(arc
					(start 19.777456 -396.183104)
					(mid 19.738415 -396.190861)
					(end 19.705574 -396.21333)
				)
				(arc
					(start 19.705574 -396.21333)
					(mid 19.685532 -396.244018)
					(end 19.677888 -396.279878)
				)
				(xy 19.677888 -397.311118) (xy 19.678142 -397.311118)
				(arc
					(start 19.678142 -397.349472)
					(mid 19.707332 -397.412978)
					(end 19.77136 -397.440912)
				)
			)
		)
	)
	(zone
		(layer "In1.Cu")
		(hatch none 0.5)
		(connect_pads
			(clearance 0)
		)
		(min_thickness 0.25)
		(keepout
			(tracks not_allowed)
			(vias allowed)
			(pads allowed)
			(copperpour not_allowed)
			(footprints allowed)
		)
		(placement
			(enabled no)
			(sheetname "")
		)
		(fill
			(thermal_gap 0.5)
			(thermal_bridge_width 0.5)
			(island_removal_mode 0)
		)
		(polygon
			(pts
				(arc
					(start 376.986038 0.929894)
					(mid 377.008356 0.983776)
					(end 377.062238 1.006094)
				)
				(arc
					(start 377.674378 1.006094)
					(mid 377.72826 0.983776)
					(end 377.750578 0.929894)
				)
				(arc
					(start 377.750578 -0.167386)
					(mid 377.72826 -0.221268)
					(end 377.674378 -0.243586)
				)
				(arc
					(start 377.062238 -0.243586)
					(mid 377.008356 -0.221268)
					(end 376.986038 -0.167386)
				)
			)
		)
	)
	(zone
		(layer "In1.Cu")
		(hatch none 0.5)
		(connect_pads
			(clearance 0)
		)
		(min_thickness 0.25)
		(keepout
			(tracks not_allowed)
			(vias allowed)
			(pads allowed)
			(copperpour not_allowed)
			(footprints allowed)
		)
		(placement
			(enabled no)
			(sheetname "")
		)
		(fill
			(thermal_gap 0.5)
			(thermal_bridge_width 0.5)
			(island_removal_mode 0)
		)
		(polygon
			(pts
				(arc
					(start 147.506944 -402.713952)
					(mid 147.529262 -402.767834)
					(end 147.583144 -402.790152)
				)
				(arc
					(start 147.778724 -402.790152)
					(mid 147.8006 -402.78702)
					(end 147.820634 -402.777706)
				)
				(arc
					(start 148.114258 -402.585174)
					(mid 148.155914 -402.572772)
					(end 148.19757 -402.585174)
				)
				(arc
					(start 148.492464 -402.777706)
					(mid 148.512388 -402.786942)
					(end 148.53412 -402.790152)
				)
				(arc
					(start 148.728684 -402.790152)
					(mid 148.782566 -402.767834)
					(end 148.804884 -402.713952)
				)
				(arc
					(start 148.804884 -402.028152)
					(mid 148.782566 -401.97427)
					(end 148.728684 -401.951952)
				)
				(arc
					(start 148.53412 -401.951952)
					(mid 148.512376 -401.95512)
					(end 148.492464 -401.964398)
				)
				(arc
					(start 148.1963 -402.157184)
					(mid 148.154616 -402.169406)
					(end 148.112988 -402.15693)
				)
				(arc
					(start 147.819364 -401.964398)
					(mid 147.79944 -401.955162)
					(end 147.777708 -401.951952)
				)
				(arc
					(start 147.583144 -401.951952)
					(mid 147.529262 -401.97427)
					(end 147.506944 -402.028152)
				)
			)
		)
	)
	(zone
		(layer "In1.Cu")
		(hatch none 0.5)
		(connect_pads
			(clearance 0)
		)
		(min_thickness 0.25)
		(keepout
			(tracks not_allowed)
			(vias allowed)
			(pads allowed)
			(copperpour not_allowed)
			(footprints allowed)
		)
		(placement
			(enabled no)
			(sheetname "")
		)
		(fill
			(thermal_gap 0.5)
			(thermal_bridge_width 0.5)
			(island_removal_mode 0)
		)
		(polygon
			(pts
				(arc
					(start 158.042864 -408.860244)
					(mid 158.065182 -408.914126)
					(end 158.119064 -408.936444)
				)
				(arc
					(start 158.314644 -408.936444)
					(mid 158.33652 -408.933312)
					(end 158.356554 -408.923998)
				)
				(arc
					(start 158.650178 -408.731466)
					(mid 158.691834 -408.719064)
					(end 158.73349 -408.731466)
				)
				(arc
					(start 159.028384 -408.923998)
					(mid 159.048308 -408.933234)
					(end 159.07004 -408.936444)
				)
				(arc
					(start 159.264604 -408.936444)
					(mid 159.318486 -408.914126)
					(end 159.340804 -408.860244)
				)
				(arc
					(start 159.340804 -408.174444)
					(mid 159.318486 -408.120562)
					(end 159.264604 -408.098244)
				)
				(arc
					(start 159.07004 -408.098244)
					(mid 159.048296 -408.101412)
					(end 159.028384 -408.11069)
				)
				(arc
					(start 158.73222 -408.303476)
					(mid 158.690536 -408.315698)
					(end 158.648908 -408.303222)
				)
				(arc
					(start 158.355284 -408.11069)
					(mid 158.33536 -408.101454)
					(end 158.313628 -408.098244)
				)
				(arc
					(start 158.119064 -408.098244)
					(mid 158.065182 -408.120562)
					(end 158.042864 -408.174444)
				)
			)
		)
	)
	(zone
		(layer "In1.Cu")
		(hatch none 0.5)
		(connect_pads
			(clearance 0)
		)
		(min_thickness 0.25)
		(keepout
			(tracks not_allowed)
			(vias allowed)
			(pads allowed)
			(copperpour not_allowed)
			(footprints allowed)
		)
		(placement
			(enabled no)
			(sheetname "")
		)
		(fill
			(thermal_gap 0.5)
			(thermal_bridge_width 0.5)
			(island_removal_mode 0)
		)
		(polygon
			(pts
				(arc
					(start 176.38268 -47.93615)
					(mid 176.328798 -47.913832)
					(end 176.30648 -47.85995)
				)
				(arc
					(start 176.30648 -47.22749)
					(mid 176.328798 -47.173608)
					(end 176.38268 -47.15129)
				)
				(arc
					(start 177.83556 -47.15129)
					(mid 177.889442 -47.173608)
					(end 177.91176 -47.22749)
				)
				(arc
					(start 177.91176 -47.85995)
					(mid 177.889442 -47.913832)
					(end 177.83556 -47.93615)
				)
			)
		)
	)
	(zone
		(layer "In1.Cu")
		(hatch none 0.5)
		(connect_pads
			(clearance 0)
		)
		(min_thickness 0.25)
		(keepout
			(tracks not_allowed)
			(vias allowed)
			(pads allowed)
			(copperpour not_allowed)
			(footprints allowed)
		)
		(placement
			(enabled no)
			(sheetname "")
		)
		(fill
			(thermal_gap 0.5)
			(thermal_bridge_width 0.5)
			(island_removal_mode 0)
		)
		(polygon
			(pts
				(arc
					(start 312.952638 -402.713952)
					(mid 312.974956 -402.767834)
					(end 313.028838 -402.790152)
				)
				(arc
					(start 313.224418 -402.790152)
					(mid 313.246294 -402.78702)
					(end 313.266328 -402.777706)
				)
				(arc
					(start 313.559952 -402.585174)
					(mid 313.601608 -402.572772)
					(end 313.643264 -402.585174)
				)
				(arc
					(start 313.938158 -402.777706)
					(mid 313.958082 -402.786942)
					(end 313.979814 -402.790152)
				)
				(arc
					(start 314.174378 -402.790152)
					(mid 314.22826 -402.767834)
					(end 314.250578 -402.713952)
				)
				(arc
					(start 314.250578 -402.028152)
					(mid 314.22826 -401.97427)
					(end 314.174378 -401.951952)
				)
				(arc
					(start 313.979814 -401.951952)
					(mid 313.95807 -401.95512)
					(end 313.938158 -401.964398)
				)
				(arc
					(start 313.641994 -402.157184)
					(mid 313.60031 -402.169406)
					(end 313.558682 -402.15693)
				)
				(arc
					(start 313.265058 -401.964398)
					(mid 313.245134 -401.955162)
					(end 313.223402 -401.951952)
				)
				(arc
					(start 313.028838 -401.951952)
					(mid 312.974956 -401.97427)
					(end 312.952638 -402.028152)
				)
			)
		)
	)
	(zone
		(layer "In1.Cu")
		(hatch none 0.5)
		(connect_pads
			(clearance 0)
		)
		(min_thickness 0.25)
		(keepout
			(tracks not_allowed)
			(vias allowed)
			(pads allowed)
			(copperpour not_allowed)
			(footprints allowed)
		)
		(placement
			(enabled no)
			(sheetname "")
		)
		(fill
			(thermal_gap 0.5)
			(thermal_bridge_width 0.5)
			(island_removal_mode 0)
		)
		(polygon
			(pts
				(arc
					(start 129.127504 -402.713952)
					(mid 129.149822 -402.767834)
					(end 129.203704 -402.790152)
				)
				(arc
					(start 129.399284 -402.790152)
					(mid 129.42116 -402.78702)
					(end 129.441194 -402.777706)
				)
				(arc
					(start 129.734818 -402.585174)
					(mid 129.776474 -402.572772)
					(end 129.81813 -402.585174)
				)
				(arc
					(start 130.113024 -402.777706)
					(mid 130.132948 -402.786942)
					(end 130.15468 -402.790152)
				)
				(arc
					(start 130.349244 -402.790152)
					(mid 130.403126 -402.767834)
					(end 130.425444 -402.713952)
				)
				(arc
					(start 130.425444 -402.028152)
					(mid 130.403126 -401.97427)
					(end 130.349244 -401.951952)
				)
				(arc
					(start 130.15468 -401.951952)
					(mid 130.132936 -401.95512)
					(end 130.113024 -401.964398)
				)
				(arc
					(start 129.81686 -402.157184)
					(mid 129.775176 -402.169406)
					(end 129.733548 -402.15693)
				)
				(arc
					(start 129.439924 -401.964398)
					(mid 129.42 -401.955162)
					(end 129.398268 -401.951952)
				)
				(arc
					(start 129.203704 -401.951952)
					(mid 129.149822 -401.97427)
					(end 129.127504 -402.028152)
				)
			)
		)
	)
	(zone
		(layer "In1.Cu")
		(hatch none 0.5)
		(connect_pads
			(clearance 0)
		)
		(min_thickness 0.25)
		(keepout
			(tracks not_allowed)
			(vias allowed)
			(pads allowed)
			(copperpour not_allowed)
			(footprints allowed)
		)
		(placement
			(enabled no)
			(sheetname "")
		)
		(fill
			(thermal_gap 0.5)
			(thermal_bridge_width 0.5)
			(island_removal_mode 0)
		)
		(polygon
			(pts
				(arc
					(start 176.38268 -44.936156)
					(mid 176.328798 -44.913838)
					(end 176.30648 -44.859956)
				)
				(arc
					(start 176.30648 -44.227496)
					(mid 176.328798 -44.173614)
					(end 176.38268 -44.151296)
				)
				(arc
					(start 177.83556 -44.151296)
					(mid 177.889442 -44.173614)
					(end 177.91176 -44.227496)
				)
				(arc
					(start 177.91176 -44.859956)
					(mid 177.889442 -44.913838)
					(end 177.83556 -44.936156)
				)
			)
		)
	)
	(zone
		(layer "In1.Cu")
		(hatch none 0.5)
		(connect_pads
			(clearance 0)
		)
		(min_thickness 0.25)
		(keepout
			(tracks not_allowed)
			(vias allowed)
			(pads allowed)
			(copperpour not_allowed)
			(footprints allowed)
		)
		(placement
			(enabled no)
			(sheetname "")
		)
		(fill
			(thermal_gap 0.5)
			(thermal_bridge_width 0.5)
			(island_removal_mode 0)
		)
		(polygon
			(pts
				(arc
					(start 343.585038 -402.713952)
					(mid 343.607356 -402.767834)
					(end 343.661238 -402.790152)
				)
				(arc
					(start 343.856818 -402.790152)
					(mid 343.878694 -402.78702)
					(end 343.898728 -402.777706)
				)
				(arc
					(start 344.192352 -402.585174)
					(mid 344.234008 -402.572772)
					(end 344.275664 -402.585174)
				)
				(arc
					(start 344.570558 -402.777706)
					(mid 344.590482 -402.786942)
					(end 344.612214 -402.790152)
				)
				(arc
					(start 344.806778 -402.790152)
					(mid 344.86066 -402.767834)
					(end 344.882978 -402.713952)
				)
				(arc
					(start 344.882978 -402.028152)
					(mid 344.86066 -401.97427)
					(end 344.806778 -401.951952)
				)
				(arc
					(start 344.612214 -401.951952)
					(mid 344.59047 -401.95512)
					(end 344.570558 -401.964398)
				)
				(arc
					(start 344.274394 -402.157184)
					(mid 344.23271 -402.169406)
					(end 344.191082 -402.15693)
				)
				(arc
					(start 343.897458 -401.964398)
					(mid 343.877534 -401.955162)
					(end 343.855802 -401.951952)
				)
				(arc
					(start 343.661238 -401.951952)
					(mid 343.607356 -401.97427)
					(end 343.585038 -402.028152)
				)
			)
		)
	)
	(zone
		(layer "In1.Cu")
		(hatch none 0.5)
		(connect_pads
			(clearance 0)
		)
		(min_thickness 0.25)
		(keepout
			(tracks not_allowed)
			(vias allowed)
			(pads allowed)
			(copperpour not_allowed)
			(footprints allowed)
		)
		(placement
			(enabled no)
			(sheetname "")
		)
		(fill
			(thermal_gap 0.5)
			(thermal_bridge_width 0.5)
			(island_removal_mode 0)
		)
		(polygon
			(pts
				(arc
					(start 383.45872 -402.713952)
					(mid 383.481038 -402.767834)
					(end 383.53492 -402.790152)
				)
				(arc
					(start 383.7305 -402.790152)
					(mid 383.752376 -402.78702)
					(end 383.77241 -402.777706)
				)
				(arc
					(start 384.066034 -402.585174)
					(mid 384.10769 -402.572772)
					(end 384.149346 -402.585174)
				)
				(arc
					(start 384.44424 -402.777706)
					(mid 384.464164 -402.786942)
					(end 384.485896 -402.790152)
				)
				(arc
					(start 384.68046 -402.790152)
					(mid 384.734342 -402.767834)
					(end 384.75666 -402.713952)
				)
				(arc
					(start 384.75666 -402.028152)
					(mid 384.734342 -401.97427)
					(end 384.68046 -401.951952)
				)
				(arc
					(start 384.485896 -401.951952)
					(mid 384.464152 -401.95512)
					(end 384.44424 -401.964398)
				)
				(arc
					(start 384.148076 -402.157184)
					(mid 384.106392 -402.169406)
					(end 384.064764 -402.15693)
				)
				(arc
					(start 383.77114 -401.964398)
					(mid 383.751216 -401.955162)
					(end 383.729484 -401.951952)
				)
				(arc
					(start 383.53492 -401.951952)
					(mid 383.481038 -401.97427)
					(end 383.45872 -402.028152)
				)
			)
		)
	)
	(zone
		(layer "In1.Cu")
		(hatch none 0.5)
		(connect_pads
			(clearance 0)
		)
		(min_thickness 0.25)
		(keepout
			(tracks not_allowed)
			(vias allowed)
			(pads allowed)
			(copperpour not_allowed)
			(footprints allowed)
		)
		(placement
			(enabled no)
			(sheetname "")
		)
		(fill
			(thermal_gap 0.5)
			(thermal_bridge_width 0.5)
			(island_removal_mode 0)
		)
		(polygon
			(pts
				(arc
					(start 236.03458 -52.961286)
					(mid 235.980698 -52.938968)
					(end 235.95838 -52.885086)
				)
				(arc
					(start 235.95838 -52.057046)
					(mid 235.980698 -52.003164)
					(end 236.03458 -51.980846)
				)
				(arc
					(start 237.1598 -51.980846)
					(mid 237.213682 -52.003164)
					(end 237.236 -52.057046)
				)
				(arc
					(start 237.236 -52.885086)
					(mid 237.213682 -52.938968)
					(end 237.1598 -52.961286)
				)
			)
		)
	)
	(zone
		(layer "In1.Cu")
		(hatch none 0.5)
		(connect_pads
			(clearance 0)
		)
		(min_thickness 0.25)
		(keepout
			(tracks not_allowed)
			(vias allowed)
			(pads allowed)
			(copperpour not_allowed)
			(footprints allowed)
		)
		(placement
			(enabled no)
			(sheetname "")
		)
		(fill
			(thermal_gap 0.5)
			(thermal_bridge_width 0.5)
			(island_removal_mode 0)
		)
		(polygon
			(pts
				(arc
					(start 157.211776 -46.091602)
					(mid 157.250817 -46.083845)
					(end 157.283658 -46.061376)
				)
				(arc
					(start 157.283658 -46.061376)
					(mid 157.3037 -46.030688)
					(end 157.311344 -45.994828)
				)
				(xy 157.311344 -45.852588) (xy 157.31109 -45.852588)
				(arc
					(start 157.31109 -44.925234)
					(mid 157.2819 -44.861728)
					(end 157.217872 -44.833794)
				)
				(arc
					(start 156.91104 -44.833794)
					(mid 156.871999 -44.841551)
					(end 156.839158 -44.86402)
				)
				(arc
					(start 156.839158 -44.86402)
					(mid 156.819116 -44.894708)
					(end 156.811472 -44.930568)
				)
				(xy 156.811472 -45.961808) (xy 156.811726 -45.961808)
				(arc
					(start 156.811726 -46.000162)
					(mid 156.840916 -46.063668)
					(end 156.904944 -46.091602)
				)
			)
		)
	)
	(zone
		(layer "In1.Cu")
		(hatch none 0.5)
		(connect_pads
			(clearance 0)
		)
		(min_thickness 0.25)
		(keepout
			(tracks not_allowed)
			(vias allowed)
			(pads allowed)
			(copperpour not_allowed)
			(footprints allowed)
		)
		(placement
			(enabled no)
			(sheetname "")
		)
		(fill
			(thermal_gap 0.5)
			(thermal_bridge_width 0.5)
			(island_removal_mode 0)
		)
		(polygon
			(pts
				(arc
					(start 372.55196 -408.860244)
					(mid 372.574278 -408.914126)
					(end 372.62816 -408.936444)
				)
				(arc
					(start 372.82374 -408.936444)
					(mid 372.845616 -408.933312)
					(end 372.86565 -408.923998)
				)
				(arc
					(start 373.159274 -408.731466)
					(mid 373.20093 -408.719064)
					(end 373.242586 -408.731466)
				)
				(arc
					(start 373.53748 -408.923998)
					(mid 373.557404 -408.933234)
					(end 373.579136 -408.936444)
				)
				(arc
					(start 373.7737 -408.936444)
					(mid 373.827582 -408.914126)
					(end 373.8499 -408.860244)
				)
				(arc
					(start 373.8499 -408.174444)
					(mid 373.827582 -408.120562)
					(end 373.7737 -408.098244)
				)
				(arc
					(start 373.579136 -408.098244)
					(mid 373.557392 -408.101412)
					(end 373.53748 -408.11069)
				)
				(arc
					(start 373.241316 -408.303476)
					(mid 373.199632 -408.315698)
					(end 373.158004 -408.303222)
				)
				(arc
					(start 372.86438 -408.11069)
					(mid 372.844456 -408.101454)
					(end 372.822724 -408.098244)
				)
				(arc
					(start 372.62816 -408.098244)
					(mid 372.574278 -408.120562)
					(end 372.55196 -408.174444)
				)
			)
		)
	)
	(zone
		(layer "In1.Cu")
		(hatch none 0.5)
		(connect_pads
			(clearance 0)
		)
		(min_thickness 0.25)
		(keepout
			(tracks not_allowed)
			(vias allowed)
			(pads allowed)
			(copperpour not_allowed)
			(footprints allowed)
		)
		(placement
			(enabled no)
			(sheetname "")
		)
		(fill
			(thermal_gap 0.5)
			(thermal_bridge_width 0.5)
			(island_removal_mode 0)
		)
		(polygon
			(pts
				(arc
					(start 18.490438 -395.381734)
					(mid 18.451397 -395.389491)
					(end 18.418556 -395.41196)
				)
				(arc
					(start 18.418556 -395.41196)
					(mid 18.398514 -395.442648)
					(end 18.39087 -395.478508)
				)
				(xy 18.39087 -395.620748) (xy 18.391124 -395.620748)
				(arc
					(start 18.391124 -396.548102)
					(mid 18.420314 -396.611608)
					(end 18.484342 -396.639542)
				)
				(arc
					(start 18.791174 -396.639542)
					(mid 18.830215 -396.631785)
					(end 18.863056 -396.609316)
				)
				(arc
					(start 18.863056 -396.609316)
					(mid 18.883098 -396.578628)
					(end 18.890742 -396.542768)
				)
				(xy 18.890742 -395.511528) (xy 18.890488 -395.511528)
				(arc
					(start 18.890488 -395.473174)
					(mid 18.861298 -395.409668)
					(end 18.79727 -395.381734)
				)
			)
		)
	)
	(zone
		(layer "In1.Cu")
		(hatch none 0.5)
		(connect_pads
			(clearance 0)
		)
		(min_thickness 0.25)
		(keepout
			(tracks not_allowed)
			(vias allowed)
			(pads allowed)
			(copperpour not_allowed)
			(footprints allowed)
		)
		(placement
			(enabled no)
			(sheetname "")
		)
		(fill
			(thermal_gap 0.5)
			(thermal_bridge_width 0.5)
			(island_removal_mode 0)
		)
		(polygon
			(pts
				(arc
					(start 325.205598 -402.713952)
					(mid 325.227916 -402.767834)
					(end 325.281798 -402.790152)
				)
				(arc
					(start 325.477378 -402.790152)
					(mid 325.499254 -402.78702)
					(end 325.519288 -402.777706)
				)
				(arc
					(start 325.812912 -402.585174)
					(mid 325.854568 -402.572772)
					(end 325.896224 -402.585174)
				)
				(arc
					(start 326.191118 -402.777706)
					(mid 326.211042 -402.786942)
					(end 326.232774 -402.790152)
				)
				(arc
					(start 326.427338 -402.790152)
					(mid 326.48122 -402.767834)
					(end 326.503538 -402.713952)
				)
				(arc
					(start 326.503538 -402.028152)
					(mid 326.48122 -401.97427)
					(end 326.427338 -401.951952)
				)
				(arc
					(start 326.232774 -401.951952)
					(mid 326.21103 -401.95512)
					(end 326.191118 -401.964398)
				)
				(arc
					(start 325.894954 -402.157184)
					(mid 325.85327 -402.169406)
					(end 325.811642 -402.15693)
				)
				(arc
					(start 325.518018 -401.964398)
					(mid 325.498094 -401.955162)
					(end 325.476362 -401.951952)
				)
				(arc
					(start 325.281798 -401.951952)
					(mid 325.227916 -401.97427)
					(end 325.205598 -402.028152)
				)
			)
		)
	)
	(zone
		(layer "In1.Cu")
		(hatch none 0.5)
		(connect_pads
			(clearance 0)
		)
		(min_thickness 0.25)
		(keepout
			(tracks not_allowed)
			(vias allowed)
			(pads allowed)
			(copperpour not_allowed)
			(footprints allowed)
		)
		(placement
			(enabled no)
			(sheetname "")
		)
		(fill
			(thermal_gap 0.5)
			(thermal_bridge_width 0.5)
			(island_removal_mode 0)
		)
		(polygon
			(pts
				(arc
					(start 389.364474 -19.769328)
					(mid 388.601458 -19.769328)
					(end 389.364474 -19.769328)
				)
			)
		)
	)
	(zone
		(layer "In1.Cu")
		(hatch none 0.5)
		(connect_pads
			(clearance 0)
		)
		(min_thickness 0.25)
		(keepout
			(tracks not_allowed)
			(vias allowed)
			(pads allowed)
			(copperpour not_allowed)
			(footprints allowed)
		)
		(placement
			(enabled no)
			(sheetname "")
		)
		(fill
			(thermal_gap 0.5)
			(thermal_bridge_width 0.5)
			(island_removal_mode 0)
		)
		(polygon
			(pts
				(arc
					(start 30.966918 -7.672324)
					(mid 30.9446 -7.618442)
					(end 30.890718 -7.596124)
				)
				(arc
					(start 29.609288 -7.596124)
					(mid 29.555406 -7.618442)
					(end 29.533088 -7.672324)
				)
				(arc
					(start 29.533088 -9.094724)
					(mid 29.555406 -9.148606)
					(end 29.609288 -9.170924)
				)
				(arc
					(start 30.890718 -9.170924)
					(mid 30.9446 -9.148606)
					(end 30.966918 -9.094724)
				)
			)
		)
	)
	(zone
		(layer "In1.Cu")
		(hatch none 0.5)
		(connect_pads
			(clearance 0)
		)
		(min_thickness 0.25)
		(keepout
			(tracks not_allowed)
			(vias allowed)
			(pads allowed)
			(copperpour not_allowed)
			(footprints allowed)
		)
		(placement
			(enabled no)
			(sheetname "")
		)
		(fill
			(thermal_gap 0.5)
			(thermal_bridge_width 0.5)
			(island_removal_mode 0)
		)
		(polygon
			(pts
				(arc
					(start 371.20576 -402.713952)
					(mid 371.228078 -402.767834)
					(end 371.28196 -402.790152)
				)
				(arc
					(start 371.47754 -402.790152)
					(mid 371.499416 -402.78702)
					(end 371.51945 -402.777706)
				)
				(arc
					(start 371.813074 -402.585174)
					(mid 371.85473 -402.572772)
					(end 371.896386 -402.585174)
				)
				(arc
					(start 372.19128 -402.777706)
					(mid 372.211204 -402.786942)
					(end 372.232936 -402.790152)
				)
				(arc
					(start 372.4275 -402.790152)
					(mid 372.481382 -402.767834)
					(end 372.5037 -402.713952)
				)
				(arc
					(start 372.5037 -402.028152)
					(mid 372.481382 -401.97427)
					(end 372.4275 -401.951952)
				)
				(arc
					(start 372.232936 -401.951952)
					(mid 372.211192 -401.95512)
					(end 372.19128 -401.964398)
				)
				(arc
					(start 371.895116 -402.157184)
					(mid 371.853432 -402.169406)
					(end 371.811804 -402.15693)
				)
				(arc
					(start 371.51818 -401.964398)
					(mid 371.498256 -401.955162)
					(end 371.476524 -401.951952)
				)
				(arc
					(start 371.28196 -401.951952)
					(mid 371.228078 -401.97427)
					(end 371.20576 -402.028152)
				)
			)
		)
	)
	(zone
		(layer "In1.Cu")
		(hatch none 0.5)
		(connect_pads
			(clearance 0)
		)
		(min_thickness 0.25)
		(keepout
			(tracks not_allowed)
			(vias allowed)
			(pads allowed)
			(copperpour not_allowed)
			(footprints allowed)
		)
		(placement
			(enabled no)
			(sheetname "")
		)
		(fill
			(thermal_gap 0.5)
			(thermal_bridge_width 0.5)
			(island_removal_mode 0)
		)
		(polygon
			(pts
				(arc
					(start 340.41207 -5.242306)
					(mid 340.389752 -5.296188)
					(end 340.33587 -5.318506)
				)
				(arc
					(start 339.72373 -5.318506)
					(mid 339.669848 -5.296188)
					(end 339.64753 -5.242306)
				)
				(arc
					(start 339.64753 -4.145026)
					(mid 339.669848 -4.091144)
					(end 339.72373 -4.068826)
				)
				(arc
					(start 340.33587 -4.068826)
					(mid 340.389752 -4.091144)
					(end 340.41207 -4.145026)
				)
			)
		)
	)
	(zone
		(layer "In1.Cu")
		(hatch none 0.5)
		(connect_pads
			(clearance 0)
		)
		(min_thickness 0.25)
		(keepout
			(tracks not_allowed)
			(vias allowed)
			(pads allowed)
			(copperpour not_allowed)
			(footprints allowed)
		)
		(placement
			(enabled no)
			(sheetname "")
		)
		(fill
			(thermal_gap 0.5)
			(thermal_bridge_width 0.5)
			(island_removal_mode 0)
		)
		(polygon
			(pts
				(arc
					(start 159.051752 -44.46143)
					(mid 159.090793 -44.453673)
					(end 159.123634 -44.431204)
				)
				(arc
					(start 159.123634 -44.431204)
					(mid 159.143676 -44.400516)
					(end 159.15132 -44.364656)
				)
				(xy 159.15132 -44.222416) (xy 159.151066 -44.222416)
				(arc
					(start 159.151066 -43.295062)
					(mid 159.121876 -43.231556)
					(end 159.057848 -43.203622)
				)
				(arc
					(start 158.751016 -43.203622)
					(mid 158.711975 -43.211379)
					(end 158.679134 -43.233848)
				)
				(arc
					(start 158.679134 -43.233848)
					(mid 158.659092 -43.264536)
					(end 158.651448 -43.300396)
				)
				(xy 158.651448 -44.331636) (xy 158.651702 -44.331636)
				(arc
					(start 158.651702 -44.36999)
					(mid 158.680892 -44.433496)
					(end 158.74492 -44.46143)
				)
			)
		)
	)
	(zone
		(layer "In1.Cu")
		(hatch none 0.5)
		(connect_pads
			(clearance 0)
		)
		(min_thickness 0.25)
		(keepout
			(tracks not_allowed)
			(vias allowed)
			(pads allowed)
			(copperpour not_allowed)
			(footprints allowed)
		)
		(placement
			(enabled no)
			(sheetname "")
		)
		(fill
			(thermal_gap 0.5)
			(thermal_bridge_width 0.5)
			(island_removal_mode 0)
		)
		(polygon
			(pts
				(arc
					(start 406.2476 -408.860244)
					(mid 406.269918 -408.914126)
					(end 406.3238 -408.936444)
				)
				(arc
					(start 406.51938 -408.936444)
					(mid 406.541256 -408.933312)
					(end 406.56129 -408.923998)
				)
				(arc
					(start 406.854914 -408.731466)
					(mid 406.89657 -408.719064)
					(end 406.938226 -408.731466)
				)
				(arc
					(start 407.23312 -408.923998)
					(mid 407.253044 -408.933234)
					(end 407.274776 -408.936444)
				)
				(arc
					(start 407.46934 -408.936444)
					(mid 407.523222 -408.914126)
					(end 407.54554 -408.860244)
				)
				(arc
					(start 407.54554 -408.174444)
					(mid 407.523222 -408.120562)
					(end 407.46934 -408.098244)
				)
				(arc
					(start 407.274776 -408.098244)
					(mid 407.253032 -408.101412)
					(end 407.23312 -408.11069)
				)
				(arc
					(start 406.936956 -408.303476)
					(mid 406.895272 -408.315698)
					(end 406.853644 -408.303222)
				)
				(arc
					(start 406.56002 -408.11069)
					(mid 406.540096 -408.101454)
					(end 406.518364 -408.098244)
				)
				(arc
					(start 406.3238 -408.098244)
					(mid 406.269918 -408.120562)
					(end 406.2476 -408.174444)
				)
			)
		)
	)
	(zone
		(layer "In1.Cu")
		(hatch none 0.5)
		(connect_pads
			(clearance 0)
		)
		(min_thickness 0.25)
		(keepout
			(tracks not_allowed)
			(vias allowed)
			(pads allowed)
			(copperpour not_allowed)
			(footprints allowed)
		)
		(placement
			(enabled no)
			(sheetname "")
		)
		(fill
			(thermal_gap 0.5)
			(thermal_bridge_width 0.5)
			(island_removal_mode 0)
		)
		(polygon
			(pts
				(arc
					(start 11.570208 -106.09072)
					(mid 11.609249 -106.082963)
					(end 11.64209 -106.060494)
				)
				(arc
					(start 11.64209 -106.060494)
					(mid 11.662132 -106.029806)
					(end 11.669776 -105.993946)
				)
				(xy 11.669776 -105.851706) (xy 11.669522 -105.851706)
				(arc
					(start 11.669522 -104.924352)
					(mid 11.640332 -104.860846)
					(end 11.576304 -104.832912)
				)
				(arc
					(start 11.269472 -104.832912)
					(mid 11.230431 -104.840669)
					(end 11.19759 -104.863138)
				)
				(arc
					(start 11.19759 -104.863138)
					(mid 11.177548 -104.893826)
					(end 11.169904 -104.929686)
				)
				(xy 11.169904 -105.960926) (xy 11.170158 -105.960926)
				(arc
					(start 11.170158 -105.99928)
					(mid 11.199348 -106.062786)
					(end 11.263376 -106.09072)
				)
			)
		)
	)
	(zone
		(layer "In1.Cu")
		(hatch none 0.5)
		(connect_pads
			(clearance 0)
		)
		(min_thickness 0.25)
		(keepout
			(tracks not_allowed)
			(vias allowed)
			(pads allowed)
			(copperpour not_allowed)
			(footprints allowed)
		)
		(placement
			(enabled no)
			(sheetname "")
		)
		(fill
			(thermal_gap 0.5)
			(thermal_bridge_width 0.5)
			(island_removal_mode 0)
		)
		(polygon
			(pts
				(arc
					(start 212.967316 -5.2451)
					(mid 212.944998 -5.298982)
					(end 212.891116 -5.3213)
				)
				(arc
					(start 212.278976 -5.3213)
					(mid 212.225094 -5.298982)
					(end 212.202776 -5.2451)
				)
				(arc
					(start 212.202776 -4.14782)
					(mid 212.225094 -4.093938)
					(end 212.278976 -4.07162)
				)
				(arc
					(start 212.891116 -4.07162)
					(mid 212.944998 -4.093938)
					(end 212.967316 -4.14782)
				)
			)
		)
	)
	(zone
		(layer "In1.Cu")
		(hatch none 0.5)
		(connect_pads
			(clearance 0)
		)
		(min_thickness 0.25)
		(keepout
			(tracks not_allowed)
			(vias allowed)
			(pads allowed)
			(copperpour not_allowed)
			(footprints allowed)
		)
		(placement
			(enabled no)
			(sheetname "")
		)
		(fill
			(thermal_gap 0.5)
			(thermal_bridge_width 0.5)
			(island_removal_mode 0)
		)
		(polygon
			(pts
				(arc
					(start 337.458558 -402.713952)
					(mid 337.480876 -402.767834)
					(end 337.534758 -402.790152)
				)
				(arc
					(start 337.730338 -402.790152)
					(mid 337.752214 -402.78702)
					(end 337.772248 -402.777706)
				)
				(arc
					(start 338.065872 -402.585174)
					(mid 338.107528 -402.572772)
					(end 338.149184 -402.585174)
				)
				(arc
					(start 338.444078 -402.777706)
					(mid 338.464002 -402.786942)
					(end 338.485734 -402.790152)
				)
				(arc
					(start 338.680298 -402.790152)
					(mid 338.73418 -402.767834)
					(end 338.756498 -402.713952)
				)
				(arc
					(start 338.756498 -402.028152)
					(mid 338.73418 -401.97427)
					(end 338.680298 -401.951952)
				)
				(arc
					(start 338.485734 -401.951952)
					(mid 338.46399 -401.95512)
					(end 338.444078 -401.964398)
				)
				(arc
					(start 338.147914 -402.157184)
					(mid 338.10623 -402.169406)
					(end 338.064602 -402.15693)
				)
				(arc
					(start 337.770978 -401.964398)
					(mid 337.751054 -401.955162)
					(end 337.729322 -401.951952)
				)
				(arc
					(start 337.534758 -401.951952)
					(mid 337.480876 -401.97427)
					(end 337.458558 -402.028152)
				)
			)
		)
	)
	(zone
		(layer "In1.Cu")
		(hatch none 0.5)
		(connect_pads
			(clearance 0)
		)
		(min_thickness 0.25)
		(keepout
			(tracks not_allowed)
			(vias allowed)
			(pads allowed)
			(copperpour not_allowed)
			(footprints allowed)
		)
		(placement
			(enabled no)
			(sheetname "")
		)
		(fill
			(thermal_gap 0.5)
			(thermal_bridge_width 0.5)
			(island_removal_mode 0)
		)
		(polygon
			(pts
				(arc
					(start 63.078868 -402.713952)
					(mid 63.101186 -402.767834)
					(end 63.155068 -402.790152)
				)
				(arc
					(start 63.350648 -402.790152)
					(mid 63.372524 -402.78702)
					(end 63.392558 -402.777706)
				)
				(arc
					(start 63.686182 -402.585174)
					(mid 63.727838 -402.572772)
					(end 63.769494 -402.585174)
				)
				(arc
					(start 64.064388 -402.777706)
					(mid 64.084312 -402.786942)
					(end 64.106044 -402.790152)
				)
				(arc
					(start 64.300608 -402.790152)
					(mid 64.35449 -402.767834)
					(end 64.376808 -402.713952)
				)
				(arc
					(start 64.376808 -402.028152)
					(mid 64.35449 -401.97427)
					(end 64.300608 -401.951952)
				)
				(arc
					(start 64.106044 -401.951952)
					(mid 64.0843 -401.95512)
					(end 64.064388 -401.964398)
				)
				(arc
					(start 63.768224 -402.157184)
					(mid 63.72654 -402.169406)
					(end 63.684912 -402.15693)
				)
				(arc
					(start 63.391288 -401.964398)
					(mid 63.371364 -401.955162)
					(end 63.349632 -401.951952)
				)
				(arc
					(start 63.155068 -401.951952)
					(mid 63.101186 -401.97427)
					(end 63.078868 -402.028152)
				)
			)
		)
	)
	(zone
		(layer "In1.Cu")
		(hatch none 0.5)
		(connect_pads
			(clearance 0)
		)
		(min_thickness 0.25)
		(keepout
			(tracks not_allowed)
			(vias allowed)
			(pads allowed)
			(copperpour not_allowed)
			(footprints allowed)
		)
		(placement
			(enabled no)
			(sheetname "")
		)
		(fill
			(thermal_gap 0.5)
			(thermal_bridge_width 0.5)
			(island_removal_mode 0)
		)
		(polygon
			(pts
				(arc
					(start 72.268588 -402.713952)
					(mid 72.290906 -402.767834)
					(end 72.344788 -402.790152)
				)
				(arc
					(start 72.540368 -402.790152)
					(mid 72.562244 -402.78702)
					(end 72.582278 -402.777706)
				)
				(arc
					(start 72.875902 -402.585174)
					(mid 72.917558 -402.572772)
					(end 72.959214 -402.585174)
				)
				(arc
					(start 73.254108 -402.777706)
					(mid 73.274032 -402.786942)
					(end 73.295764 -402.790152)
				)
				(arc
					(start 73.490328 -402.790152)
					(mid 73.54421 -402.767834)
					(end 73.566528 -402.713952)
				)
				(arc
					(start 73.566528 -402.028152)
					(mid 73.54421 -401.97427)
					(end 73.490328 -401.951952)
				)
				(arc
					(start 73.295764 -401.951952)
					(mid 73.27402 -401.95512)
					(end 73.254108 -401.964398)
				)
				(arc
					(start 72.957944 -402.157184)
					(mid 72.91626 -402.169406)
					(end 72.874632 -402.15693)
				)
				(arc
					(start 72.581008 -401.964398)
					(mid 72.561084 -401.955162)
					(end 72.539352 -401.951952)
				)
				(arc
					(start 72.344788 -401.951952)
					(mid 72.290906 -401.97427)
					(end 72.268588 -402.028152)
				)
			)
		)
	)
	(zone
		(layer "In1.Cu")
		(hatch none 0.5)
		(connect_pads
			(clearance 0)
		)
		(min_thickness 0.25)
		(keepout
			(tracks not_allowed)
			(vias allowed)
			(pads allowed)
			(copperpour not_allowed)
			(footprints allowed)
		)
		(placement
			(enabled no)
			(sheetname "")
		)
		(fill
			(thermal_gap 0.5)
			(thermal_bridge_width 0.5)
			(island_removal_mode 0)
		)
		(polygon
			(pts
				(arc
					(start 183.259476 2.3749)
					(mid 183.237158 2.321018)
					(end 183.183276 2.2987)
				)
				(arc
					(start 182.571136 2.2987)
					(mid 182.517254 2.321018)
					(end 182.494936 2.3749)
				)
				(arc
					(start 182.494936 3.47218)
					(mid 182.517254 3.526062)
					(end 182.571136 3.54838)
				)
				(arc
					(start 183.183276 3.54838)
					(mid 183.237158 3.526062)
					(end 183.259476 3.47218)
				)
			)
		)
	)
	(zone
		(layer "In1.Cu")
		(hatch none 0.5)
		(connect_pads
			(clearance 0)
		)
		(min_thickness 0.25)
		(keepout
			(tracks not_allowed)
			(vias allowed)
			(pads allowed)
			(copperpour not_allowed)
			(footprints allowed)
		)
		(placement
			(enabled no)
			(sheetname "")
		)
		(fill
			(thermal_gap 0.5)
			(thermal_bridge_width 0.5)
			(island_removal_mode 0)
		)
		(polygon
			(pts
				(arc
					(start 349.153734 -67.97548)
					(mid 349.099852 -67.997798)
					(end 349.077534 -68.05168)
				)
				(arc
					(start 349.077534 -68.38188)
					(mid 349.099852 -68.435762)
					(end 349.153734 -68.45808)
				)
				(arc
					(start 349.407734 -68.45808)
					(mid 349.461616 -68.435762)
					(end 349.483934 -68.38188)
				)
				(arc
					(start 349.483934 -68.05168)
					(mid 349.461616 -67.997798)
					(end 349.407734 -67.97548)
				)
			)
		)
	)
	(zone
		(layer "In1.Cu")
		(hatch none 0.5)
		(connect_pads
			(clearance 0)
		)
		(min_thickness 0.25)
		(keepout
			(tracks not_allowed)
			(vias allowed)
			(pads allowed)
			(copperpour not_allowed)
			(footprints allowed)
		)
		(placement
			(enabled no)
			(sheetname "")
		)
		(fill
			(thermal_gap 0.5)
			(thermal_bridge_width 0.5)
			(island_removal_mode 0)
		)
		(polygon
			(pts
				(arc
					(start 133.16585 -12.952222)
					(mid 133.143532 -12.89834)
					(end 133.08965 -12.876022)
				)
				(arc
					(start 131.80822 -12.876022)
					(mid 131.754338 -12.89834)
					(end 131.73202 -12.952222)
				)
				(arc
					(start 131.73202 -14.374622)
					(mid 131.754338 -14.428504)
					(end 131.80822 -14.450822)
				)
				(arc
					(start 133.08965 -14.450822)
					(mid 133.143532 -14.428504)
					(end 133.16585 -14.374622)
				)
			)
		)
	)
	(zone
		(layer "In1.Cu")
		(hatch none 0.5)
		(connect_pads
			(clearance 0)
		)
		(min_thickness 0.25)
		(keepout
			(tracks not_allowed)
			(vias allowed)
			(pads allowed)
			(copperpour not_allowed)
			(footprints allowed)
		)
		(placement
			(enabled no)
			(sheetname "")
		)
		(fill
			(thermal_gap 0.5)
			(thermal_bridge_width 0.5)
			(island_removal_mode 0)
		)
		(polygon
			(pts
				(arc
					(start 24.128984 -11.91768)
					(mid 24.151302 -11.971562)
					(end 24.205184 -11.99388)
				)
				(arc
					(start 25.486614 -11.99388)
					(mid 25.540496 -11.971562)
					(end 25.562814 -11.91768)
				)
				(arc
					(start 25.562814 -10.49528)
					(mid 25.540496 -10.441398)
					(end 25.486614 -10.41908)
				)
				(arc
					(start 24.205184 -10.41908)
					(mid 24.151302 -10.441398)
					(end 24.128984 -10.49528)
				)
			)
		)
	)
	(zone
		(layer "In1.Cu")
		(hatch none 0.5)
		(connect_pads
			(clearance 0)
		)
		(min_thickness 0.25)
		(keepout
			(tracks not_allowed)
			(vias allowed)
			(pads allowed)
			(copperpour not_allowed)
			(footprints allowed)
		)
		(placement
			(enabled no)
			(sheetname "")
		)
		(fill
			(thermal_gap 0.5)
			(thermal_bridge_width 0.5)
			(island_removal_mode 0)
		)
		(polygon
			(pts
				(arc
					(start 44.039028 -11.91768)
					(mid 44.061346 -11.971562)
					(end 44.115228 -11.99388)
				)
				(arc
					(start 45.396658 -11.99388)
					(mid 45.45054 -11.971562)
					(end 45.472858 -11.91768)
				)
				(arc
					(start 45.472858 -10.49528)
					(mid 45.45054 -10.441398)
					(end 45.396658 -10.41908)
				)
				(arc
					(start 44.115228 -10.41908)
					(mid 44.061346 -10.441398)
					(end 44.039028 -10.49528)
				)
			)
		)
	)
	(zone
		(layer "In1.Cu")
		(hatch none 0.5)
		(connect_pads
			(clearance 0)
		)
		(min_thickness 0.25)
		(keepout
			(tracks not_allowed)
			(vias allowed)
			(pads allowed)
			(copperpour not_allowed)
			(footprints allowed)
		)
		(placement
			(enabled no)
			(sheetname "")
		)
		(fill
			(thermal_gap 0.5)
			(thermal_bridge_width 0.5)
			(island_removal_mode 0)
		)
		(polygon
			(pts
				(xy 17.16786 -9.05637) (xy 17.16786 -7.59841) (xy 18.1356 -7.59841) (xy 18.1356 -9.05637)
			)
		)
	)
	(zone
		(layer "In1.Cu")
		(hatch none 0.5)
		(connect_pads
			(clearance 0)
		)
		(min_thickness 0.25)
		(keepout
			(tracks not_allowed)
			(vias allowed)
			(pads allowed)
			(copperpour not_allowed)
			(footprints allowed)
		)
		(placement
			(enabled no)
			(sheetname "")
		)
		(fill
			(thermal_gap 0.5)
			(thermal_bridge_width 0.5)
			(island_removal_mode 0)
		)
		(polygon
			(pts
				(arc
					(start 384.80492 -408.860244)
					(mid 384.827238 -408.914126)
					(end 384.88112 -408.936444)
				)
				(arc
					(start 385.0767 -408.936444)
					(mid 385.098576 -408.933312)
					(end 385.11861 -408.923998)
				)
				(arc
					(start 385.412234 -408.731466)
					(mid 385.45389 -408.719064)
					(end 385.495546 -408.731466)
				)
				(arc
					(start 385.79044 -408.923998)
					(mid 385.810364 -408.933234)
					(end 385.832096 -408.936444)
				)
				(arc
					(start 386.02666 -408.936444)
					(mid 386.080542 -408.914126)
					(end 386.10286 -408.860244)
				)
				(arc
					(start 386.10286 -408.174444)
					(mid 386.080542 -408.120562)
					(end 386.02666 -408.098244)
				)
				(arc
					(start 385.832096 -408.098244)
					(mid 385.810352 -408.101412)
					(end 385.79044 -408.11069)
				)
				(arc
					(start 385.494276 -408.303476)
					(mid 385.452592 -408.315698)
					(end 385.410964 -408.303222)
				)
				(arc
					(start 385.11734 -408.11069)
					(mid 385.097416 -408.101454)
					(end 385.075684 -408.098244)
				)
				(arc
					(start 384.88112 -408.098244)
					(mid 384.827238 -408.120562)
					(end 384.80492 -408.174444)
				)
			)
		)
	)
	(zone
		(layer "In1.Cu")
		(hatch none 0.5)
		(connect_pads
			(clearance 0)
		)
		(min_thickness 0.25)
		(keepout
			(tracks not_allowed)
			(vias allowed)
			(pads allowed)
			(copperpour not_allowed)
			(footprints allowed)
		)
		(placement
			(enabled no)
			(sheetname "")
		)
		(fill
			(thermal_gap 0.5)
			(thermal_bridge_width 0.5)
			(island_removal_mode 0)
		)
		(polygon
			(pts
				(arc
					(start 426.486066 -17.955514)
					(mid 426.508384 -18.009396)
					(end 426.562266 -18.031714)
				)
				(arc
					(start 426.757846 -18.031714)
					(mid 426.779722 -18.028582)
					(end 426.799756 -18.019268)
				)
				(arc
					(start 427.09338 -17.826736)
					(mid 427.135036 -17.814334)
					(end 427.176692 -17.826736)
				)
				(arc
					(start 427.471586 -18.019268)
					(mid 427.49151 -18.028504)
					(end 427.513242 -18.031714)
				)
				(arc
					(start 427.707806 -18.031714)
					(mid 427.761688 -18.009396)
					(end 427.784006 -17.955514)
				)
				(arc
					(start 427.784006 -17.269714)
					(mid 427.761688 -17.215832)
					(end 427.707806 -17.193514)
				)
				(arc
					(start 427.513242 -17.193514)
					(mid 427.491498 -17.196682)
					(end 427.471586 -17.20596)
				)
				(arc
					(start 427.175422 -17.398746)
					(mid 427.133738 -17.410968)
					(end 427.09211 -17.398492)
				)
				(arc
					(start 426.798486 -17.20596)
					(mid 426.778562 -17.196724)
					(end 426.75683 -17.193514)
				)
				(arc
					(start 426.562266 -17.193514)
					(mid 426.508384 -17.215832)
					(end 426.486066 -17.269714)
				)
			)
		)
	)
	(zone
		(layer "In1.Cu")
		(hatch none 0.5)
		(connect_pads
			(clearance 0)
		)
		(min_thickness 0.25)
		(keepout
			(tracks not_allowed)
			(vias allowed)
			(pads allowed)
			(copperpour not_allowed)
			(footprints allowed)
		)
		(placement
			(enabled no)
			(sheetname "")
		)
		(fill
			(thermal_gap 0.5)
			(thermal_bridge_width 0.5)
			(island_removal_mode 0)
		)
		(polygon
			(pts
				(arc
					(start 31.328868 -11.91768)
					(mid 31.351186 -11.971562)
					(end 31.405068 -11.99388)
				)
				(arc
					(start 32.686498 -11.99388)
					(mid 32.74038 -11.971562)
					(end 32.762698 -11.91768)
				)
				(arc
					(start 32.762698 -10.49528)
					(mid 32.74038 -10.441398)
					(end 32.686498 -10.41908)
				)
				(arc
					(start 31.405068 -10.41908)
					(mid 31.351186 -10.441398)
					(end 31.328868 -10.49528)
				)
			)
		)
	)
	(zone
		(layer "In1.Cu")
		(hatch none 0.5)
		(connect_pads
			(clearance 0)
		)
		(min_thickness 0.25)
		(keepout
			(tracks not_allowed)
			(vias allowed)
			(pads allowed)
			(copperpour not_allowed)
			(footprints allowed)
		)
		(placement
			(enabled no)
			(sheetname "")
		)
		(fill
			(thermal_gap 0.5)
			(thermal_bridge_width 0.5)
			(island_removal_mode 0)
		)
		(polygon
			(pts
				(arc
					(start 343.97569 -70.66026)
					(mid 343.953372 -70.606378)
					(end 343.89949 -70.58406)
				)
				(arc
					(start 343.56929 -70.58406)
					(mid 343.515408 -70.606378)
					(end 343.49309 -70.66026)
				)
				(arc
					(start 343.49309 -70.91426)
					(mid 343.515408 -70.968142)
					(end 343.56929 -70.99046)
				)
				(arc
					(start 343.89949 -70.99046)
					(mid 343.953372 -70.968142)
					(end 343.97569 -70.91426)
				)
			)
		)
	)
	(zone
		(layer "In1.Cu")
		(hatch none 0.5)
		(connect_pads
			(clearance 0)
		)
		(min_thickness 0.25)
		(keepout
			(tracks not_allowed)
			(vias allowed)
			(pads allowed)
			(copperpour not_allowed)
			(footprints allowed)
		)
		(placement
			(enabled no)
			(sheetname "")
		)
		(fill
			(thermal_gap 0.5)
			(thermal_bridge_width 0.5)
			(island_removal_mode 0)
		)
		(polygon
			(pts
				(xy 140.956284 -15.825978) (xy 141.937232 -15.825978) (xy 141.937232 -17.273778) (xy 140.956284 -17.273778)
			)
		)
	)
	(zone
		(layer "In1.Cu")
		(hatch none 0.5)
		(connect_pads
			(clearance 0)
		)
		(min_thickness 0.25)
		(keepout
			(tracks not_allowed)
			(vias allowed)
			(pads allowed)
			(copperpour not_allowed)
			(footprints allowed)
		)
		(placement
			(enabled no)
			(sheetname "")
		)
		(fill
			(thermal_gap 0.5)
			(thermal_bridge_width 0.5)
			(island_removal_mode 0)
		)
		(polygon
			(pts
				(arc
					(start 343.97569 -70.12686)
					(mid 343.953372 -70.072978)
					(end 343.89949 -70.05066)
				)
				(arc
					(start 343.56929 -70.05066)
					(mid 343.515408 -70.072978)
					(end 343.49309 -70.12686)
				)
				(arc
					(start 343.49309 -70.38086)
					(mid 343.515408 -70.434742)
					(end 343.56929 -70.45706)
				)
				(arc
					(start 343.89949 -70.45706)
					(mid 343.953372 -70.434742)
					(end 343.97569 -70.38086)
				)
			)
		)
	)
	(zone
		(layer "In1.Cu")
		(hatch none 0.5)
		(connect_pads
			(clearance 0)
		)
		(min_thickness 0.25)
		(keepout
			(tracks not_allowed)
			(vias allowed)
			(pads allowed)
			(copperpour not_allowed)
			(footprints allowed)
		)
		(placement
			(enabled no)
			(sheetname "")
		)
		(fill
			(thermal_gap 0.5)
			(thermal_bridge_width 0.5)
			(island_removal_mode 0)
		)
		(polygon
			(pts
				(arc
					(start 249.541284 -4.1529)
					(mid 249.563602 -4.099018)
					(end 249.617484 -4.0767)
				)
				(arc
					(start 250.229624 -4.0767)
					(mid 250.283506 -4.099018)
					(end 250.305824 -4.1529)
				)
				(arc
					(start 250.305824 -5.25018)
					(mid 250.283506 -5.304062)
					(end 250.229624 -5.32638)
				)
				(arc
					(start 249.617484 -5.32638)
					(mid 249.563602 -5.304062)
					(end 249.541284 -5.25018)
				)
			)
		)
	)
	(zone
		(layer "In1.Cu")
		(hatch none 0.5)
		(connect_pads
			(clearance 0)
		)
		(min_thickness 0.25)
		(keepout
			(tracks not_allowed)
			(vias allowed)
			(pads allowed)
			(copperpour not_allowed)
			(footprints allowed)
		)
		(placement
			(enabled no)
			(sheetname "")
		)
		(fill
			(thermal_gap 0.5)
			(thermal_bridge_width 0.5)
			(island_removal_mode 0)
		)
		(polygon
			(pts
				(arc
					(start 344.89009 -70.66026)
					(mid 344.867772 -70.606378)
					(end 344.81389 -70.58406)
				)
				(arc
					(start 344.48369 -70.58406)
					(mid 344.429808 -70.606378)
					(end 344.40749 -70.66026)
				)
				(arc
					(start 344.40749 -70.91426)
					(mid 344.429808 -70.968142)
					(end 344.48369 -70.99046)
				)
				(arc
					(start 344.81389 -70.99046)
					(mid 344.867772 -70.968142)
					(end 344.89009 -70.91426)
				)
			)
		)
	)
	(zone
		(layer "In1.Cu")
		(hatch none 0.5)
		(connect_pads
			(clearance 0)
		)
		(min_thickness 0.25)
		(keepout
			(tracks not_allowed)
			(vias allowed)
			(pads allowed)
			(copperpour not_allowed)
			(footprints allowed)
		)
		(placement
			(enabled no)
			(sheetname "")
		)
		(fill
			(thermal_gap 0.5)
			(thermal_bridge_width 0.5)
			(island_removal_mode 0)
		)
		(polygon
			(pts
				(arc
					(start 409.382214 -17.955514)
					(mid 409.404532 -18.009396)
					(end 409.458414 -18.031714)
				)
				(arc
					(start 409.653994 -18.031714)
					(mid 409.67587 -18.028582)
					(end 409.695904 -18.019268)
				)
				(arc
					(start 409.989528 -17.826736)
					(mid 410.031184 -17.814334)
					(end 410.07284 -17.826736)
				)
				(arc
					(start 410.367734 -18.019268)
					(mid 410.387658 -18.028504)
					(end 410.40939 -18.031714)
				)
				(arc
					(start 410.603954 -18.031714)
					(mid 410.657836 -18.009396)
					(end 410.680154 -17.955514)
				)
				(arc
					(start 410.680154 -17.269714)
					(mid 410.657836 -17.215832)
					(end 410.603954 -17.193514)
				)
				(arc
					(start 410.40939 -17.193514)
					(mid 410.387646 -17.196682)
					(end 410.367734 -17.20596)
				)
				(arc
					(start 410.07157 -17.398746)
					(mid 410.029886 -17.410968)
					(end 409.988258 -17.398492)
				)
				(arc
					(start 409.694634 -17.20596)
					(mid 409.67471 -17.196724)
					(end 409.652978 -17.193514)
				)
				(arc
					(start 409.458414 -17.193514)
					(mid 409.404532 -17.215832)
					(end 409.382214 -17.269714)
				)
			)
		)
	)
	(zone
		(layer "In1.Cu")
		(hatch none 0.5)
		(connect_pads
			(clearance 0)
		)
		(min_thickness 0.25)
		(keepout
			(tracks not_allowed)
			(vias allowed)
			(pads allowed)
			(copperpour not_allowed)
			(footprints allowed)
		)
		(placement
			(enabled no)
			(sheetname "")
		)
		(fill
			(thermal_gap 0.5)
			(thermal_bridge_width 0.5)
			(island_removal_mode 0)
		)
		(polygon
			(pts
				(arc
					(start 158.902654 -42.24909)
					(mid 158.140654 -42.24909)
					(end 158.902654 -42.24909)
				)
			)
		)
	)
	(zone
		(layer "In1.Cu")
		(hatch none 0.5)
		(connect_pads
			(clearance 0)
		)
		(min_thickness 0.25)
		(keepout
			(tracks not_allowed)
			(vias allowed)
			(pads allowed)
			(copperpour not_allowed)
			(footprints allowed)
		)
		(placement
			(enabled no)
			(sheetname "")
		)
		(fill
			(thermal_gap 0.5)
			(thermal_bridge_width 0.5)
			(island_removal_mode 0)
		)
		(polygon
			(pts
				(arc
					(start 75.331828 -402.713952)
					(mid 75.354146 -402.767834)
					(end 75.408028 -402.790152)
				)
				(arc
					(start 75.603608 -402.790152)
					(mid 75.625484 -402.78702)
					(end 75.645518 -402.777706)
				)
				(arc
					(start 75.939142 -402.585174)
					(mid 75.980798 -402.572772)
					(end 76.022454 -402.585174)
				)
				(arc
					(start 76.317348 -402.777706)
					(mid 76.337272 -402.786942)
					(end 76.359004 -402.790152)
				)
				(arc
					(start 76.553568 -402.790152)
					(mid 76.60745 -402.767834)
					(end 76.629768 -402.713952)
				)
				(arc
					(start 76.629768 -402.028152)
					(mid 76.60745 -401.97427)
					(end 76.553568 -401.951952)
				)
				(arc
					(start 76.359004 -401.951952)
					(mid 76.33726 -401.95512)
					(end 76.317348 -401.964398)
				)
				(arc
					(start 76.021184 -402.157184)
					(mid 75.9795 -402.169406)
					(end 75.937872 -402.15693)
				)
				(arc
					(start 75.644248 -401.964398)
					(mid 75.624324 -401.955162)
					(end 75.602592 -401.951952)
				)
				(arc
					(start 75.408028 -401.951952)
					(mid 75.354146 -401.97427)
					(end 75.331828 -402.028152)
				)
			)
		)
	)
	(zone
		(layer "In1.Cu")
		(hatch none 0.5)
		(connect_pads
			(clearance 0)
		)
		(min_thickness 0.25)
		(keepout
			(tracks not_allowed)
			(vias allowed)
			(pads allowed)
			(copperpour not_allowed)
			(footprints allowed)
		)
		(placement
			(enabled no)
			(sheetname "")
		)
		(fill
			(thermal_gap 0.5)
			(thermal_bridge_width 0.5)
			(island_removal_mode 0)
		)
		(polygon
			(pts
				(arc
					(start 319.079118 -402.713952)
					(mid 319.101436 -402.767834)
					(end 319.155318 -402.790152)
				)
				(arc
					(start 319.350898 -402.790152)
					(mid 319.372774 -402.78702)
					(end 319.392808 -402.777706)
				)
				(arc
					(start 319.686432 -402.585174)
					(mid 319.728088 -402.572772)
					(end 319.769744 -402.585174)
				)
				(arc
					(start 320.064638 -402.777706)
					(mid 320.084562 -402.786942)
					(end 320.106294 -402.790152)
				)
				(arc
					(start 320.300858 -402.790152)
					(mid 320.35474 -402.767834)
					(end 320.377058 -402.713952)
				)
				(arc
					(start 320.377058 -402.028152)
					(mid 320.35474 -401.97427)
					(end 320.300858 -401.951952)
				)
				(arc
					(start 320.106294 -401.951952)
					(mid 320.08455 -401.95512)
					(end 320.064638 -401.964398)
				)
				(arc
					(start 319.768474 -402.157184)
					(mid 319.72679 -402.169406)
					(end 319.685162 -402.15693)
				)
				(arc
					(start 319.391538 -401.964398)
					(mid 319.371614 -401.955162)
					(end 319.349882 -401.951952)
				)
				(arc
					(start 319.155318 -401.951952)
					(mid 319.101436 -401.97427)
					(end 319.079118 -402.028152)
				)
			)
		)
	)
	(zone
		(layer "In1.Cu")
		(hatch none 0.5)
		(connect_pads
			(clearance 0)
		)
		(min_thickness 0.25)
		(keepout
			(tracks not_allowed)
			(vias allowed)
			(pads allowed)
			(copperpour not_allowed)
			(footprints allowed)
		)
		(placement
			(enabled no)
			(sheetname "")
		)
		(fill
			(thermal_gap 0.5)
			(thermal_bridge_width 0.5)
			(island_removal_mode 0)
		)
		(polygon
			(pts
				(xy 14.9352 -101.910388) (xy 14.9352 -101.191568) (xy 15.69212 -101.191568) (xy 15.69212 -101.910388)
			)
		)
	)
	(zone
		(layer "In1.Cu")
		(hatch none 0.5)
		(connect_pads
			(clearance 0)
		)
		(min_thickness 0.25)
		(keepout
			(tracks not_allowed)
			(vias allowed)
			(pads allowed)
			(copperpour not_allowed)
			(footprints allowed)
		)
		(placement
			(enabled no)
			(sheetname "")
		)
		(fill
			(thermal_gap 0.5)
			(thermal_bridge_width 0.5)
			(island_removal_mode 0)
		)
		(polygon
			(pts
				(arc
					(start 13.63599 -103.908352)
					(mid 12.874498 -103.908352)
					(end 13.63599 -103.908352)
				)
			)
		)
	)
	(zone
		(layer "In1.Cu")
		(hatch none 0.5)
		(connect_pads
			(clearance 0)
		)
		(min_thickness 0.25)
		(keepout
			(tracks not_allowed)
			(vias allowed)
			(pads allowed)
			(copperpour not_allowed)
			(footprints allowed)
		)
		(placement
			(enabled no)
			(sheetname "")
		)
		(fill
			(thermal_gap 0.5)
			(thermal_bridge_width 0.5)
			(island_removal_mode 0)
		)
		(polygon
			(pts
				(arc
					(start 52.172108 -408.860244)
					(mid 52.194426 -408.914126)
					(end 52.248308 -408.936444)
				)
				(arc
					(start 52.443888 -408.936444)
					(mid 52.465764 -408.933312)
					(end 52.485798 -408.923998)
				)
				(arc
					(start 52.779422 -408.731466)
					(mid 52.821078 -408.719064)
					(end 52.862734 -408.731466)
				)
				(arc
					(start 53.157628 -408.923998)
					(mid 53.177552 -408.933234)
					(end 53.199284 -408.936444)
				)
				(arc
					(start 53.393848 -408.936444)
					(mid 53.44773 -408.914126)
					(end 53.470048 -408.860244)
				)
				(arc
					(start 53.470048 -408.174444)
					(mid 53.44773 -408.120562)
					(end 53.393848 -408.098244)
				)
				(arc
					(start 53.199284 -408.098244)
					(mid 53.17754 -408.101412)
					(end 53.157628 -408.11069)
				)
				(arc
					(start 52.861464 -408.303476)
					(mid 52.81978 -408.315698)
					(end 52.778152 -408.303222)
				)
				(arc
					(start 52.484528 -408.11069)
					(mid 52.464604 -408.101454)
					(end 52.442872 -408.098244)
				)
				(arc
					(start 52.248308 -408.098244)
					(mid 52.194426 -408.120562)
					(end 52.172108 -408.174444)
				)
			)
		)
	)
	(zone
		(layer "In1.Cu")
		(hatch none 0.5)
		(connect_pads
			(clearance 0)
		)
		(min_thickness 0.25)
		(keepout
			(tracks not_allowed)
			(vias allowed)
			(pads allowed)
			(copperpour not_allowed)
			(footprints allowed)
		)
		(placement
			(enabled no)
			(sheetname "")
		)
		(fill
			(thermal_gap 0.5)
			(thermal_bridge_width 0.5)
			(island_removal_mode 0)
		)
		(polygon
			(pts
				(arc
					(start 394.665962 -7.672324)
					(mid 394.643644 -7.618442)
					(end 394.589762 -7.596124)
				)
				(arc
					(start 393.308332 -7.596124)
					(mid 393.25445 -7.618442)
					(end 393.232132 -7.672324)
				)
				(arc
					(start 393.232132 -9.094724)
					(mid 393.25445 -9.148606)
					(end 393.308332 -9.170924)
				)
				(arc
					(start 394.589762 -9.170924)
					(mid 394.643644 -9.148606)
					(end 394.665962 -9.094724)
				)
			)
		)
	)
	(zone
		(layer "In1.Cu")
		(hatch none 0.5)
		(connect_pads
			(clearance 0)
		)
		(min_thickness 0.25)
		(keepout
			(tracks not_allowed)
			(vias allowed)
			(pads allowed)
			(copperpour not_allowed)
			(footprints allowed)
		)
		(placement
			(enabled no)
			(sheetname "")
		)
		(fill
			(thermal_gap 0.5)
			(thermal_bridge_width 0.5)
			(island_removal_mode 0)
		)
		(polygon
			(pts
				(arc
					(start 16.416528 -107.273852)
					(mid 16.424285 -107.312893)
					(end 16.446754 -107.345734)
				)
				(arc
					(start 16.446754 -107.345734)
					(mid 16.477442 -107.365776)
					(end 16.513302 -107.37342)
				)
				(xy 16.655542 -107.37342) (xy 16.655542 -107.373166)
				(arc
					(start 17.582896 -107.373166)
					(mid 17.646402 -107.343976)
					(end 17.674336 -107.279948)
				)
				(arc
					(start 17.674336 -106.973116)
					(mid 17.666579 -106.934075)
					(end 17.64411 -106.901234)
				)
				(arc
					(start 17.64411 -106.901234)
					(mid 17.613422 -106.881192)
					(end 17.577562 -106.873548)
				)
				(xy 16.546322 -106.873548) (xy 16.546322 -106.873802)
				(arc
					(start 16.507968 -106.873802)
					(mid 16.444462 -106.902992)
					(end 16.416528 -106.96702)
				)
			)
		)
	)
	(zone
		(layer "In1.Cu")
		(hatch none 0.5)
		(connect_pads
			(clearance 0)
		)
		(min_thickness 0.25)
		(keepout
			(tracks not_allowed)
			(vias allowed)
			(pads allowed)
			(copperpour not_allowed)
			(footprints allowed)
		)
		(placement
			(enabled no)
			(sheetname "")
		)
		(fill
			(thermal_gap 0.5)
			(thermal_bridge_width 0.5)
			(island_removal_mode 0)
		)
		(polygon
			(pts
				(arc
					(start 19.777456 -395.383004)
					(mid 19.738415 -395.390761)
					(end 19.705574 -395.41323)
				)
				(arc
					(start 19.705574 -395.41323)
					(mid 19.685532 -395.443918)
					(end 19.677888 -395.479778)
				)
				(xy 19.677888 -395.622018) (xy 19.678142 -395.622018)
				(arc
					(start 19.678142 -396.549372)
					(mid 19.707332 -396.612878)
					(end 19.77136 -396.640812)
				)
				(arc
					(start 20.078192 -396.640812)
					(mid 20.117233 -396.633055)
					(end 20.150074 -396.610586)
				)
				(arc
					(start 20.150074 -396.610586)
					(mid 20.170116 -396.579898)
					(end 20.17776 -396.544038)
				)
				(xy 20.17776 -395.512798) (xy 20.177506 -395.512798)
				(arc
					(start 20.177506 -395.474444)
					(mid 20.148316 -395.410938)
					(end 20.084288 -395.383004)
				)
			)
		)
	)
	(zone
		(layer "In1.Cu")
		(hatch none 0.5)
		(connect_pads
			(clearance 0)
		)
		(min_thickness 0.25)
		(keepout
			(tracks not_allowed)
			(vias allowed)
			(pads allowed)
			(copperpour not_allowed)
			(footprints allowed)
		)
		(placement
			(enabled no)
			(sheetname "")
		)
		(fill
			(thermal_gap 0.5)
			(thermal_bridge_width 0.5)
			(island_removal_mode 0)
		)
		(polygon
			(pts
				(arc
					(start 401.865846 -7.672324)
					(mid 401.843528 -7.618442)
					(end 401.789646 -7.596124)
				)
				(arc
					(start 400.508216 -7.596124)
					(mid 400.454334 -7.618442)
					(end 400.432016 -7.672324)
				)
				(arc
					(start 400.432016 -9.094724)
					(mid 400.454334 -9.148606)
					(end 400.508216 -9.170924)
				)
				(arc
					(start 401.789646 -9.170924)
					(mid 401.843528 -9.148606)
					(end 401.865846 -9.094724)
				)
			)
		)
	)
	(zone
		(layer "In1.Cu")
		(hatch none 0.5)
		(connect_pads
			(clearance 0)
		)
		(min_thickness 0.25)
		(keepout
			(tracks not_allowed)
			(vias allowed)
			(pads allowed)
			(copperpour not_allowed)
			(footprints allowed)
		)
		(placement
			(enabled no)
			(sheetname "")
		)
		(fill
			(thermal_gap 0.5)
			(thermal_bridge_width 0.5)
			(island_removal_mode 0)
		)
		(polygon
			(pts
				(arc
					(start 56.952388 -402.713952)
					(mid 56.974706 -402.767834)
					(end 57.028588 -402.790152)
				)
				(arc
					(start 57.224168 -402.790152)
					(mid 57.246044 -402.78702)
					(end 57.266078 -402.777706)
				)
				(arc
					(start 57.559702 -402.585174)
					(mid 57.601358 -402.572772)
					(end 57.643014 -402.585174)
				)
				(arc
					(start 57.937908 -402.777706)
					(mid 57.957832 -402.786942)
					(end 57.979564 -402.790152)
				)
				(arc
					(start 58.174128 -402.790152)
					(mid 58.22801 -402.767834)
					(end 58.250328 -402.713952)
				)
				(arc
					(start 58.250328 -402.028152)
					(mid 58.22801 -401.97427)
					(end 58.174128 -401.951952)
				)
				(arc
					(start 57.979564 -401.951952)
					(mid 57.95782 -401.95512)
					(end 57.937908 -401.964398)
				)
				(arc
					(start 57.641744 -402.157184)
					(mid 57.60006 -402.169406)
					(end 57.558432 -402.15693)
				)
				(arc
					(start 57.264808 -401.964398)
					(mid 57.244884 -401.955162)
					(end 57.223152 -401.951952)
				)
				(arc
					(start 57.028588 -401.951952)
					(mid 56.974706 -401.97427)
					(end 56.952388 -402.028152)
				)
			)
		)
	)
	(zone
		(layer "In1.Cu")
		(hatch none 0.5)
		(connect_pads
			(clearance 0)
		)
		(min_thickness 0.25)
		(keepout
			(tracks not_allowed)
			(vias allowed)
			(pads allowed)
			(copperpour not_allowed)
			(footprints allowed)
		)
		(placement
			(enabled no)
			(sheetname "")
		)
		(fill
			(thermal_gap 0.5)
			(thermal_bridge_width 0.5)
			(island_removal_mode 0)
		)
		(polygon
			(pts
				(arc
					(start 150.570184 -402.713952)
					(mid 150.592502 -402.767834)
					(end 150.646384 -402.790152)
				)
				(arc
					(start 150.841964 -402.790152)
					(mid 150.86384 -402.78702)
					(end 150.883874 -402.777706)
				)
				(arc
					(start 151.177498 -402.585174)
					(mid 151.219154 -402.572772)
					(end 151.26081 -402.585174)
				)
				(arc
					(start 151.555704 -402.777706)
					(mid 151.575628 -402.786942)
					(end 151.59736 -402.790152)
				)
				(arc
					(start 151.791924 -402.790152)
					(mid 151.845806 -402.767834)
					(end 151.868124 -402.713952)
				)
				(arc
					(start 151.868124 -402.028152)
					(mid 151.845806 -401.97427)
					(end 151.791924 -401.951952)
				)
				(arc
					(start 151.59736 -401.951952)
					(mid 151.575616 -401.95512)
					(end 151.555704 -401.964398)
				)
				(arc
					(start 151.25954 -402.157184)
					(mid 151.217856 -402.169406)
					(end 151.176228 -402.15693)
				)
				(arc
					(start 150.882604 -401.964398)
					(mid 150.86268 -401.955162)
					(end 150.840948 -401.951952)
				)
				(arc
					(start 150.646384 -401.951952)
					(mid 150.592502 -401.97427)
					(end 150.570184 -402.028152)
				)
			)
		)
	)
	(zone
		(layer "In1.Cu")
		(hatch none 0.5)
		(connect_pads
			(clearance 0)
		)
		(min_thickness 0.25)
		(keepout
			(tracks not_allowed)
			(vias allowed)
			(pads allowed)
			(copperpour not_allowed)
			(footprints allowed)
		)
		(placement
			(enabled no)
			(sheetname "")
		)
		(fill
			(thermal_gap 0.5)
			(thermal_bridge_width 0.5)
			(island_removal_mode 0)
		)
		(polygon
			(pts
				(arc
					(start 12.917932 -103.19004)
					(mid 12.155424 -103.19004)
					(end 12.917932 -103.19004)
				)
			)
		)
	)
	(zone
		(layer "In1.Cu")
		(hatch none 0.5)
		(connect_pads
			(clearance 0)
		)
		(min_thickness 0.25)
		(keepout
			(tracks not_allowed)
			(vias allowed)
			(pads allowed)
			(copperpour not_allowed)
			(footprints allowed)
		)
		(placement
			(enabled no)
			(sheetname "")
		)
		(fill
			(thermal_gap 0.5)
			(thermal_bridge_width 0.5)
			(island_removal_mode 0)
		)
		(polygon
			(pts
				(arc
					(start 24.83485 -398.316196)
					(mid 24.873891 -398.308439)
					(end 24.906732 -398.28597)
				)
				(arc
					(start 24.906732 -398.28597)
					(mid 24.926774 -398.255282)
					(end 24.934418 -398.219422)
				)
				(xy 24.934418 -398.077182) (xy 24.934164 -398.077182)
				(arc
					(start 24.934164 -397.149828)
					(mid 24.904974 -397.086322)
					(end 24.840946 -397.058388)
				)
				(arc
					(start 24.534114 -397.058388)
					(mid 24.495073 -397.066145)
					(end 24.462232 -397.088614)
				)
				(arc
					(start 24.462232 -397.088614)
					(mid 24.44219 -397.119302)
					(end 24.434546 -397.155162)
				)
				(xy 24.434546 -398.186402) (xy 24.4348 -398.186402)
				(arc
					(start 24.4348 -398.224756)
					(mid 24.46399 -398.288262)
					(end 24.528018 -398.316196)
				)
			)
		)
	)
	(zone
		(layer "In1.Cu")
		(hatch none 0.5)
		(connect_pads
			(clearance 0)
		)
		(min_thickness 0.25)
		(keepout
			(tracks not_allowed)
			(vias allowed)
			(pads allowed)
			(copperpour not_allowed)
			(footprints allowed)
		)
		(placement
			(enabled no)
			(sheetname "")
		)
		(fill
			(thermal_gap 0.5)
			(thermal_bridge_width 0.5)
			(island_removal_mode 0)
		)
		(polygon
			(pts
				(arc
					(start 390.9314 -408.860244)
					(mid 390.953718 -408.914126)
					(end 391.0076 -408.936444)
				)
				(arc
					(start 391.20318 -408.936444)
					(mid 391.225056 -408.933312)
					(end 391.24509 -408.923998)
				)
				(arc
					(start 391.538714 -408.731466)
					(mid 391.58037 -408.719064)
					(end 391.622026 -408.731466)
				)
				(arc
					(start 391.91692 -408.923998)
					(mid 391.936844 -408.933234)
					(end 391.958576 -408.936444)
				)
				(arc
					(start 392.15314 -408.936444)
					(mid 392.207022 -408.914126)
					(end 392.22934 -408.860244)
				)
				(arc
					(start 392.22934 -408.174444)
					(mid 392.207022 -408.120562)
					(end 392.15314 -408.098244)
				)
				(arc
					(start 391.958576 -408.098244)
					(mid 391.936832 -408.101412)
					(end 391.91692 -408.11069)
				)
				(arc
					(start 391.620756 -408.303476)
					(mid 391.579072 -408.315698)
					(end 391.537444 -408.303222)
				)
				(arc
					(start 391.24382 -408.11069)
					(mid 391.223896 -408.101454)
					(end 391.202164 -408.098244)
				)
				(arc
					(start 391.0076 -408.098244)
					(mid 390.953718 -408.120562)
					(end 390.9314 -408.174444)
				)
			)
		)
	)
	(zone
		(layer "In1.Cu")
		(hatch none 0.5)
		(connect_pads
			(clearance 0)
		)
		(min_thickness 0.25)
		(keepout
			(tracks not_allowed)
			(vias allowed)
			(pads allowed)
			(copperpour not_allowed)
			(footprints allowed)
		)
		(placement
			(enabled no)
			(sheetname "")
		)
		(fill
			(thermal_gap 0.5)
			(thermal_bridge_width 0.5)
			(island_removal_mode 0)
		)
		(polygon
			(pts
				(arc
					(start 395.71168 -402.713952)
					(mid 395.733998 -402.767834)
					(end 395.78788 -402.790152)
				)
				(arc
					(start 395.98346 -402.790152)
					(mid 396.005336 -402.78702)
					(end 396.02537 -402.777706)
				)
				(arc
					(start 396.318994 -402.585174)
					(mid 396.36065 -402.572772)
					(end 396.402306 -402.585174)
				)
				(arc
					(start 396.6972 -402.777706)
					(mid 396.717124 -402.786942)
					(end 396.738856 -402.790152)
				)
				(arc
					(start 396.93342 -402.790152)
					(mid 396.987302 -402.767834)
					(end 397.00962 -402.713952)
				)
				(arc
					(start 397.00962 -402.028152)
					(mid 396.987302 -401.97427)
					(end 396.93342 -401.951952)
				)
				(arc
					(start 396.738856 -401.951952)
					(mid 396.717112 -401.95512)
					(end 396.6972 -401.964398)
				)
				(arc
					(start 396.401036 -402.157184)
					(mid 396.359352 -402.169406)
					(end 396.317724 -402.15693)
				)
				(arc
					(start 396.0241 -401.964398)
					(mid 396.004176 -401.955162)
					(end 395.982444 -401.951952)
				)
				(arc
					(start 395.78788 -401.951952)
					(mid 395.733998 -401.97427)
					(end 395.71168 -402.028152)
				)
			)
		)
	)
	(zone
		(layer "In1.Cu")
		(hatch none 0.5)
		(connect_pads
			(clearance 0)
		)
		(min_thickness 0.25)
		(keepout
			(tracks not_allowed)
			(vias allowed)
			(pads allowed)
			(copperpour not_allowed)
			(footprints allowed)
		)
		(placement
			(enabled no)
			(sheetname "")
		)
		(fill
			(thermal_gap 0.5)
			(thermal_bridge_width 0.5)
			(island_removal_mode 0)
		)
		(polygon
			(pts
				(arc
					(start 23.767034 -7.672324)
					(mid 23.744716 -7.618442)
					(end 23.690834 -7.596124)
				)
				(arc
					(start 22.409404 -7.596124)
					(mid 22.355522 -7.618442)
					(end 22.333204 -7.672324)
				)
				(arc
					(start 22.333204 -9.094724)
					(mid 22.355522 -9.148606)
					(end 22.409404 -9.170924)
				)
				(arc
					(start 23.690834 -9.170924)
					(mid 23.744716 -9.148606)
					(end 23.767034 -9.094724)
				)
			)
		)
	)
	(zone
		(layer "In1.Cu")
		(hatch none 0.5)
		(connect_pads
			(clearance 0)
		)
		(min_thickness 0.25)
		(keepout
			(tracks not_allowed)
			(vias allowed)
			(pads allowed)
			(copperpour not_allowed)
			(footprints allowed)
		)
		(placement
			(enabled no)
			(sheetname "")
		)
		(fill
			(thermal_gap 0.5)
			(thermal_bridge_width 0.5)
			(island_removal_mode 0)
		)
		(polygon
			(pts
				(arc
					(start 328.126852 0.929894)
					(mid 328.14917 0.983776)
					(end 328.203052 1.006094)
				)
				(arc
					(start 328.815192 1.006094)
					(mid 328.869074 0.983776)
					(end 328.891392 0.929894)
				)
				(arc
					(start 328.891392 -0.167386)
					(mid 328.869074 -0.221268)
					(end 328.815192 -0.243586)
				)
				(arc
					(start 328.203052 -0.243586)
					(mid 328.14917 -0.221268)
					(end 328.126852 -0.167386)
				)
			)
		)
	)
	(zone
		(layer "In1.Cu")
		(hatch none 0.5)
		(connect_pads
			(clearance 0)
		)
		(min_thickness 0.25)
		(keepout
			(tracks not_allowed)
			(vias allowed)
			(pads allowed)
			(copperpour not_allowed)
			(footprints allowed)
		)
		(placement
			(enabled no)
			(sheetname "")
		)
		(fill
			(thermal_gap 0.5)
			(thermal_bridge_width 0.5)
			(island_removal_mode 0)
		)
		(polygon
			(pts
				(arc
					(start 95.057468 -408.860244)
					(mid 95.079786 -408.914126)
					(end 95.133668 -408.936444)
				)
				(arc
					(start 95.329248 -408.936444)
					(mid 95.351124 -408.933312)
					(end 95.371158 -408.923998)
				)
				(arc
					(start 95.664782 -408.731466)
					(mid 95.706438 -408.719064)
					(end 95.748094 -408.731466)
				)
				(arc
					(start 96.042988 -408.923998)
					(mid 96.062912 -408.933234)
					(end 96.084644 -408.936444)
				)
				(arc
					(start 96.279208 -408.936444)
					(mid 96.33309 -408.914126)
					(end 96.355408 -408.860244)
				)
				(arc
					(start 96.355408 -408.174444)
					(mid 96.33309 -408.120562)
					(end 96.279208 -408.098244)
				)
				(arc
					(start 96.084644 -408.098244)
					(mid 96.0629 -408.101412)
					(end 96.042988 -408.11069)
				)
				(arc
					(start 95.746824 -408.303476)
					(mid 95.70514 -408.315698)
					(end 95.663512 -408.303222)
				)
				(arc
					(start 95.369888 -408.11069)
					(mid 95.349964 -408.101454)
					(end 95.328232 -408.098244)
				)
				(arc
					(start 95.133668 -408.098244)
					(mid 95.079786 -408.120562)
					(end 95.057468 -408.174444)
				)
			)
		)
	)
	(zone
		(layer "In1.Cu")
		(hatch none 0.5)
		(connect_pads
			(clearance 0)
		)
		(min_thickness 0.25)
		(keepout
			(tracks not_allowed)
			(vias allowed)
			(pads allowed)
			(copperpour not_allowed)
			(footprints allowed)
		)
		(placement
			(enabled no)
			(sheetname "")
		)
		(fill
			(thermal_gap 0.5)
			(thermal_bridge_width 0.5)
			(island_removal_mode 0)
		)
		(polygon
			(pts
				(arc
					(start 88.930988 -408.860244)
					(mid 88.953306 -408.914126)
					(end 89.007188 -408.936444)
				)
				(arc
					(start 89.202768 -408.936444)
					(mid 89.224644 -408.933312)
					(end 89.244678 -408.923998)
				)
				(arc
					(start 89.538302 -408.731466)
					(mid 89.579958 -408.719064)
					(end 89.621614 -408.731466)
				)
				(arc
					(start 89.916508 -408.923998)
					(mid 89.936432 -408.933234)
					(end 89.958164 -408.936444)
				)
				(arc
					(start 90.152728 -408.936444)
					(mid 90.20661 -408.914126)
					(end 90.228928 -408.860244)
				)
				(arc
					(start 90.228928 -408.174444)
					(mid 90.20661 -408.120562)
					(end 90.152728 -408.098244)
				)
				(arc
					(start 89.958164 -408.098244)
					(mid 89.93642 -408.101412)
					(end 89.916508 -408.11069)
				)
				(arc
					(start 89.620344 -408.303476)
					(mid 89.57866 -408.315698)
					(end 89.537032 -408.303222)
				)
				(arc
					(start 89.243408 -408.11069)
					(mid 89.223484 -408.101454)
					(end 89.201752 -408.098244)
				)
				(arc
					(start 89.007188 -408.098244)
					(mid 88.953306 -408.120562)
					(end 88.930988 -408.174444)
				)
			)
		)
	)
	(zone
		(layer "In1.Cu")
		(hatch none 0.5)
		(connect_pads
			(clearance 0)
		)
		(min_thickness 0.25)
		(keepout
			(tracks not_allowed)
			(vias allowed)
			(pads allowed)
			(copperpour not_allowed)
			(footprints allowed)
		)
		(placement
			(enabled no)
			(sheetname "")
		)
		(fill
			(thermal_gap 0.5)
			(thermal_bridge_width 0.5)
			(island_removal_mode 0)
		)
		(polygon
			(pts
				(arc
					(start 66.142108 -402.713952)
					(mid 66.164426 -402.767834)
					(end 66.218308 -402.790152)
				)
				(arc
					(start 66.413888 -402.790152)
					(mid 66.435764 -402.78702)
					(end 66.455798 -402.777706)
				)
				(arc
					(start 66.749422 -402.585174)
					(mid 66.791078 -402.572772)
					(end 66.832734 -402.585174)
				)
				(arc
					(start 67.127628 -402.777706)
					(mid 67.147552 -402.786942)
					(end 67.169284 -402.790152)
				)
				(arc
					(start 67.363848 -402.790152)
					(mid 67.41773 -402.767834)
					(end 67.440048 -402.713952)
				)
				(arc
					(start 67.440048 -402.028152)
					(mid 67.41773 -401.97427)
					(end 67.363848 -401.951952)
				)
				(arc
					(start 67.169284 -401.951952)
					(mid 67.14754 -401.95512)
					(end 67.127628 -401.964398)
				)
				(arc
					(start 66.831464 -402.157184)
					(mid 66.78978 -402.169406)
					(end 66.748152 -402.15693)
				)
				(arc
					(start 66.454528 -401.964398)
					(mid 66.434604 -401.955162)
					(end 66.412872 -401.951952)
				)
				(arc
					(start 66.218308 -401.951952)
					(mid 66.164426 -401.97427)
					(end 66.142108 -402.028152)
				)
			)
		)
	)
	(zone
		(layer "In1.Cu")
		(hatch none 0.5)
		(connect_pads
			(clearance 0)
		)
		(min_thickness 0.25)
		(keepout
			(tracks not_allowed)
			(vias allowed)
			(pads allowed)
			(copperpour not_allowed)
			(footprints allowed)
		)
		(placement
			(enabled no)
			(sheetname "")
		)
		(fill
			(thermal_gap 0.5)
			(thermal_bridge_width 0.5)
			(island_removal_mode 0)
		)
		(polygon
			(pts
				(arc
					(start 12.936474 -106.932984)
					(mid 12.975515 -106.925227)
					(end 13.008356 -106.902758)
				)
				(arc
					(start 13.008356 -106.902758)
					(mid 13.028398 -106.87207)
					(end 13.036042 -106.83621)
				)
				(xy 13.036042 -106.69397) (xy 13.035788 -106.69397)
				(arc
					(start 13.035788 -105.766616)
					(mid 13.006598 -105.70311)
					(end 12.94257 -105.675176)
				)
				(arc
					(start 12.635738 -105.675176)
					(mid 12.596697 -105.682933)
					(end 12.563856 -105.705402)
				)
				(arc
					(start 12.563856 -105.705402)
					(mid 12.543814 -105.73609)
					(end 12.53617 -105.77195)
				)
				(xy 12.53617 -106.80319) (xy 12.536424 -106.80319)
				(arc
					(start 12.536424 -106.841544)
					(mid 12.565614 -106.90505)
					(end 12.629642 -106.932984)
				)
			)
		)
	)
	(zone
		(layer "In1.Cu")
		(hatch none 0.5)
		(connect_pads
			(clearance 0)
		)
		(min_thickness 0.25)
		(keepout
			(tracks not_allowed)
			(vias allowed)
			(pads allowed)
			(copperpour not_allowed)
			(footprints allowed)
		)
		(placement
			(enabled no)
			(sheetname "")
		)
		(fill
			(thermal_gap 0.5)
			(thermal_bridge_width 0.5)
			(island_removal_mode 0)
		)
		(polygon
			(pts
				(arc
					(start 341.867998 -408.860244)
					(mid 341.890316 -408.914126)
					(end 341.944198 -408.936444)
				)
				(arc
					(start 342.139778 -408.936444)
					(mid 342.161654 -408.933312)
					(end 342.181688 -408.923998)
				)
				(arc
					(start 342.475312 -408.731466)
					(mid 342.516968 -408.719064)
					(end 342.558624 -408.731466)
				)
				(arc
					(start 342.853518 -408.923998)
					(mid 342.873442 -408.933234)
					(end 342.895174 -408.936444)
				)
				(arc
					(start 343.089738 -408.936444)
					(mid 343.14362 -408.914126)
					(end 343.165938 -408.860244)
				)
				(arc
					(start 343.165938 -408.174444)
					(mid 343.14362 -408.120562)
					(end 343.089738 -408.098244)
				)
				(arc
					(start 342.895174 -408.098244)
					(mid 342.87343 -408.101412)
					(end 342.853518 -408.11069)
				)
				(arc
					(start 342.557354 -408.303476)
					(mid 342.51567 -408.315698)
					(end 342.474042 -408.303222)
				)
				(arc
					(start 342.180418 -408.11069)
					(mid 342.160494 -408.101454)
					(end 342.138762 -408.098244)
				)
				(arc
					(start 341.944198 -408.098244)
					(mid 341.890316 -408.120562)
					(end 341.867998 -408.174444)
				)
			)
		)
	)
	(zone
		(layer "In1.Cu")
		(hatch none 0.5)
		(connect_pads
			(clearance 0)
		)
		(min_thickness 0.25)
		(keepout
			(tracks not_allowed)
			(vias allowed)
			(pads allowed)
			(copperpour not_allowed)
			(footprints allowed)
		)
		(placement
			(enabled no)
			(sheetname "")
		)
		(fill
			(thermal_gap 0.5)
			(thermal_bridge_width 0.5)
			(island_removal_mode 0)
		)
		(polygon
			(pts
				(arc
					(start 316.015878 -402.713952)
					(mid 316.038196 -402.767834)
					(end 316.092078 -402.790152)
				)
				(arc
					(start 316.287658 -402.790152)
					(mid 316.309534 -402.78702)
					(end 316.329568 -402.777706)
				)
				(arc
					(start 316.623192 -402.585174)
					(mid 316.664848 -402.572772)
					(end 316.706504 -402.585174)
				)
				(arc
					(start 317.001398 -402.777706)
					(mid 317.021322 -402.786942)
					(end 317.043054 -402.790152)
				)
				(arc
					(start 317.237618 -402.790152)
					(mid 317.2915 -402.767834)
					(end 317.313818 -402.713952)
				)
				(arc
					(start 317.313818 -402.028152)
					(mid 317.2915 -401.97427)
					(end 317.237618 -401.951952)
				)
				(arc
					(start 317.043054 -401.951952)
					(mid 317.02131 -401.95512)
					(end 317.001398 -401.964398)
				)
				(arc
					(start 316.705234 -402.157184)
					(mid 316.66355 -402.169406)
					(end 316.621922 -402.15693)
				)
				(arc
					(start 316.328298 -401.964398)
					(mid 316.308374 -401.955162)
					(end 316.286642 -401.951952)
				)
				(arc
					(start 316.092078 -401.951952)
					(mid 316.038196 -401.97427)
					(end 316.015878 -402.028152)
				)
			)
		)
	)
	(zone
		(layer "In1.Cu")
		(hatch none 0.5)
		(connect_pads
			(clearance 0)
		)
		(min_thickness 0.25)
		(keepout
			(tracks not_allowed)
			(vias allowed)
			(pads allowed)
			(copperpour not_allowed)
			(footprints allowed)
		)
		(placement
			(enabled no)
			(sheetname "")
		)
		(fill
			(thermal_gap 0.5)
			(thermal_bridge_width 0.5)
			(island_removal_mode 0)
		)
		(polygon
			(pts
				(arc
					(start 334.395318 -402.713952)
					(mid 334.417636 -402.767834)
					(end 334.471518 -402.790152)
				)
				(arc
					(start 334.667098 -402.790152)
					(mid 334.688974 -402.78702)
					(end 334.709008 -402.777706)
				)
				(arc
					(start 335.002632 -402.585174)
					(mid 335.044288 -402.572772)
					(end 335.085944 -402.585174)
				)
				(arc
					(start 335.380838 -402.777706)
					(mid 335.400762 -402.786942)
					(end 335.422494 -402.790152)
				)
				(arc
					(start 335.617058 -402.790152)
					(mid 335.67094 -402.767834)
					(end 335.693258 -402.713952)
				)
				(arc
					(start 335.693258 -402.028152)
					(mid 335.67094 -401.97427)
					(end 335.617058 -401.951952)
				)
				(arc
					(start 335.422494 -401.951952)
					(mid 335.40075 -401.95512)
					(end 335.380838 -401.964398)
				)
				(arc
					(start 335.084674 -402.157184)
					(mid 335.04299 -402.169406)
					(end 335.001362 -402.15693)
				)
				(arc
					(start 334.707738 -401.964398)
					(mid 334.687814 -401.955162)
					(end 334.666082 -401.951952)
				)
				(arc
					(start 334.471518 -401.951952)
					(mid 334.417636 -401.97427)
					(end 334.395318 -402.028152)
				)
			)
		)
	)
	(zone
		(layer "In1.Cu")
		(hatch none 0.5)
		(connect_pads
			(clearance 0)
		)
		(min_thickness 0.25)
		(keepout
			(tracks not_allowed)
			(vias allowed)
			(pads allowed)
			(copperpour not_allowed)
			(footprints allowed)
		)
		(placement
			(enabled no)
			(sheetname "")
		)
		(fill
			(thermal_gap 0.5)
			(thermal_bridge_width 0.5)
			(island_removal_mode 0)
		)
		(polygon
			(pts
				(arc
					(start 342.68029 -70.17766)
					(mid 342.657972 -70.123778)
					(end 342.60409 -70.10146)
				)
				(arc
					(start 342.27389 -70.10146)
					(mid 342.220008 -70.123778)
					(end 342.19769 -70.17766)
				)
				(arc
					(start 342.19769 -70.43166)
					(mid 342.220008 -70.485542)
					(end 342.27389 -70.50786)
				)
				(arc
					(start 342.60409 -70.50786)
					(mid 342.657972 -70.485542)
					(end 342.68029 -70.43166)
				)
			)
		)
	)
	(zone
		(layer "In1.Cu")
		(hatch none 0.5)
		(connect_pads
			(clearance 0)
		)
		(min_thickness 0.25)
		(keepout
			(tracks not_allowed)
			(vias allowed)
			(pads allowed)
			(copperpour not_allowed)
			(footprints allowed)
		)
		(placement
			(enabled no)
			(sheetname "")
		)
		(fill
			(thermal_gap 0.5)
			(thermal_bridge_width 0.5)
			(island_removal_mode 0)
		)
		(polygon
			(pts
				(arc
					(start 386.52196 -402.713952)
					(mid 386.544278 -402.767834)
					(end 386.59816 -402.790152)
				)
				(arc
					(start 386.79374 -402.790152)
					(mid 386.815616 -402.78702)
					(end 386.83565 -402.777706)
				)
				(arc
					(start 387.129274 -402.585174)
					(mid 387.17093 -402.572772)
					(end 387.212586 -402.585174)
				)
				(arc
					(start 387.50748 -402.777706)
					(mid 387.527404 -402.786942)
					(end 387.549136 -402.790152)
				)
				(arc
					(start 387.7437 -402.790152)
					(mid 387.797582 -402.767834)
					(end 387.8199 -402.713952)
				)
				(arc
					(start 387.8199 -402.028152)
					(mid 387.797582 -401.97427)
					(end 387.7437 -401.951952)
				)
				(arc
					(start 387.549136 -401.951952)
					(mid 387.527392 -401.95512)
					(end 387.50748 -401.964398)
				)
				(arc
					(start 387.211316 -402.157184)
					(mid 387.169632 -402.169406)
					(end 387.128004 -402.15693)
				)
				(arc
					(start 386.83438 -401.964398)
					(mid 386.814456 -401.955162)
					(end 386.792724 -401.951952)
				)
				(arc
					(start 386.59816 -401.951952)
					(mid 386.544278 -401.97427)
					(end 386.52196 -402.028152)
				)
			)
		)
	)
	(zone
		(layer "In1.Cu")
		(hatch none 0.5)
		(connect_pads
			(clearance 0)
		)
		(min_thickness 0.25)
		(keepout
			(tracks not_allowed)
			(vias allowed)
			(pads allowed)
			(copperpour not_allowed)
			(footprints allowed)
		)
		(placement
			(enabled no)
			(sheetname "")
		)
		(fill
			(thermal_gap 0.5)
			(thermal_bridge_width 0.5)
			(island_removal_mode 0)
		)
		(polygon
			(pts
				(arc
					(start 49.108868 -408.860244)
					(mid 49.131186 -408.914126)
					(end 49.185068 -408.936444)
				)
				(arc
					(start 49.380648 -408.936444)
					(mid 49.402524 -408.933312)
					(end 49.422558 -408.923998)
				)
				(arc
					(start 49.716182 -408.731466)
					(mid 49.757838 -408.719064)
					(end 49.799494 -408.731466)
				)
				(arc
					(start 50.094388 -408.923998)
					(mid 50.114312 -408.933234)
					(end 50.136044 -408.936444)
				)
				(arc
					(start 50.330608 -408.936444)
					(mid 50.38449 -408.914126)
					(end 50.406808 -408.860244)
				)
				(arc
					(start 50.406808 -408.174444)
					(mid 50.38449 -408.120562)
					(end 50.330608 -408.098244)
				)
				(arc
					(start 50.136044 -408.098244)
					(mid 50.1143 -408.101412)
					(end 50.094388 -408.11069)
				)
				(arc
					(start 49.798224 -408.303476)
					(mid 49.75654 -408.315698)
					(end 49.714912 -408.303222)
				)
				(arc
					(start 49.421288 -408.11069)
					(mid 49.401364 -408.101454)
					(end 49.379632 -408.098244)
				)
				(arc
					(start 49.185068 -408.098244)
					(mid 49.131186 -408.120562)
					(end 49.108868 -408.174444)
				)
			)
		)
	)
	(zone
		(layer "In1.Cu")
		(hatch none 0.5)
		(connect_pads
			(clearance 0)
		)
		(min_thickness 0.25)
		(keepout
			(tracks not_allowed)
			(vias allowed)
			(pads allowed)
			(copperpour not_allowed)
			(footprints allowed)
		)
		(placement
			(enabled no)
			(sheetname "")
		)
		(fill
			(thermal_gap 0.5)
			(thermal_bridge_width 0.5)
			(island_removal_mode 0)
		)
		(polygon
			(pts
				(arc
					(start 395.027912 -11.91768)
					(mid 395.05023 -11.971562)
					(end 395.104112 -11.99388)
				)
				(arc
					(start 396.385542 -11.99388)
					(mid 396.439424 -11.971562)
					(end 396.461742 -11.91768)
				)
				(arc
					(start 396.461742 -10.49528)
					(mid 396.439424 -10.441398)
					(end 396.385542 -10.41908)
				)
				(arc
					(start 395.104112 -10.41908)
					(mid 395.05023 -10.441398)
					(end 395.027912 -10.49528)
				)
			)
		)
	)
	(zone
		(layer "In1.Cu")
		(hatch none 0.5)
		(connect_pads
			(clearance 0)
		)
		(min_thickness 0.25)
		(keepout
			(tracks not_allowed)
			(vias allowed)
			(pads allowed)
			(copperpour not_allowed)
			(footprints allowed)
		)
		(placement
			(enabled no)
			(sheetname "")
		)
		(fill
			(thermal_gap 0.5)
			(thermal_bridge_width 0.5)
			(island_removal_mode 0)
		)
		(polygon
			(pts
				(arc
					(start 159.051752 -45.26153)
					(mid 159.090793 -45.253773)
					(end 159.123634 -45.231304)
				)
				(arc
					(start 159.123634 -45.231304)
					(mid 159.143676 -45.200616)
					(end 159.15132 -45.164756)
				)
				(xy 159.15132 -45.022516) (xy 159.151066 -45.022516)
				(arc
					(start 159.151066 -44.095162)
					(mid 159.121876 -44.031656)
					(end 159.057848 -44.003722)
				)
				(arc
					(start 158.751016 -44.003722)
					(mid 158.711975 -44.011479)
					(end 158.679134 -44.033948)
				)
				(arc
					(start 158.679134 -44.033948)
					(mid 158.659092 -44.064636)
					(end 158.651448 -44.100496)
				)
				(xy 158.651448 -45.131736) (xy 158.651702 -45.131736)
				(arc
					(start 158.651702 -45.17009)
					(mid 158.680892 -45.233596)
					(end 158.74492 -45.26153)
				)
			)
		)
	)
	(zone
		(layer "In1.Cu")
		(hatch none 0.5)
		(connect_pads
			(clearance 0)
		)
		(min_thickness 0.25)
		(keepout
			(tracks not_allowed)
			(vias allowed)
			(pads allowed)
			(copperpour not_allowed)
			(footprints allowed)
		)
		(placement
			(enabled no)
			(sheetname "")
		)
		(fill
			(thermal_gap 0.5)
			(thermal_bridge_width 0.5)
			(island_removal_mode 0)
		)
		(polygon
			(pts
				(arc
					(start 19.048222 -384.43662)
					(mid 19.009181 -384.444377)
					(end 18.97634 -384.466846)
				)
				(arc
					(start 18.97634 -384.466846)
					(mid 18.956298 -384.497534)
					(end 18.948654 -384.533394)
				)
				(xy 18.948654 -384.675634) (xy 18.948908 -384.675634)
				(arc
					(start 18.948908 -385.602988)
					(mid 18.978098 -385.666494)
					(end 19.042126 -385.694428)
				)
				(arc
					(start 19.348958 -385.694428)
					(mid 19.387999 -385.686671)
					(end 19.42084 -385.664202)
				)
				(arc
					(start 19.42084 -385.664202)
					(mid 19.440882 -385.633514)
					(end 19.448526 -385.597654)
				)
				(xy 19.448526 -384.566414) (xy 19.448272 -384.566414)
				(arc
					(start 19.448272 -384.52806)
					(mid 19.419082 -384.464554)
					(end 19.355054 -384.43662)
				)
			)
		)
	)
	(zone
		(layer "In1.Cu")
		(hatch none 0.5)
		(connect_pads
			(clearance 0)
		)
		(min_thickness 0.25)
		(keepout
			(tracks not_allowed)
			(vias allowed)
			(pads allowed)
			(copperpour not_allowed)
			(footprints allowed)
		)
		(placement
			(enabled no)
			(sheetname "")
		)
		(fill
			(thermal_gap 0.5)
			(thermal_bridge_width 0.5)
			(island_removal_mode 0)
		)
		(polygon
			(pts
				(arc
					(start 90.648028 -402.713952)
					(mid 90.670346 -402.767834)
					(end 90.724228 -402.790152)
				)
				(arc
					(start 90.919808 -402.790152)
					(mid 90.941684 -402.78702)
					(end 90.961718 -402.777706)
				)
				(arc
					(start 91.255342 -402.585174)
					(mid 91.296998 -402.572772)
					(end 91.338654 -402.585174)
				)
				(arc
					(start 91.633548 -402.777706)
					(mid 91.653472 -402.786942)
					(end 91.675204 -402.790152)
				)
				(arc
					(start 91.869768 -402.790152)
					(mid 91.92365 -402.767834)
					(end 91.945968 -402.713952)
				)
				(arc
					(start 91.945968 -402.028152)
					(mid 91.92365 -401.97427)
					(end 91.869768 -401.951952)
				)
				(arc
					(start 91.675204 -401.951952)
					(mid 91.65346 -401.95512)
					(end 91.633548 -401.964398)
				)
				(arc
					(start 91.337384 -402.157184)
					(mid 91.2957 -402.169406)
					(end 91.254072 -402.15693)
				)
				(arc
					(start 90.960448 -401.964398)
					(mid 90.940524 -401.955162)
					(end 90.918792 -401.951952)
				)
				(arc
					(start 90.724228 -401.951952)
					(mid 90.670346 -401.97427)
					(end 90.648028 -402.028152)
				)
			)
		)
	)
	(zone
		(layer "In1.Cu")
		(hatch none 0.5)
		(connect_pads
			(clearance 0)
		)
		(min_thickness 0.25)
		(keepout
			(tracks not_allowed)
			(vias allowed)
			(pads allowed)
			(copperpour not_allowed)
			(footprints allowed)
		)
		(placement
			(enabled no)
			(sheetname "")
		)
		(fill
			(thermal_gap 0.5)
			(thermal_bridge_width 0.5)
			(island_removal_mode 0)
		)
		(polygon
			(pts
				(arc
					(start 390.110726 -19.050762)
					(mid 389.34771 -19.050762)
					(end 390.110726 -19.050762)
				)
			)
		)
	)
	(zone
		(layer "In1.Cu")
		(hatch none 0.5)
		(connect_pads
			(clearance 0)
		)
		(min_thickness 0.25)
		(keepout
			(tracks not_allowed)
			(vias allowed)
			(pads allowed)
			(copperpour not_allowed)
			(footprints allowed)
		)
		(placement
			(enabled no)
			(sheetname "")
		)
		(fill
			(thermal_gap 0.5)
			(thermal_bridge_width 0.5)
			(island_removal_mode 0)
		)
		(polygon
			(pts
				(arc
					(start 55.235348 -408.860244)
					(mid 55.257666 -408.914126)
					(end 55.311548 -408.936444)
				)
				(arc
					(start 55.507128 -408.936444)
					(mid 55.529004 -408.933312)
					(end 55.549038 -408.923998)
				)
				(arc
					(start 55.842662 -408.731466)
					(mid 55.884318 -408.719064)
					(end 55.925974 -408.731466)
				)
				(arc
					(start 56.220868 -408.923998)
					(mid 56.240792 -408.933234)
					(end 56.262524 -408.936444)
				)
				(arc
					(start 56.457088 -408.936444)
					(mid 56.51097 -408.914126)
					(end 56.533288 -408.860244)
				)
				(arc
					(start 56.533288 -408.174444)
					(mid 56.51097 -408.120562)
					(end 56.457088 -408.098244)
				)
				(arc
					(start 56.262524 -408.098244)
					(mid 56.24078 -408.101412)
					(end 56.220868 -408.11069)
				)
				(arc
					(start 55.924704 -408.303476)
					(mid 55.88302 -408.315698)
					(end 55.841392 -408.303222)
				)
				(arc
					(start 55.547768 -408.11069)
					(mid 55.527844 -408.101454)
					(end 55.506112 -408.098244)
				)
				(arc
					(start 55.311548 -408.098244)
					(mid 55.257666 -408.120562)
					(end 55.235348 -408.174444)
				)
			)
		)
	)
	(zone
		(layer "In1.Cu")
		(hatch none 0.5)
		(connect_pads
			(clearance 0)
		)
		(min_thickness 0.25)
		(keepout
			(tracks not_allowed)
			(vias allowed)
			(pads allowed)
			(copperpour not_allowed)
			(footprints allowed)
		)
		(placement
			(enabled no)
			(sheetname "")
		)
		(fill
			(thermal_gap 0.5)
			(thermal_bridge_width 0.5)
			(island_removal_mode 0)
		)
		(polygon
			(pts
				(arc
					(start 389.824214 -16.431514)
					(mid 389.846532 -16.485396)
					(end 389.900414 -16.507714)
				)
				(arc
					(start 390.095994 -16.507714)
					(mid 390.11787 -16.504582)
					(end 390.137904 -16.495268)
				)
				(arc
					(start 390.431528 -16.302736)
					(mid 390.473184 -16.290334)
					(end 390.51484 -16.302736)
				)
				(arc
					(start 390.809734 -16.495268)
					(mid 390.829658 -16.504504)
					(end 390.85139 -16.507714)
				)
				(arc
					(start 391.045954 -16.507714)
					(mid 391.099836 -16.485396)
					(end 391.122154 -16.431514)
				)
				(arc
					(start 391.122154 -15.745714)
					(mid 391.099836 -15.691832)
					(end 391.045954 -15.669514)
				)
				(arc
					(start 390.85139 -15.669514)
					(mid 390.829646 -15.672682)
					(end 390.809734 -15.68196)
				)
				(arc
					(start 390.51357 -15.874746)
					(mid 390.471886 -15.886968)
					(end 390.430258 -15.874492)
				)
				(arc
					(start 390.136634 -15.68196)
					(mid 390.11671 -15.672724)
					(end 390.094978 -15.669514)
				)
				(arc
					(start 389.900414 -15.669514)
					(mid 389.846532 -15.691832)
					(end 389.824214 -15.745714)
				)
			)
		)
	)
	(zone
		(layer "In1.Cu")
		(hatch none 0.5)
		(connect_pads
			(clearance 0)
		)
		(min_thickness 0.25)
		(keepout
			(tracks not_allowed)
			(vias allowed)
			(pads allowed)
			(copperpour not_allowed)
			(footprints allowed)
		)
		(placement
			(enabled no)
			(sheetname "")
		)
		(fill
			(thermal_gap 0.5)
			(thermal_bridge_width 0.5)
			(island_removal_mode 0)
		)
		(polygon
			(pts
				(arc
					(start 176.38268 -46.436026)
					(mid 176.328798 -46.413708)
					(end 176.30648 -46.359826)
				)
				(arc
					(start 176.30648 -45.727366)
					(mid 176.328798 -45.673484)
					(end 176.38268 -45.651166)
				)
				(arc
					(start 177.83556 -45.651166)
					(mid 177.889442 -45.673484)
					(end 177.91176 -45.727366)
				)
				(arc
					(start 177.91176 -46.359826)
					(mid 177.889442 -46.413708)
					(end 177.83556 -46.436026)
				)
			)
		)
	)
	(zone
		(layer "In1.Cu")
		(hatch none 0.5)
		(connect_pads
			(clearance 0)
		)
		(min_thickness 0.25)
		(keepout
			(tracks not_allowed)
			(vias allowed)
			(pads allowed)
			(copperpour not_allowed)
			(footprints allowed)
		)
		(placement
			(enabled no)
			(sheetname "")
		)
		(fill
			(thermal_gap 0.5)
			(thermal_bridge_width 0.5)
			(island_removal_mode 0)
		)
		(polygon
			(pts
				(arc
					(start 64.425068 -408.860244)
					(mid 64.447386 -408.914126)
					(end 64.501268 -408.936444)
				)
				(arc
					(start 64.696848 -408.936444)
					(mid 64.718724 -408.933312)
					(end 64.738758 -408.923998)
				)
				(arc
					(start 65.032382 -408.731466)
					(mid 65.074038 -408.719064)
					(end 65.115694 -408.731466)
				)
				(arc
					(start 65.410588 -408.923998)
					(mid 65.430512 -408.933234)
					(end 65.452244 -408.936444)
				)
				(arc
					(start 65.646808 -408.936444)
					(mid 65.70069 -408.914126)
					(end 65.723008 -408.860244)
				)
				(arc
					(start 65.723008 -408.174444)
					(mid 65.70069 -408.120562)
					(end 65.646808 -408.098244)
				)
				(arc
					(start 65.452244 -408.098244)
					(mid 65.4305 -408.101412)
					(end 65.410588 -408.11069)
				)
				(arc
					(start 65.114424 -408.303476)
					(mid 65.07274 -408.315698)
					(end 65.031112 -408.303222)
				)
				(arc
					(start 64.737488 -408.11069)
					(mid 64.717564 -408.101454)
					(end 64.695832 -408.098244)
				)
				(arc
					(start 64.501268 -408.098244)
					(mid 64.447386 -408.120562)
					(end 64.425068 -408.174444)
				)
			)
		)
	)
	(zone
		(layer "In1.Cu")
		(hatch none 0.5)
		(connect_pads
			(clearance 0)
		)
		(min_thickness 0.25)
		(keepout
			(tracks not_allowed)
			(vias allowed)
			(pads allowed)
			(copperpour not_allowed)
			(footprints allowed)
		)
		(placement
			(enabled no)
			(sheetname "")
		)
		(fill
			(thermal_gap 0.5)
			(thermal_bridge_width 0.5)
			(island_removal_mode 0)
		)
		(polygon
			(pts
				(arc
					(start 388.428484 -14.882114)
					(mid 388.467525 -14.874357)
					(end 388.500366 -14.851888)
				)
				(arc
					(start 388.500366 -14.851888)
					(mid 388.520408 -14.8212)
					(end 388.528052 -14.78534)
				)
				(xy 388.528052 -14.6431) (xy 388.527798 -14.6431)
				(arc
					(start 388.527798 -13.715746)
					(mid 388.498608 -13.65224)
					(end 388.43458 -13.624306)
				)
				(arc
					(start 388.127748 -13.624306)
					(mid 388.088707 -13.632063)
					(end 388.055866 -13.654532)
				)
				(arc
					(start 388.055866 -13.654532)
					(mid 388.035824 -13.68522)
					(end 388.02818 -13.72108)
				)
				(xy 388.02818 -14.75232) (xy 388.028434 -14.75232)
				(arc
					(start 388.028434 -14.790674)
					(mid 388.057624 -14.85418)
					(end 388.121652 -14.882114)
				)
			)
		)
	)
	(zone
		(layer "In1.Cu")
		(hatch none 0.5)
		(connect_pads
			(clearance 0)
		)
		(min_thickness 0.25)
		(keepout
			(tracks not_allowed)
			(vias allowed)
			(pads allowed)
			(copperpour not_allowed)
			(footprints allowed)
		)
		(placement
			(enabled no)
			(sheetname "")
		)
		(fill
			(thermal_gap 0.5)
			(thermal_bridge_width 0.5)
			(island_removal_mode 0)
		)
		(polygon
			(pts
				(arc
					(start 87.584788 -402.713952)
					(mid 87.607106 -402.767834)
					(end 87.660988 -402.790152)
				)
				(arc
					(start 87.856568 -402.790152)
					(mid 87.878444 -402.78702)
					(end 87.898478 -402.777706)
				)
				(arc
					(start 88.192102 -402.585174)
					(mid 88.233758 -402.572772)
					(end 88.275414 -402.585174)
				)
				(arc
					(start 88.570308 -402.777706)
					(mid 88.590232 -402.786942)
					(end 88.611964 -402.790152)
				)
				(arc
					(start 88.806528 -402.790152)
					(mid 88.86041 -402.767834)
					(end 88.882728 -402.713952)
				)
				(arc
					(start 88.882728 -402.028152)
					(mid 88.86041 -401.97427)
					(end 88.806528 -401.951952)
				)
				(arc
					(start 88.611964 -401.951952)
					(mid 88.59022 -401.95512)
					(end 88.570308 -401.964398)
				)
				(arc
					(start 88.274144 -402.157184)
					(mid 88.23246 -402.169406)
					(end 88.190832 -402.15693)
				)
				(arc
					(start 87.897208 -401.964398)
					(mid 87.877284 -401.955162)
					(end 87.855552 -401.951952)
				)
				(arc
					(start 87.660988 -401.951952)
					(mid 87.607106 -401.97427)
					(end 87.584788 -402.028152)
				)
			)
		)
	)
	(zone
		(layer "In1.Cu")
		(hatch none 0.5)
		(connect_pads
			(clearance 0)
		)
		(min_thickness 0.25)
		(keepout
			(tracks not_allowed)
			(vias allowed)
			(pads allowed)
			(copperpour not_allowed)
			(footprints allowed)
		)
		(placement
			(enabled no)
			(sheetname "")
		)
		(fill
			(thermal_gap 0.5)
			(thermal_bridge_width 0.5)
			(island_removal_mode 0)
		)
		(polygon
			(pts
				(arc
					(start 418.50056 -408.860244)
					(mid 418.522878 -408.914126)
					(end 418.57676 -408.936444)
				)
				(arc
					(start 418.77234 -408.936444)
					(mid 418.794216 -408.933312)
					(end 418.81425 -408.923998)
				)
				(arc
					(start 419.107874 -408.731466)
					(mid 419.14953 -408.719064)
					(end 419.191186 -408.731466)
				)
				(arc
					(start 419.48608 -408.923998)
					(mid 419.506004 -408.933234)
					(end 419.527736 -408.936444)
				)
				(arc
					(start 419.7223 -408.936444)
					(mid 419.776182 -408.914126)
					(end 419.7985 -408.860244)
				)
				(arc
					(start 419.7985 -408.174444)
					(mid 419.776182 -408.120562)
					(end 419.7223 -408.098244)
				)
				(arc
					(start 419.527736 -408.098244)
					(mid 419.505992 -408.101412)
					(end 419.48608 -408.11069)
				)
				(arc
					(start 419.189916 -408.303476)
					(mid 419.148232 -408.315698)
					(end 419.106604 -408.303222)
				)
				(arc
					(start 418.81298 -408.11069)
					(mid 418.793056 -408.101454)
					(end 418.771324 -408.098244)
				)
				(arc
					(start 418.57676 -408.098244)
					(mid 418.522878 -408.120562)
					(end 418.50056 -408.174444)
				)
			)
		)
	)
	(zone
		(layer "In1.Cu")
		(hatch none 0.5)
		(connect_pads
			(clearance 0)
		)
		(min_thickness 0.25)
		(keepout
			(tracks not_allowed)
			(vias allowed)
			(pads allowed)
			(copperpour not_allowed)
			(footprints allowed)
		)
		(placement
			(enabled no)
			(sheetname "")
		)
		(fill
			(thermal_gap 0.5)
			(thermal_bridge_width 0.5)
			(island_removal_mode 0)
		)
		(polygon
			(pts
				(arc
					(start 40.077136 -7.672324)
					(mid 40.054818 -7.618442)
					(end 40.000936 -7.596124)
				)
				(arc
					(start 38.719506 -7.596124)
					(mid 38.665624 -7.618442)
					(end 38.643306 -7.672324)
				)
				(arc
					(start 38.643306 -9.094724)
					(mid 38.665624 -9.148606)
					(end 38.719506 -9.170924)
				)
				(arc
					(start 40.000936 -9.170924)
					(mid 40.054818 -9.148606)
					(end 40.077136 -9.094724)
				)
			)
		)
	)
	(zone
		(layer "In1.Cu")
		(hatch none 0.5)
		(connect_pads
			(clearance 0)
		)
		(min_thickness 0.25)
		(keepout
			(tracks not_allowed)
			(vias allowed)
			(pads allowed)
			(copperpour not_allowed)
			(footprints allowed)
		)
		(placement
			(enabled no)
			(sheetname "")
		)
		(fill
			(thermal_gap 0.5)
			(thermal_bridge_width 0.5)
			(island_removal_mode 0)
		)
		(polygon
			(pts
				(arc
					(start 22.309836 -384.349244)
					(mid 22.270795 -384.357001)
					(end 22.237954 -384.37947)
				)
				(arc
					(start 22.237954 -384.37947)
					(mid 22.217912 -384.410158)
					(end 22.210268 -384.446018)
				)
				(xy 22.210268 -384.588258) (xy 22.210522 -384.588258)
				(arc
					(start 22.210522 -385.515612)
					(mid 22.239712 -385.579118)
					(end 22.30374 -385.607052)
				)
				(arc
					(start 22.610572 -385.607052)
					(mid 22.649613 -385.599295)
					(end 22.682454 -385.576826)
				)
				(arc
					(start 22.682454 -385.576826)
					(mid 22.702496 -385.546138)
					(end 22.71014 -385.510278)
				)
				(xy 22.71014 -384.479038) (xy 22.709886 -384.479038)
				(arc
					(start 22.709886 -384.440684)
					(mid 22.680696 -384.377178)
					(end 22.616668 -384.349244)
				)
			)
		)
	)
	(zone
		(layer "In1.Cu")
		(hatch none 0.5)
		(connect_pads
			(clearance 0)
		)
		(min_thickness 0.25)
		(keepout
			(tracks not_allowed)
			(vias allowed)
			(pads allowed)
			(copperpour not_allowed)
			(footprints allowed)
		)
		(placement
			(enabled no)
			(sheetname "")
		)
		(fill
			(thermal_gap 0.5)
			(thermal_bridge_width 0.5)
			(island_removal_mode 0)
		)
		(polygon
			(pts
				(arc
					(start 176.38268 -53.936138)
					(mid 176.328798 -53.91382)
					(end 176.30648 -53.859938)
				)
				(arc
					(start 176.30648 -53.227478)
					(mid 176.328798 -53.173596)
					(end 176.38268 -53.151278)
				)
				(arc
					(start 177.83556 -53.151278)
					(mid 177.889442 -53.173596)
					(end 177.91176 -53.227478)
				)
				(arc
					(start 177.91176 -53.859938)
					(mid 177.889442 -53.91382)
					(end 177.83556 -53.936138)
				)
			)
		)
	)
	(zone
		(layer "In1.Cu")
		(hatch none 0.5)
		(connect_pads
			(clearance 0)
		)
		(min_thickness 0.25)
		(keepout
			(tracks not_allowed)
			(vias allowed)
			(pads allowed)
			(copperpour not_allowed)
			(footprints allowed)
		)
		(placement
			(enabled no)
			(sheetname "")
		)
		(fill
			(thermal_gap 0.5)
			(thermal_bridge_width 0.5)
			(island_removal_mode 0)
		)
		(polygon
			(pts
				(arc
					(start 412.37408 -408.860244)
					(mid 412.396398 -408.914126)
					(end 412.45028 -408.936444)
				)
				(arc
					(start 412.64586 -408.936444)
					(mid 412.667736 -408.933312)
					(end 412.68777 -408.923998)
				)
				(arc
					(start 412.981394 -408.731466)
					(mid 413.02305 -408.719064)
					(end 413.064706 -408.731466)
				)
				(arc
					(start 413.3596 -408.923998)
					(mid 413.379524 -408.933234)
					(end 413.401256 -408.936444)
				)
				(arc
					(start 413.59582 -408.936444)
					(mid 413.649702 -408.914126)
					(end 413.67202 -408.860244)
				)
				(arc
					(start 413.67202 -408.174444)
					(mid 413.649702 -408.120562)
					(end 413.59582 -408.098244)
				)
				(arc
					(start 413.401256 -408.098244)
					(mid 413.379512 -408.101412)
					(end 413.3596 -408.11069)
				)
				(arc
					(start 413.063436 -408.303476)
					(mid 413.021752 -408.315698)
					(end 412.980124 -408.303222)
				)
				(arc
					(start 412.6865 -408.11069)
					(mid 412.666576 -408.101454)
					(end 412.644844 -408.098244)
				)
				(arc
					(start 412.45028 -408.098244)
					(mid 412.396398 -408.120562)
					(end 412.37408 -408.174444)
				)
			)
		)
	)
	(zone
		(layer "In1.Cu")
		(hatch none 0.5)
		(connect_pads
			(clearance 0)
		)
		(min_thickness 0.25)
		(keepout
			(tracks not_allowed)
			(vias allowed)
			(pads allowed)
			(copperpour not_allowed)
			(footprints allowed)
		)
		(placement
			(enabled no)
			(sheetname "")
		)
		(fill
			(thermal_gap 0.5)
			(thermal_bridge_width 0.5)
			(island_removal_mode 0)
		)
		(polygon
			(pts
				(arc
					(start 136.600184 -408.860244)
					(mid 136.622502 -408.914126)
					(end 136.676384 -408.936444)
				)
				(arc
					(start 136.871964 -408.936444)
					(mid 136.89384 -408.933312)
					(end 136.913874 -408.923998)
				)
				(arc
					(start 137.207498 -408.731466)
					(mid 137.249154 -408.719064)
					(end 137.29081 -408.731466)
				)
				(arc
					(start 137.585704 -408.923998)
					(mid 137.605628 -408.933234)
					(end 137.62736 -408.936444)
				)
				(arc
					(start 137.821924 -408.936444)
					(mid 137.875806 -408.914126)
					(end 137.898124 -408.860244)
				)
				(arc
					(start 137.898124 -408.174444)
					(mid 137.875806 -408.120562)
					(end 137.821924 -408.098244)
				)
				(arc
					(start 137.62736 -408.098244)
					(mid 137.605616 -408.101412)
					(end 137.585704 -408.11069)
				)
				(arc
					(start 137.28954 -408.303476)
					(mid 137.247856 -408.315698)
					(end 137.206228 -408.303222)
				)
				(arc
					(start 136.912604 -408.11069)
					(mid 136.89268 -408.101454)
					(end 136.870948 -408.098244)
				)
				(arc
					(start 136.676384 -408.098244)
					(mid 136.622502 -408.120562)
					(end 136.600184 -408.174444)
				)
			)
		)
	)
	(zone
		(layer "In1.Cu")
		(hatch none 0.5)
		(connect_pads
			(clearance 0)
		)
		(min_thickness 0.25)
		(keepout
			(tracks not_allowed)
			(vias allowed)
			(pads allowed)
			(copperpour not_allowed)
			(footprints allowed)
		)
		(placement
			(enabled no)
			(sheetname "")
		)
		(fill
			(thermal_gap 0.5)
			(thermal_bridge_width 0.5)
			(island_removal_mode 0)
		)
		(polygon
			(pts
				(arc
					(start 51.649122 -11.91768)
					(mid 51.67144 -11.971562)
					(end 51.725322 -11.99388)
				)
				(arc
					(start 53.006752 -11.99388)
					(mid 53.060634 -11.971562)
					(end 53.082952 -11.91768)
				)
				(arc
					(start 53.082952 -10.49528)
					(mid 53.060634 -10.441398)
					(end 53.006752 -10.41908)
				)
				(arc
					(start 51.725322 -10.41908)
					(mid 51.67144 -10.441398)
					(end 51.649122 -10.49528)
				)
			)
		)
	)
	(zone
		(layer "In1.Cu")
		(hatch none 0.5)
		(connect_pads
			(clearance 0)
		)
		(min_thickness 0.25)
		(keepout
			(tracks not_allowed)
			(vias allowed)
			(pads allowed)
			(copperpour not_allowed)
			(footprints allowed)
		)
		(placement
			(enabled no)
			(sheetname "")
		)
		(fill
			(thermal_gap 0.5)
			(thermal_bridge_width 0.5)
			(island_removal_mode 0)
		)
		(polygon
			(pts
				(arc
					(start 349.711518 -402.713952)
					(mid 349.733836 -402.767834)
					(end 349.787718 -402.790152)
				)
				(arc
					(start 349.983298 -402.790152)
					(mid 350.005174 -402.78702)
					(end 350.025208 -402.777706)
				)
				(arc
					(start 350.318832 -402.585174)
					(mid 350.360488 -402.572772)
					(end 350.402144 -402.585174)
				)
				(arc
					(start 350.697038 -402.777706)
					(mid 350.716962 -402.786942)
					(end 350.738694 -402.790152)
				)
				(arc
					(start 350.933258 -402.790152)
					(mid 350.98714 -402.767834)
					(end 351.009458 -402.713952)
				)
				(arc
					(start 351.009458 -402.028152)
					(mid 350.98714 -401.97427)
					(end 350.933258 -401.951952)
				)
				(arc
					(start 350.738694 -401.951952)
					(mid 350.71695 -401.95512)
					(end 350.697038 -401.964398)
				)
				(arc
					(start 350.400874 -402.157184)
					(mid 350.35919 -402.169406)
					(end 350.317562 -402.15693)
				)
				(arc
					(start 350.023938 -401.964398)
					(mid 350.004014 -401.955162)
					(end 349.982282 -401.951952)
				)
				(arc
					(start 349.787718 -401.951952)
					(mid 349.733836 -401.97427)
					(end 349.711518 -402.028152)
				)
			)
		)
	)
	(zone
		(layer "In1.Cu")
		(hatch none 0.5)
		(connect_pads
			(clearance 0)
		)
		(min_thickness 0.25)
		(keepout
			(tracks not_allowed)
			(vias allowed)
			(pads allowed)
			(copperpour not_allowed)
			(footprints allowed)
		)
		(placement
			(enabled no)
			(sheetname "")
		)
		(fill
			(thermal_gap 0.5)
			(thermal_bridge_width 0.5)
			(island_removal_mode 0)
		)
		(polygon
			(pts
				(arc
					(start 167.232584 -408.860244)
					(mid 167.254902 -408.914126)
					(end 167.308784 -408.936444)
				)
				(arc
					(start 167.504364 -408.936444)
					(mid 167.52624 -408.933312)
					(end 167.546274 -408.923998)
				)
				(arc
					(start 167.839898 -408.731466)
					(mid 167.881554 -408.719064)
					(end 167.92321 -408.731466)
				)
				(arc
					(start 168.218104 -408.923998)
					(mid 168.238028 -408.933234)
					(end 168.25976 -408.936444)
				)
				(arc
					(start 168.454324 -408.936444)
					(mid 168.508206 -408.914126)
					(end 168.530524 -408.860244)
				)
				(arc
					(start 168.530524 -408.174444)
					(mid 168.508206 -408.120562)
					(end 168.454324 -408.098244)
				)
				(arc
					(start 168.25976 -408.098244)
					(mid 168.238016 -408.101412)
					(end 168.218104 -408.11069)
				)
				(arc
					(start 167.92194 -408.303476)
					(mid 167.880256 -408.315698)
					(end 167.838628 -408.303222)
				)
				(arc
					(start 167.545004 -408.11069)
					(mid 167.52508 -408.101454)
					(end 167.503348 -408.098244)
				)
				(arc
					(start 167.308784 -408.098244)
					(mid 167.254902 -408.120562)
					(end 167.232584 -408.174444)
				)
			)
		)
	)
	(zone
		(layer "In1.Cu")
		(hatch none 0.5)
		(connect_pads
			(clearance 0)
		)
		(min_thickness 0.25)
		(keepout
			(tracks not_allowed)
			(vias allowed)
			(pads allowed)
			(copperpour not_allowed)
			(footprints allowed)
		)
		(placement
			(enabled no)
			(sheetname "")
		)
		(fill
			(thermal_gap 0.5)
			(thermal_bridge_width 0.5)
			(island_removal_mode 0)
		)
		(polygon
			(pts
				(arc
					(start 144.443704 -402.713952)
					(mid 144.466022 -402.767834)
					(end 144.519904 -402.790152)
				)
				(arc
					(start 144.715484 -402.790152)
					(mid 144.73736 -402.78702)
					(end 144.757394 -402.777706)
				)
				(arc
					(start 145.051018 -402.585174)
					(mid 145.092674 -402.572772)
					(end 145.13433 -402.585174)
				)
				(arc
					(start 145.429224 -402.777706)
					(mid 145.449148 -402.786942)
					(end 145.47088 -402.790152)
				)
				(arc
					(start 145.665444 -402.790152)
					(mid 145.719326 -402.767834)
					(end 145.741644 -402.713952)
				)
				(arc
					(start 145.741644 -402.028152)
					(mid 145.719326 -401.97427)
					(end 145.665444 -401.951952)
				)
				(arc
					(start 145.47088 -401.951952)
					(mid 145.449136 -401.95512)
					(end 145.429224 -401.964398)
				)
				(arc
					(start 145.13306 -402.157184)
					(mid 145.091376 -402.169406)
					(end 145.049748 -402.15693)
				)
				(arc
					(start 144.756124 -401.964398)
					(mid 144.7362 -401.955162)
					(end 144.714468 -401.951952)
				)
				(arc
					(start 144.519904 -401.951952)
					(mid 144.466022 -401.97427)
					(end 144.443704 -402.028152)
				)
			)
		)
	)
	(zone
		(layer "In1.Cu")
		(hatch none 0.5)
		(connect_pads
			(clearance 0)
		)
		(min_thickness 0.25)
		(keepout
			(tracks not_allowed)
			(vias allowed)
			(pads allowed)
			(copperpour not_allowed)
			(footprints allowed)
		)
		(placement
			(enabled no)
			(sheetname "")
		)
		(fill
			(thermal_gap 0.5)
			(thermal_bridge_width 0.5)
			(island_removal_mode 0)
		)
		(polygon
			(pts
				(arc
					(start 16.871188 -103.055928)
					(mid 16.109696 -103.055928)
					(end 16.871188 -103.055928)
				)
			)
		)
	)
	(zone
		(layer "In1.Cu")
		(hatch none 0.5)
		(connect_pads
			(clearance 0)
		)
		(min_thickness 0.25)
		(keepout
			(tracks not_allowed)
			(vias allowed)
			(pads allowed)
			(copperpour not_allowed)
			(footprints allowed)
		)
		(placement
			(enabled no)
			(sheetname "")
		)
		(fill
			(thermal_gap 0.5)
			(thermal_bridge_width 0.5)
			(island_removal_mode 0)
		)
		(polygon
			(pts
				(arc
					(start 323.488558 -408.860244)
					(mid 323.510876 -408.914126)
					(end 323.564758 -408.936444)
				)
				(arc
					(start 323.760338 -408.936444)
					(mid 323.782214 -408.933312)
					(end 323.802248 -408.923998)
				)
				(arc
					(start 324.095872 -408.731466)
					(mid 324.137528 -408.719064)
					(end 324.179184 -408.731466)
				)
				(arc
					(start 324.474078 -408.923998)
					(mid 324.494002 -408.933234)
					(end 324.515734 -408.936444)
				)
				(arc
					(start 324.710298 -408.936444)
					(mid 324.76418 -408.914126)
					(end 324.786498 -408.860244)
				)
				(arc
					(start 324.786498 -408.174444)
					(mid 324.76418 -408.120562)
					(end 324.710298 -408.098244)
				)
				(arc
					(start 324.515734 -408.098244)
					(mid 324.49399 -408.101412)
					(end 324.474078 -408.11069)
				)
				(arc
					(start 324.177914 -408.303476)
					(mid 324.13623 -408.315698)
					(end 324.094602 -408.303222)
				)
				(arc
					(start 323.800978 -408.11069)
					(mid 323.781054 -408.101454)
					(end 323.759322 -408.098244)
				)
				(arc
					(start 323.564758 -408.098244)
					(mid 323.510876 -408.120562)
					(end 323.488558 -408.174444)
				)
			)
		)
	)
	(zone
		(layer "In1.Cu")
		(hatch none 0.5)
		(connect_pads
			(clearance 0)
		)
		(min_thickness 0.25)
		(keepout
			(tracks not_allowed)
			(vias allowed)
			(pads allowed)
			(copperpour not_allowed)
			(footprints allowed)
		)
		(placement
			(enabled no)
			(sheetname "")
		)
		(fill
			(thermal_gap 0.5)
			(thermal_bridge_width 0.5)
			(island_removal_mode 0)
		)
		(polygon
			(pts
				(arc
					(start 342.68029 -69.64426)
					(mid 342.657972 -69.590378)
					(end 342.60409 -69.56806)
				)
				(arc
					(start 342.27389 -69.56806)
					(mid 342.220008 -69.590378)
					(end 342.19769 -69.64426)
				)
				(arc
					(start 342.19769 -69.89826)
					(mid 342.220008 -69.952142)
					(end 342.27389 -69.97446)
				)
				(arc
					(start 342.60409 -69.97446)
					(mid 342.657972 -69.952142)
					(end 342.68029 -69.89826)
				)
			)
		)
	)
	(zone
		(layer "In1.Cu")
		(hatch none 0.5)
		(connect_pads
			(clearance 0)
		)
		(min_thickness 0.25)
		(keepout
			(tracks not_allowed)
			(vias allowed)
			(pads allowed)
			(copperpour not_allowed)
			(footprints allowed)
		)
		(placement
			(enabled no)
			(sheetname "")
		)
		(fill
			(thermal_gap 0.5)
			(thermal_bridge_width 0.5)
			(island_removal_mode 0)
		)
		(polygon
			(pts
				(arc
					(start 145.789904 -408.860244)
					(mid 145.812222 -408.914126)
					(end 145.866104 -408.936444)
				)
				(arc
					(start 146.061684 -408.936444)
					(mid 146.08356 -408.933312)
					(end 146.103594 -408.923998)
				)
				(arc
					(start 146.397218 -408.731466)
					(mid 146.438874 -408.719064)
					(end 146.48053 -408.731466)
				)
				(arc
					(start 146.775424 -408.923998)
					(mid 146.795348 -408.933234)
					(end 146.81708 -408.936444)
				)
				(arc
					(start 147.011644 -408.936444)
					(mid 147.065526 -408.914126)
					(end 147.087844 -408.860244)
				)
				(arc
					(start 147.087844 -408.174444)
					(mid 147.065526 -408.120562)
					(end 147.011644 -408.098244)
				)
				(arc
					(start 146.81708 -408.098244)
					(mid 146.795336 -408.101412)
					(end 146.775424 -408.11069)
				)
				(arc
					(start 146.47926 -408.303476)
					(mid 146.437576 -408.315698)
					(end 146.395948 -408.303222)
				)
				(arc
					(start 146.102324 -408.11069)
					(mid 146.0824 -408.101454)
					(end 146.060668 -408.098244)
				)
				(arc
					(start 145.866104 -408.098244)
					(mid 145.812222 -408.120562)
					(end 145.789904 -408.174444)
				)
			)
		)
	)
	(zone
		(layer "In1.Cu")
		(hatch none 0.5)
		(connect_pads
			(clearance 0)
		)
		(min_thickness 0.25)
		(keepout
			(tracks not_allowed)
			(vias allowed)
			(pads allowed)
			(copperpour not_allowed)
			(footprints allowed)
		)
		(placement
			(enabled no)
			(sheetname "")
		)
		(fill
			(thermal_gap 0.5)
			(thermal_bridge_width 0.5)
			(island_removal_mode 0)
		)
		(polygon
			(pts
				(arc
					(start 142.726664 -408.860244)
					(mid 142.748982 -408.914126)
					(end 142.802864 -408.936444)
				)
				(arc
					(start 142.998444 -408.936444)
					(mid 143.02032 -408.933312)
					(end 143.040354 -408.923998)
				)
				(arc
					(start 143.333978 -408.731466)
					(mid 143.375634 -408.719064)
					(end 143.41729 -408.731466)
				)
				(arc
					(start 143.712184 -408.923998)
					(mid 143.732108 -408.933234)
					(end 143.75384 -408.936444)
				)
				(arc
					(start 143.948404 -408.936444)
					(mid 144.002286 -408.914126)
					(end 144.024604 -408.860244)
				)
				(arc
					(start 144.024604 -408.174444)
					(mid 144.002286 -408.120562)
					(end 143.948404 -408.098244)
				)
				(arc
					(start 143.75384 -408.098244)
					(mid 143.732096 -408.101412)
					(end 143.712184 -408.11069)
				)
				(arc
					(start 143.41602 -408.303476)
					(mid 143.374336 -408.315698)
					(end 143.332708 -408.303222)
				)
				(arc
					(start 143.039084 -408.11069)
					(mid 143.01916 -408.101454)
					(end 142.997428 -408.098244)
				)
				(arc
					(start 142.802864 -408.098244)
					(mid 142.748982 -408.120562)
					(end 142.726664 -408.174444)
				)
			)
		)
	)
	(zone
		(layer "In1.Cu")
		(hatch none 0.5)
		(connect_pads
			(clearance 0)
		)
		(min_thickness 0.25)
		(keepout
			(tracks not_allowed)
			(vias allowed)
			(pads allowed)
			(copperpour not_allowed)
			(footprints allowed)
		)
		(placement
			(enabled no)
			(sheetname "")
		)
		(fill
			(thermal_gap 0.5)
			(thermal_bridge_width 0.5)
			(island_removal_mode 0)
		)
		(polygon
			(pts
				(arc
					(start 413.137858 -11.91768)
					(mid 413.160176 -11.971562)
					(end 413.214058 -11.99388)
				)
				(arc
					(start 414.495488 -11.99388)
					(mid 414.54937 -11.971562)
					(end 414.571688 -11.91768)
				)
				(arc
					(start 414.571688 -10.49528)
					(mid 414.54937 -10.441398)
					(end 414.495488 -10.41908)
				)
				(arc
					(start 413.214058 -10.41908)
					(mid 413.160176 -10.441398)
					(end 413.137858 -10.49528)
				)
			)
		)
	)
	(zone
		(layer "In1.Cu")
		(hatch none 0.5)
		(connect_pads
			(clearance 0)
		)
		(min_thickness 0.25)
		(keepout
			(tracks not_allowed)
			(vias allowed)
			(pads allowed)
			(copperpour not_allowed)
			(footprints allowed)
		)
		(placement
			(enabled no)
			(sheetname "")
		)
		(fill
			(thermal_gap 0.5)
			(thermal_bridge_width 0.5)
			(island_removal_mode 0)
		)
		(polygon
			(pts
				(xy 135.556244 -15.825978) (xy 136.537192 -15.825978) (xy 136.537192 -17.273778) (xy 135.556244 -17.273778)
			)
		)
	)
	(zone
		(layer "In1.Cu")
		(hatch none 0.5)
		(connect_pads
			(clearance 0)
		)
		(min_thickness 0.25)
		(keepout
			(tracks not_allowed)
			(vias allowed)
			(pads allowed)
			(copperpour not_allowed)
			(footprints allowed)
		)
		(placement
			(enabled no)
			(sheetname "")
		)
		(fill
			(thermal_gap 0.5)
			(thermal_bridge_width 0.5)
			(island_removal_mode 0)
		)
		(polygon
			(pts
				(arc
					(start 21.96719 -7.672324)
					(mid 21.944872 -7.618442)
					(end 21.89099 -7.596124)
				)
				(arc
					(start 20.60956 -7.596124)
					(mid 20.555678 -7.618442)
					(end 20.53336 -7.672324)
				)
				(arc
					(start 20.53336 -9.094724)
					(mid 20.555678 -9.148606)
					(end 20.60956 -9.170924)
				)
				(arc
					(start 21.89099 -9.170924)
					(mid 21.944872 -9.148606)
					(end 21.96719 -9.094724)
				)
			)
		)
	)
	(zone
		(layer "In1.Cu")
		(hatch none 0.5)
		(connect_pads
			(clearance 0)
		)
		(min_thickness 0.25)
		(keepout
			(tracks not_allowed)
			(vias allowed)
			(pads allowed)
			(copperpour not_allowed)
			(footprints allowed)
		)
		(placement
			(enabled no)
			(sheetname "")
		)
		(fill
			(thermal_gap 0.5)
			(thermal_bridge_width 0.5)
			(island_removal_mode 0)
		)
		(polygon
			(pts
				(arc
					(start 58.298588 -408.860244)
					(mid 58.320906 -408.914126)
					(end 58.374788 -408.936444)
				)
				(arc
					(start 58.570368 -408.936444)
					(mid 58.592244 -408.933312)
					(end 58.612278 -408.923998)
				)
				(arc
					(start 58.905902 -408.731466)
					(mid 58.947558 -408.719064)
					(end 58.989214 -408.731466)
				)
				(arc
					(start 59.284108 -408.923998)
					(mid 59.304032 -408.933234)
					(end 59.325764 -408.936444)
				)
				(arc
					(start 59.520328 -408.936444)
					(mid 59.57421 -408.914126)
					(end 59.596528 -408.860244)
				)
				(arc
					(start 59.596528 -408.174444)
					(mid 59.57421 -408.120562)
					(end 59.520328 -408.098244)
				)
				(arc
					(start 59.325764 -408.098244)
					(mid 59.30402 -408.101412)
					(end 59.284108 -408.11069)
				)
				(arc
					(start 58.987944 -408.303476)
					(mid 58.94626 -408.315698)
					(end 58.904632 -408.303222)
				)
				(arc
					(start 58.611008 -408.11069)
					(mid 58.591084 -408.101454)
					(end 58.569352 -408.098244)
				)
				(arc
					(start 58.374788 -408.098244)
					(mid 58.320906 -408.120562)
					(end 58.298588 -408.174444)
				)
			)
		)
	)
	(zone
		(layer "In1.Cu")
		(hatch none 0.5)
		(connect_pads
			(clearance 0)
		)
		(min_thickness 0.25)
		(keepout
			(tracks not_allowed)
			(vias allowed)
			(pads allowed)
			(copperpour not_allowed)
			(footprints allowed)
		)
		(placement
			(enabled no)
			(sheetname "")
		)
		(fill
			(thermal_gap 0.5)
			(thermal_bridge_width 0.5)
			(island_removal_mode 0)
		)
		(polygon
			(pts
				(arc
					(start 32.767016 -7.672324)
					(mid 32.744698 -7.618442)
					(end 32.690816 -7.596124)
				)
				(arc
					(start 31.409386 -7.596124)
					(mid 31.355504 -7.618442)
					(end 31.333186 -7.672324)
				)
				(arc
					(start 31.333186 -9.094724)
					(mid 31.355504 -9.148606)
					(end 31.409386 -9.170924)
				)
				(arc
					(start 32.690816 -9.170924)
					(mid 32.744698 -9.148606)
					(end 32.767016 -9.094724)
				)
			)
		)
	)
	(zone
		(layer "In1.Cu")
		(hatch none 0.5)
		(connect_pads
			(clearance 0)
		)
		(min_thickness 0.25)
		(keepout
			(tracks not_allowed)
			(vias allowed)
			(pads allowed)
			(copperpour not_allowed)
			(footprints allowed)
		)
		(placement
			(enabled no)
			(sheetname "")
		)
		(fill
			(thermal_gap 0.5)
			(thermal_bridge_width 0.5)
			(island_removal_mode 0)
		)
		(polygon
			(pts
				(arc
					(start 317.362078 -408.860244)
					(mid 317.384396 -408.914126)
					(end 317.438278 -408.936444)
				)
				(arc
					(start 317.633858 -408.936444)
					(mid 317.655734 -408.933312)
					(end 317.675768 -408.923998)
				)
				(arc
					(start 317.969392 -408.731466)
					(mid 318.011048 -408.719064)
					(end 318.052704 -408.731466)
				)
				(arc
					(start 318.347598 -408.923998)
					(mid 318.367522 -408.933234)
					(end 318.389254 -408.936444)
				)
				(arc
					(start 318.583818 -408.936444)
					(mid 318.6377 -408.914126)
					(end 318.660018 -408.860244)
				)
				(arc
					(start 318.660018 -408.174444)
					(mid 318.6377 -408.120562)
					(end 318.583818 -408.098244)
				)
				(arc
					(start 318.389254 -408.098244)
					(mid 318.36751 -408.101412)
					(end 318.347598 -408.11069)
				)
				(arc
					(start 318.051434 -408.303476)
					(mid 318.00975 -408.315698)
					(end 317.968122 -408.303222)
				)
				(arc
					(start 317.674498 -408.11069)
					(mid 317.654574 -408.101454)
					(end 317.632842 -408.098244)
				)
				(arc
					(start 317.438278 -408.098244)
					(mid 317.384396 -408.120562)
					(end 317.362078 -408.174444)
				)
			)
		)
	)
	(zone
		(layer "In1.Cu")
		(hatch none 0.5)
		(connect_pads
			(clearance 0)
		)
		(min_thickness 0.25)
		(keepout
			(tracks not_allowed)
			(vias allowed)
			(pads allowed)
			(copperpour not_allowed)
			(footprints allowed)
		)
		(placement
			(enabled no)
			(sheetname "")
		)
		(fill
			(thermal_gap 0.5)
			(thermal_bridge_width 0.5)
			(island_removal_mode 0)
		)
		(polygon
			(pts
				(arc
					(start 11.571986 -106.911394)
					(mid 11.611027 -106.903637)
					(end 11.643868 -106.881168)
				)
				(arc
					(start 11.643868 -106.881168)
					(mid 11.66391 -106.85048)
					(end 11.671554 -106.81462)
				)
				(xy 11.671554 -106.67238) (xy 11.6713 -106.67238)
				(arc
					(start 11.6713 -105.745026)
					(mid 11.64211 -105.68152)
					(end 11.578082 -105.653586)
				)
				(arc
					(start 11.27125 -105.653586)
					(mid 11.232209 -105.661343)
					(end 11.199368 -105.683812)
				)
				(arc
					(start 11.199368 -105.683812)
					(mid 11.179326 -105.7145)
					(end 11.171682 -105.75036)
				)
				(xy 11.171682 -106.7816) (xy 11.171936 -106.7816)
				(arc
					(start 11.171936 -106.819954)
					(mid 11.201126 -106.88346)
					(end 11.265154 -106.911394)
				)
			)
		)
	)
	(zone
		(layer "In1.Cu")
		(hatch none 0.5)
		(connect_pads
			(clearance 0)
		)
		(min_thickness 0.25)
		(keepout
			(tracks not_allowed)
			(vias allowed)
			(pads allowed)
			(copperpour not_allowed)
			(footprints allowed)
		)
		(placement
			(enabled no)
			(sheetname "")
		)
		(fill
			(thermal_gap 0.5)
			(thermal_bridge_width 0.5)
			(island_removal_mode 0)
		)
		(polygon
			(pts
				(arc
					(start 378.67844 -408.860244)
					(mid 378.700758 -408.914126)
					(end 378.75464 -408.936444)
				)
				(arc
					(start 378.95022 -408.936444)
					(mid 378.972096 -408.933312)
					(end 378.99213 -408.923998)
				)
				(arc
					(start 379.285754 -408.731466)
					(mid 379.32741 -408.719064)
					(end 379.369066 -408.731466)
				)
				(arc
					(start 379.66396 -408.923998)
					(mid 379.683884 -408.933234)
					(end 379.705616 -408.936444)
				)
				(arc
					(start 379.90018 -408.936444)
					(mid 379.954062 -408.914126)
					(end 379.97638 -408.860244)
				)
				(arc
					(start 379.97638 -408.174444)
					(mid 379.954062 -408.120562)
					(end 379.90018 -408.098244)
				)
				(arc
					(start 379.705616 -408.098244)
					(mid 379.683872 -408.101412)
					(end 379.66396 -408.11069)
				)
				(arc
					(start 379.367796 -408.303476)
					(mid 379.326112 -408.315698)
					(end 379.284484 -408.303222)
				)
				(arc
					(start 378.99086 -408.11069)
					(mid 378.970936 -408.101454)
					(end 378.949204 -408.098244)
				)
				(arc
					(start 378.75464 -408.098244)
					(mid 378.700758 -408.120562)
					(end 378.67844 -408.174444)
				)
			)
		)
	)
	(zone
		(layer "In1.Cu")
		(hatch none 0.5)
		(connect_pads
			(clearance 0)
		)
		(min_thickness 0.25)
		(keepout
			(tracks not_allowed)
			(vias allowed)
			(pads allowed)
			(copperpour not_allowed)
			(footprints allowed)
		)
		(placement
			(enabled no)
			(sheetname "")
		)
		(fill
			(thermal_gap 0.5)
			(thermal_bridge_width 0.5)
			(island_removal_mode 0)
		)
		(polygon
			(pts
				(arc
					(start 45.477176 -7.672324)
					(mid 45.454858 -7.618442)
					(end 45.400976 -7.596124)
				)
				(arc
					(start 44.119546 -7.596124)
					(mid 44.065664 -7.618442)
					(end 44.043346 -7.672324)
				)
				(arc
					(start 44.043346 -9.094724)
					(mid 44.065664 -9.148606)
					(end 44.119546 -9.170924)
				)
				(arc
					(start 45.400976 -9.170924)
					(mid 45.454858 -9.148606)
					(end 45.477176 -9.094724)
				)
			)
		)
	)
	(zone
		(layer "In1.Cu")
		(hatch none 0.5)
		(connect_pads
			(clearance 0)
		)
		(min_thickness 0.25)
		(keepout
			(tracks not_allowed)
			(vias allowed)
			(pads allowed)
			(copperpour not_allowed)
			(footprints allowed)
		)
		(placement
			(enabled no)
			(sheetname "")
		)
		(fill
			(thermal_gap 0.5)
			(thermal_bridge_width 0.5)
			(island_removal_mode 0)
		)
		(polygon
			(pts
				(arc
					(start 14.257274 -107.273852)
					(mid 14.265031 -107.312893)
					(end 14.2875 -107.345734)
				)
				(arc
					(start 14.2875 -107.345734)
					(mid 14.318188 -107.365776)
					(end 14.354048 -107.37342)
				)
				(xy 14.496288 -107.37342) (xy 14.496288 -107.373166)
				(arc
					(start 15.423642 -107.373166)
					(mid 15.487148 -107.343976)
					(end 15.515082 -107.279948)
				)
				(arc
					(start 15.515082 -106.973116)
					(mid 15.507325 -106.934075)
					(end 15.484856 -106.901234)
				)
				(arc
					(start 15.484856 -106.901234)
					(mid 15.454168 -106.881192)
					(end 15.418308 -106.873548)
				)
				(xy 14.387068 -106.873548) (xy 14.387068 -106.873802)
				(arc
					(start 14.348714 -106.873802)
					(mid 14.285208 -106.902992)
					(end 14.257274 -106.96702)
				)
			)
		)
	)
	(zone
		(layer "In1.Cu")
		(hatch none 0.5)
		(connect_pads
			(clearance 0)
		)
		(min_thickness 0.25)
		(keepout
			(tracks not_allowed)
			(vias allowed)
			(pads allowed)
			(copperpour not_allowed)
			(footprints allowed)
		)
		(placement
			(enabled no)
			(sheetname "")
		)
		(fill
			(thermal_gap 0.5)
			(thermal_bridge_width 0.5)
			(island_removal_mode 0)
		)
		(polygon
			(pts
				(xy 137.356342 -15.825978) (xy 138.33729 -15.825978) (xy 138.33729 -17.273778) (xy 137.356342 -17.273778)
			)
		)
	)
	(zone
		(layer "In1.Cu")
		(hatch none 0.5)
		(connect_pads
			(clearance 0)
		)
		(min_thickness 0.25)
		(keepout
			(tracks not_allowed)
			(vias allowed)
			(pads allowed)
			(copperpour not_allowed)
			(footprints allowed)
		)
		(placement
			(enabled no)
			(sheetname "")
		)
		(fill
			(thermal_gap 0.5)
			(thermal_bridge_width 0.5)
			(island_removal_mode 0)
		)
		(polygon
			(pts
				(arc
					(start 13.693648 -15.942818)
					(mid 13.639766 -15.9205)
					(end 13.617448 -15.866618)
				)
				(arc
					(start 13.617448 -14.782292)
					(mid 13.639766 -14.72841)
					(end 13.693648 -14.706092)
				)
				(arc
					(start 14.045184 -14.706092)
					(mid 14.099066 -14.72841)
					(end 14.121384 -14.782292)
				)
				(arc
					(start 14.121384 -15.866618)
					(mid 14.099066 -15.9205)
					(end 14.045184 -15.942818)
				)
			)
		)
	)
	(zone
		(layer "In1.Cu")
		(hatch none 0.5)
		(connect_pads
			(clearance 0)
		)
		(min_thickness 0.25)
		(keepout
			(tracks not_allowed)
			(vias allowed)
			(pads allowed)
			(copperpour not_allowed)
			(footprints allowed)
		)
		(placement
			(enabled no)
			(sheetname "")
		)
		(fill
			(thermal_gap 0.5)
			(thermal_bridge_width 0.5)
			(island_removal_mode 0)
		)
		(polygon
			(pts
				(arc
					(start 160.430718 -44.46143)
					(mid 160.469759 -44.453673)
					(end 160.5026 -44.431204)
				)
				(arc
					(start 160.5026 -44.431204)
					(mid 160.522642 -44.400516)
					(end 160.530286 -44.364656)
				)
				(xy 160.530286 -44.222416) (xy 160.530032 -44.222416)
				(arc
					(start 160.530032 -43.295062)
					(mid 160.500842 -43.231556)
					(end 160.436814 -43.203622)
				)
				(arc
					(start 160.129982 -43.203622)
					(mid 160.090941 -43.211379)
					(end 160.0581 -43.233848)
				)
				(arc
					(start 160.0581 -43.233848)
					(mid 160.038058 -43.264536)
					(end 160.030414 -43.300396)
				)
				(xy 160.030414 -44.331636) (xy 160.030668 -44.331636)
				(arc
					(start 160.030668 -44.36999)
					(mid 160.059858 -44.433496)
					(end 160.123886 -44.46143)
				)
			)
		)
	)
	(zone
		(layer "In1.Cu")
		(hatch none 0.5)
		(connect_pads
			(clearance 0)
		)
		(min_thickness 0.25)
		(keepout
			(tracks not_allowed)
			(vias allowed)
			(pads allowed)
			(copperpour not_allowed)
			(footprints allowed)
		)
		(placement
			(enabled no)
			(sheetname "")
		)
		(fill
			(thermal_gap 0.5)
			(thermal_bridge_width 0.5)
			(island_removal_mode 0)
		)
		(polygon
			(pts
				(arc
					(start 403.665944 -7.672324)
					(mid 403.643626 -7.618442)
					(end 403.589744 -7.596124)
				)
				(arc
					(start 402.308314 -7.596124)
					(mid 402.254432 -7.618442)
					(end 402.232114 -7.672324)
				)
				(arc
					(start 402.232114 -9.094724)
					(mid 402.254432 -9.148606)
					(end 402.308314 -9.170924)
				)
				(arc
					(start 403.589744 -9.170924)
					(mid 403.643626 -9.148606)
					(end 403.665944 -9.094724)
				)
			)
		)
	)
	(zone
		(layer "In1.Cu")
		(hatch none 0.5)
		(connect_pads
			(clearance 0)
		)
		(min_thickness 0.25)
		(keepout
			(tracks not_allowed)
			(vias allowed)
			(pads allowed)
			(copperpour not_allowed)
			(footprints allowed)
		)
		(placement
			(enabled no)
			(sheetname "")
		)
		(fill
			(thermal_gap 0.5)
			(thermal_bridge_width 0.5)
			(island_removal_mode 0)
		)
		(polygon
			(pts
				(arc
					(start 376.986038 -4.150106)
					(mid 377.008356 -4.096224)
					(end 377.062238 -4.073906)
				)
				(arc
					(start 377.674378 -4.073906)
					(mid 377.72826 -4.096224)
					(end 377.750578 -4.150106)
				)
				(arc
					(start 377.750578 -5.247386)
					(mid 377.72826 -5.301268)
					(end 377.674378 -5.323586)
				)
				(arc
					(start 377.062238 -5.323586)
					(mid 377.008356 -5.301268)
					(end 376.986038 -5.247386)
				)
			)
		)
	)
	(zone
		(layer "In1.Cu")
		(hatch none 0.5)
		(connect_pads
			(clearance 0)
		)
		(min_thickness 0.25)
		(keepout
			(tracks not_allowed)
			(vias allowed)
			(pads allowed)
			(copperpour not_allowed)
			(footprints allowed)
		)
		(placement
			(enabled no)
			(sheetname "")
		)
		(fill
			(thermal_gap 0.5)
			(thermal_bridge_width 0.5)
			(island_removal_mode 0)
		)
		(polygon
			(pts
				(arc
					(start 377.33224 -402.713952)
					(mid 377.354558 -402.767834)
					(end 377.40844 -402.790152)
				)
				(arc
					(start 377.60402 -402.790152)
					(mid 377.625896 -402.78702)
					(end 377.64593 -402.777706)
				)
				(arc
					(start 377.939554 -402.585174)
					(mid 377.98121 -402.572772)
					(end 378.022866 -402.585174)
				)
				(arc
					(start 378.31776 -402.777706)
					(mid 378.337684 -402.786942)
					(end 378.359416 -402.790152)
				)
				(arc
					(start 378.55398 -402.790152)
					(mid 378.607862 -402.767834)
					(end 378.63018 -402.713952)
				)
				(arc
					(start 378.63018 -402.028152)
					(mid 378.607862 -401.97427)
					(end 378.55398 -401.951952)
				)
				(arc
					(start 378.359416 -401.951952)
					(mid 378.337672 -401.95512)
					(end 378.31776 -401.964398)
				)
				(arc
					(start 378.021596 -402.157184)
					(mid 377.979912 -402.169406)
					(end 377.938284 -402.15693)
				)
				(arc
					(start 377.64466 -401.964398)
					(mid 377.624736 -401.955162)
					(end 377.603004 -401.951952)
				)
				(arc
					(start 377.40844 -401.951952)
					(mid 377.354558 -401.97427)
					(end 377.33224 -402.028152)
				)
			)
		)
	)
	(zone
		(layer "In1.Cu")
		(hatch none 0.5)
		(connect_pads
			(clearance 0)
		)
		(min_thickness 0.25)
		(keepout
			(tracks not_allowed)
			(vias allowed)
			(pads allowed)
			(copperpour not_allowed)
			(footprints allowed)
		)
		(placement
			(enabled no)
			(sheetname "")
		)
		(fill
			(thermal_gap 0.5)
			(thermal_bridge_width 0.5)
			(island_removal_mode 0)
		)
		(polygon
			(pts
				(arc
					(start 392.618214 -17.955514)
					(mid 392.640532 -18.009396)
					(end 392.694414 -18.031714)
				)
				(arc
					(start 392.889994 -18.031714)
					(mid 392.91187 -18.028582)
					(end 392.931904 -18.019268)
				)
				(arc
					(start 393.225528 -17.826736)
					(mid 393.267184 -17.814334)
					(end 393.30884 -17.826736)
				)
				(arc
					(start 393.603734 -18.019268)
					(mid 393.623658 -18.028504)
					(end 393.64539 -18.031714)
				)
				(arc
					(start 393.839954 -18.031714)
					(mid 393.893836 -18.009396)
					(end 393.916154 -17.955514)
				)
				(arc
					(start 393.916154 -17.269714)
					(mid 393.893836 -17.215832)
					(end 393.839954 -17.193514)
				)
				(arc
					(start 393.64539 -17.193514)
					(mid 393.623646 -17.196682)
					(end 393.603734 -17.20596)
				)
				(arc
					(start 393.30757 -17.398746)
					(mid 393.265886 -17.410968)
					(end 393.224258 -17.398492)
				)
				(arc
					(start 392.930634 -17.20596)
					(mid 392.91071 -17.196724)
					(end 392.888978 -17.193514)
				)
				(arc
					(start 392.694414 -17.193514)
					(mid 392.640532 -17.215832)
					(end 392.618214 -17.269714)
				)
			)
		)
	)
	(zone
		(layer "In1.Cu")
		(hatch none 0.5)
		(connect_pads
			(clearance 0)
		)
		(min_thickness 0.25)
		(keepout
			(tracks not_allowed)
			(vias allowed)
			(pads allowed)
			(copperpour not_allowed)
			(footprints allowed)
		)
		(placement
			(enabled no)
			(sheetname "")
		)
		(fill
			(thermal_gap 0.5)
			(thermal_bridge_width 0.5)
			(island_removal_mode 0)
		)
		(polygon
			(pts
				(xy 157.00502 -40.577008) (xy 157.00502 -39.837868) (xy 157.78226 -39.837868) (xy 157.78226 -40.577008)
			)
		)
	)
	(zone
		(layer "In1.Cu")
		(hatch none 0.5)
		(connect_pads
			(clearance 0)
		)
		(min_thickness 0.25)
		(keepout
			(tracks not_allowed)
			(vias allowed)
			(pads allowed)
			(copperpour not_allowed)
			(footprints allowed)
		)
		(placement
			(enabled no)
			(sheetname "")
		)
		(fill
			(thermal_gap 0.5)
			(thermal_bridge_width 0.5)
			(island_removal_mode 0)
		)
		(polygon
			(pts
				(arc
					(start 159.759904 -402.713952)
					(mid 159.782222 -402.767834)
					(end 159.836104 -402.790152)
				)
				(arc
					(start 160.031684 -402.790152)
					(mid 160.05356 -402.78702)
					(end 160.073594 -402.777706)
				)
				(arc
					(start 160.367218 -402.585174)
					(mid 160.408874 -402.572772)
					(end 160.45053 -402.585174)
				)
				(arc
					(start 160.745424 -402.777706)
					(mid 160.765348 -402.786942)
					(end 160.78708 -402.790152)
				)
				(arc
					(start 160.981644 -402.790152)
					(mid 161.035526 -402.767834)
					(end 161.057844 -402.713952)
				)
				(arc
					(start 161.057844 -402.028152)
					(mid 161.035526 -401.97427)
					(end 160.981644 -401.951952)
				)
				(arc
					(start 160.78708 -401.951952)
					(mid 160.765336 -401.95512)
					(end 160.745424 -401.964398)
				)
				(arc
					(start 160.44926 -402.157184)
					(mid 160.407576 -402.169406)
					(end 160.365948 -402.15693)
				)
				(arc
					(start 160.072324 -401.964398)
					(mid 160.0524 -401.955162)
					(end 160.030668 -401.951952)
				)
				(arc
					(start 159.836104 -401.951952)
					(mid 159.782222 -401.97427)
					(end 159.759904 -402.028152)
				)
			)
		)
	)
	(zone
		(layer "In1.Cu")
		(hatch none 0.5)
		(connect_pads
			(clearance 0)
		)
		(min_thickness 0.25)
		(keepout
			(tracks not_allowed)
			(vias allowed)
			(pads allowed)
			(copperpour not_allowed)
			(footprints allowed)
		)
		(placement
			(enabled no)
			(sheetname "")
		)
		(fill
			(thermal_gap 0.5)
			(thermal_bridge_width 0.5)
			(island_removal_mode 0)
		)
		(polygon
			(pts
				(arc
					(start 375.6152 -408.860244)
					(mid 375.637518 -408.914126)
					(end 375.6914 -408.936444)
				)
				(arc
					(start 375.88698 -408.936444)
					(mid 375.908856 -408.933312)
					(end 375.92889 -408.923998)
				)
				(arc
					(start 376.222514 -408.731466)
					(mid 376.26417 -408.719064)
					(end 376.305826 -408.731466)
				)
				(arc
					(start 376.60072 -408.923998)
					(mid 376.620644 -408.933234)
					(end 376.642376 -408.936444)
				)
				(arc
					(start 376.83694 -408.936444)
					(mid 376.890822 -408.914126)
					(end 376.91314 -408.860244)
				)
				(arc
					(start 376.91314 -408.174444)
					(mid 376.890822 -408.120562)
					(end 376.83694 -408.098244)
				)
				(arc
					(start 376.642376 -408.098244)
					(mid 376.620632 -408.101412)
					(end 376.60072 -408.11069)
				)
				(arc
					(start 376.304556 -408.303476)
					(mid 376.262872 -408.315698)
					(end 376.221244 -408.303222)
				)
				(arc
					(start 375.92762 -408.11069)
					(mid 375.907696 -408.101454)
					(end 375.885964 -408.098244)
				)
				(arc
					(start 375.6914 -408.098244)
					(mid 375.637518 -408.120562)
					(end 375.6152 -408.174444)
				)
			)
		)
	)
	(zone
		(layer "In1.Cu")
		(hatch none 0.5)
		(connect_pads
			(clearance 0)
		)
		(min_thickness 0.25)
		(keepout
			(tracks not_allowed)
			(vias allowed)
			(pads allowed)
			(copperpour not_allowed)
			(footprints allowed)
		)
		(placement
			(enabled no)
			(sheetname "")
		)
		(fill
			(thermal_gap 0.5)
			(thermal_bridge_width 0.5)
			(island_removal_mode 0)
		)
		(polygon
			(pts
				(arc
					(start 311.235598 -408.860244)
					(mid 311.257916 -408.914126)
					(end 311.311798 -408.936444)
				)
				(arc
					(start 311.507378 -408.936444)
					(mid 311.529254 -408.933312)
					(end 311.549288 -408.923998)
				)
				(arc
					(start 311.842912 -408.731466)
					(mid 311.884568 -408.719064)
					(end 311.926224 -408.731466)
				)
				(arc
					(start 312.221118 -408.923998)
					(mid 312.241042 -408.933234)
					(end 312.262774 -408.936444)
				)
				(arc
					(start 312.457338 -408.936444)
					(mid 312.51122 -408.914126)
					(end 312.533538 -408.860244)
				)
				(arc
					(start 312.533538 -408.174444)
					(mid 312.51122 -408.120562)
					(end 312.457338 -408.098244)
				)
				(arc
					(start 312.262774 -408.098244)
					(mid 312.24103 -408.101412)
					(end 312.221118 -408.11069)
				)
				(arc
					(start 311.924954 -408.303476)
					(mid 311.88327 -408.315698)
					(end 311.841642 -408.303222)
				)
				(arc
					(start 311.548018 -408.11069)
					(mid 311.528094 -408.101454)
					(end 311.506362 -408.098244)
				)
				(arc
					(start 311.311798 -408.098244)
					(mid 311.257916 -408.120562)
					(end 311.235598 -408.174444)
				)
			)
		)
	)
	(zone
		(layer "In1.Cu")
		(hatch none 0.5)
		(connect_pads
			(clearance 0)
		)
		(min_thickness 0.25)
		(keepout
			(tracks not_allowed)
			(vias allowed)
			(pads allowed)
			(copperpour not_allowed)
			(footprints allowed)
		)
		(placement
			(enabled no)
			(sheetname "")
		)
		(fill
			(thermal_gap 0.5)
			(thermal_bridge_width 0.5)
			(island_removal_mode 0)
		)
		(polygon
			(pts
				(arc
					(start 392.64844 -402.713952)
					(mid 392.670758 -402.767834)
					(end 392.72464 -402.790152)
				)
				(arc
					(start 392.92022 -402.790152)
					(mid 392.942096 -402.78702)
					(end 392.96213 -402.777706)
				)
				(arc
					(start 393.255754 -402.585174)
					(mid 393.29741 -402.572772)
					(end 393.339066 -402.585174)
				)
				(arc
					(start 393.63396 -402.777706)
					(mid 393.653884 -402.786942)
					(end 393.675616 -402.790152)
				)
				(arc
					(start 393.87018 -402.790152)
					(mid 393.924062 -402.767834)
					(end 393.94638 -402.713952)
				)
				(arc
					(start 393.94638 -402.028152)
					(mid 393.924062 -401.97427)
					(end 393.87018 -401.951952)
				)
				(arc
					(start 393.675616 -401.951952)
					(mid 393.653872 -401.95512)
					(end 393.63396 -401.964398)
				)
				(arc
					(start 393.337796 -402.157184)
					(mid 393.296112 -402.169406)
					(end 393.254484 -402.15693)
				)
				(arc
					(start 392.96086 -401.964398)
					(mid 392.940936 -401.955162)
					(end 392.919204 -401.951952)
				)
				(arc
					(start 392.72464 -401.951952)
					(mid 392.670758 -401.97427)
					(end 392.64844 -402.028152)
				)
			)
		)
	)
	(zone
		(layer "In1.Cu")
		(hatch none 0.5)
		(connect_pads
			(clearance 0)
		)
		(min_thickness 0.25)
		(keepout
			(tracks not_allowed)
			(vias allowed)
			(pads allowed)
			(copperpour not_allowed)
			(footprints allowed)
		)
		(placement
			(enabled no)
			(sheetname "")
		)
		(fill
			(thermal_gap 0.5)
			(thermal_bridge_width 0.5)
			(island_removal_mode 0)
		)
		(polygon
			(pts
				(arc
					(start 340.41207 4.917694)
					(mid 340.389752 4.863812)
					(end 340.33587 4.841494)
				)
				(arc
					(start 339.72373 4.841494)
					(mid 339.669848 4.863812)
					(end 339.64753 4.917694)
				)
				(arc
					(start 339.64753 6.014974)
					(mid 339.669848 6.068856)
					(end 339.72373 6.091174)
				)
				(arc
					(start 340.33587 6.091174)
					(mid 340.389752 6.068856)
					(end 340.41207 6.014974)
				)
			)
		)
	)
	(zone
		(layer "In1.Cu")
		(hatch none 0.5)
		(connect_pads
			(clearance 0)
		)
		(min_thickness 0.25)
		(keepout
			(tracks not_allowed)
			(vias allowed)
			(pads allowed)
			(copperpour not_allowed)
			(footprints allowed)
		)
		(placement
			(enabled no)
			(sheetname "")
		)
		(fill
			(thermal_gap 0.5)
			(thermal_bridge_width 0.5)
			(island_removal_mode 0)
		)
		(polygon
			(pts
				(arc
					(start 329.615038 -408.860244)
					(mid 329.637356 -408.914126)
					(end 329.691238 -408.936444)
				)
				(arc
					(start 329.886818 -408.936444)
					(mid 329.908694 -408.933312)
					(end 329.928728 -408.923998)
				)
				(arc
					(start 330.222352 -408.731466)
					(mid 330.264008 -408.719064)
					(end 330.305664 -408.731466)
				)
				(arc
					(start 330.600558 -408.923998)
					(mid 330.620482 -408.933234)
					(end 330.642214 -408.936444)
				)
				(arc
					(start 330.836778 -408.936444)
					(mid 330.89066 -408.914126)
					(end 330.912978 -408.860244)
				)
				(arc
					(start 330.912978 -408.174444)
					(mid 330.89066 -408.120562)
					(end 330.836778 -408.098244)
				)
				(arc
					(start 330.642214 -408.098244)
					(mid 330.62047 -408.101412)
					(end 330.600558 -408.11069)
				)
				(arc
					(start 330.304394 -408.303476)
					(mid 330.26271 -408.315698)
					(end 330.221082 -408.303222)
				)
				(arc
					(start 329.927458 -408.11069)
					(mid 329.907534 -408.101454)
					(end 329.885802 -408.098244)
				)
				(arc
					(start 329.691238 -408.098244)
					(mid 329.637356 -408.120562)
					(end 329.615038 -408.174444)
				)
			)
		)
	)
	(zone
		(layer "In1.Cu")
		(hatch none 0.5)
		(connect_pads
			(clearance 0)
		)
		(min_thickness 0.25)
		(keepout
			(tracks not_allowed)
			(vias allowed)
			(pads allowed)
			(copperpour not_allowed)
			(footprints allowed)
		)
		(placement
			(enabled no)
			(sheetname "")
		)
		(fill
			(thermal_gap 0.5)
			(thermal_bridge_width 0.5)
			(island_removal_mode 0)
		)
		(polygon
			(pts
				(arc
					(start 157.266894 -42.91711)
					(mid 156.504386 -42.91711)
					(end 157.266894 -42.91711)
				)
			)
		)
	)
	(zone
		(layer "In1.Cu")
		(hatch none 0.5)
		(connect_pads
			(clearance 0)
		)
		(min_thickness 0.25)
		(keepout
			(tracks not_allowed)
			(vias allowed)
			(pads allowed)
			(copperpour not_allowed)
			(footprints allowed)
		)
		(placement
			(enabled no)
			(sheetname "")
		)
		(fill
			(thermal_gap 0.5)
			(thermal_bridge_width 0.5)
			(island_removal_mode 0)
		)
		(polygon
			(pts
				(arc
					(start 403.794214 -17.955514)
					(mid 403.816532 -18.009396)
					(end 403.870414 -18.031714)
				)
				(arc
					(start 404.065994 -18.031714)
					(mid 404.08787 -18.028582)
					(end 404.107904 -18.019268)
				)
				(arc
					(start 404.401528 -17.826736)
					(mid 404.443184 -17.814334)
					(end 404.48484 -17.826736)
				)
				(arc
					(start 404.779734 -18.019268)
					(mid 404.799658 -18.028504)
					(end 404.82139 -18.031714)
				)
				(arc
					(start 405.015954 -18.031714)
					(mid 405.069836 -18.009396)
					(end 405.092154 -17.955514)
				)
				(arc
					(start 405.092154 -17.269714)
					(mid 405.069836 -17.215832)
					(end 405.015954 -17.193514)
				)
				(arc
					(start 404.82139 -17.193514)
					(mid 404.799646 -17.196682)
					(end 404.779734 -17.20596)
				)
				(arc
					(start 404.48357 -17.398746)
					(mid 404.441886 -17.410968)
					(end 404.400258 -17.398492)
				)
				(arc
					(start 404.106634 -17.20596)
					(mid 404.08671 -17.196724)
					(end 404.064978 -17.193514)
				)
				(arc
					(start 403.870414 -17.193514)
					(mid 403.816532 -17.215832)
					(end 403.794214 -17.269714)
				)
			)
		)
	)
	(zone
		(layer "In1.Cu")
		(hatch none 0.5)
		(connect_pads
			(clearance 0)
		)
		(min_thickness 0.25)
		(keepout
			(tracks not_allowed)
			(vias allowed)
			(pads allowed)
			(copperpour not_allowed)
			(footprints allowed)
		)
		(placement
			(enabled no)
			(sheetname "")
		)
		(fill
			(thermal_gap 0.5)
			(thermal_bridge_width 0.5)
			(island_removal_mode 0)
		)
		(polygon
			(pts
				(arc
					(start 165.886384 -402.713952)
					(mid 165.908702 -402.767834)
					(end 165.962584 -402.790152)
				)
				(arc
					(start 166.158164 -402.790152)
					(mid 166.18004 -402.78702)
					(end 166.200074 -402.777706)
				)
				(arc
					(start 166.493698 -402.585174)
					(mid 166.535354 -402.572772)
					(end 166.57701 -402.585174)
				)
				(arc
					(start 166.871904 -402.777706)
					(mid 166.891828 -402.786942)
					(end 166.91356 -402.790152)
				)
				(arc
					(start 167.108124 -402.790152)
					(mid 167.162006 -402.767834)
					(end 167.184324 -402.713952)
				)
				(arc
					(start 167.184324 -402.028152)
					(mid 167.162006 -401.97427)
					(end 167.108124 -401.951952)
				)
				(arc
					(start 166.91356 -401.951952)
					(mid 166.891816 -401.95512)
					(end 166.871904 -401.964398)
				)
				(arc
					(start 166.57574 -402.157184)
					(mid 166.534056 -402.169406)
					(end 166.492428 -402.15693)
				)
				(arc
					(start 166.198804 -401.964398)
					(mid 166.17888 -401.955162)
					(end 166.157148 -401.951952)
				)
				(arc
					(start 165.962584 -401.951952)
					(mid 165.908702 -401.97427)
					(end 165.886384 -402.028152)
				)
			)
		)
	)
	(zone
		(layer "In1.Cu")
		(hatch none 0.5)
		(connect_pads
			(clearance 0)
		)
		(min_thickness 0.25)
		(keepout
			(tracks not_allowed)
			(vias allowed)
			(pads allowed)
			(copperpour not_allowed)
			(footprints allowed)
		)
		(placement
			(enabled no)
			(sheetname "")
		)
		(fill
			(thermal_gap 0.5)
			(thermal_bridge_width 0.5)
			(island_removal_mode 0)
		)
		(polygon
			(pts
				(arc
					(start 164.169344 -408.860244)
					(mid 164.191662 -408.914126)
					(end 164.245544 -408.936444)
				)
				(arc
					(start 164.441124 -408.936444)
					(mid 164.463 -408.933312)
					(end 164.483034 -408.923998)
				)
				(arc
					(start 164.776658 -408.731466)
					(mid 164.818314 -408.719064)
					(end 164.85997 -408.731466)
				)
				(arc
					(start 165.154864 -408.923998)
					(mid 165.174788 -408.933234)
					(end 165.19652 -408.936444)
				)
				(arc
					(start 165.391084 -408.936444)
					(mid 165.444966 -408.914126)
					(end 165.467284 -408.860244)
				)
				(arc
					(start 165.467284 -408.174444)
					(mid 165.444966 -408.120562)
					(end 165.391084 -408.098244)
				)
				(arc
					(start 165.19652 -408.098244)
					(mid 165.174776 -408.101412)
					(end 165.154864 -408.11069)
				)
				(arc
					(start 164.8587 -408.303476)
					(mid 164.817016 -408.315698)
					(end 164.775388 -408.303222)
				)
				(arc
					(start 164.481764 -408.11069)
					(mid 164.46184 -408.101454)
					(end 164.440108 -408.098244)
				)
				(arc
					(start 164.245544 -408.098244)
					(mid 164.191662 -408.120562)
					(end 164.169344 -408.174444)
				)
			)
		)
	)
	(zone
		(layer "In1.Cu")
		(hatch none 0.5)
		(connect_pads
			(clearance 0)
		)
		(min_thickness 0.25)
		(keepout
			(tracks not_allowed)
			(vias allowed)
			(pads allowed)
			(copperpour not_allowed)
			(footprints allowed)
		)
		(placement
			(enabled no)
			(sheetname "")
		)
		(fill
			(thermal_gap 0.5)
			(thermal_bridge_width 0.5)
			(island_removal_mode 0)
		)
		(polygon
			(pts
				(arc
					(start 29.52877 -11.91768)
					(mid 29.551088 -11.971562)
					(end 29.60497 -11.99388)
				)
				(arc
					(start 30.8864 -11.99388)
					(mid 30.940282 -11.971562)
					(end 30.9626 -11.91768)
				)
				(arc
					(start 30.9626 -10.49528)
					(mid 30.940282 -10.441398)
					(end 30.8864 -10.41908)
				)
				(arc
					(start 29.60497 -10.41908)
					(mid 29.551088 -10.441398)
					(end 29.52877 -10.49528)
				)
			)
		)
	)
	(zone
		(layer "In1.Cu")
		(hatch none 0.5)
		(connect_pads
			(clearance 0)
		)
		(min_thickness 0.25)
		(keepout
			(tracks not_allowed)
			(vias allowed)
			(pads allowed)
			(copperpour not_allowed)
			(footprints allowed)
		)
		(placement
			(enabled no)
			(sheetname "")
		)
		(fill
			(thermal_gap 0.5)
			(thermal_bridge_width 0.5)
			(island_removal_mode 0)
		)
		(polygon
			(pts
				(arc
					(start 403.18436 -408.860244)
					(mid 403.206678 -408.914126)
					(end 403.26056 -408.936444)
				)
				(arc
					(start 403.45614 -408.936444)
					(mid 403.478016 -408.933312)
					(end 403.49805 -408.923998)
				)
				(arc
					(start 403.791674 -408.731466)
					(mid 403.83333 -408.719064)
					(end 403.874986 -408.731466)
				)
				(arc
					(start 404.16988 -408.923998)
					(mid 404.189804 -408.933234)
					(end 404.211536 -408.936444)
				)
				(arc
					(start 404.4061 -408.936444)
					(mid 404.459982 -408.914126)
					(end 404.4823 -408.860244)
				)
				(arc
					(start 404.4823 -408.174444)
					(mid 404.459982 -408.120562)
					(end 404.4061 -408.098244)
				)
				(arc
					(start 404.211536 -408.098244)
					(mid 404.189792 -408.101412)
					(end 404.16988 -408.11069)
				)
				(arc
					(start 403.873716 -408.303476)
					(mid 403.832032 -408.315698)
					(end 403.790404 -408.303222)
				)
				(arc
					(start 403.49678 -408.11069)
					(mid 403.476856 -408.101454)
					(end 403.455124 -408.098244)
				)
				(arc
					(start 403.26056 -408.098244)
					(mid 403.206678 -408.120562)
					(end 403.18436 -408.174444)
				)
			)
		)
	)
	(zone
		(layer "In1.Cu")
		(hatch none 0.5)
		(connect_pads
			(clearance 0)
		)
		(min_thickness 0.25)
		(keepout
			(tracks not_allowed)
			(vias allowed)
			(pads allowed)
			(copperpour not_allowed)
			(footprints allowed)
		)
		(placement
			(enabled no)
			(sheetname "")
		)
		(fill
			(thermal_gap 0.5)
			(thermal_bridge_width 0.5)
			(island_removal_mode 0)
		)
		(polygon
			(pts
				(arc
					(start 12.612624 -15.942818)
					(mid 12.558742 -15.9205)
					(end 12.536424 -15.866618)
				)
				(arc
					(start 12.536424 -14.764004)
					(mid 12.558742 -14.710122)
					(end 12.612624 -14.687804)
				)
				(arc
					(start 12.945872 -14.687804)
					(mid 12.999754 -14.710122)
					(end 13.022072 -14.764004)
				)
				(arc
					(start 13.022072 -15.866618)
					(mid 12.999754 -15.9205)
					(end 12.945872 -15.942818)
				)
			)
		)
	)
	(zone
		(layer "In1.Cu")
		(hatch none 0.5)
		(connect_pads
			(clearance 0)
		)
		(min_thickness 0.25)
		(keepout
			(tracks not_allowed)
			(vias allowed)
			(pads allowed)
			(copperpour not_allowed)
			(footprints allowed)
		)
		(placement
			(enabled no)
			(sheetname "")
		)
		(fill
			(thermal_gap 0.5)
			(thermal_bridge_width 0.5)
			(island_removal_mode 0)
		)
		(polygon
			(pts
				(arc
					(start 27.366976 -7.672324)
					(mid 27.344658 -7.618442)
					(end 27.290776 -7.596124)
				)
				(arc
					(start 26.009346 -7.596124)
					(mid 25.955464 -7.618442)
					(end 25.933146 -7.672324)
				)
				(arc
					(start 25.933146 -9.094724)
					(mid 25.955464 -9.148606)
					(end 26.009346 -9.170924)
				)
				(arc
					(start 27.290776 -9.170924)
					(mid 27.344658 -9.148606)
					(end 27.366976 -9.094724)
				)
			)
		)
	)
	(zone
		(layers "In1.Cu" "In2.Cu")
		(hatch none 0.5)
		(connect_pads
			(clearance 0)
		)
		(min_thickness 0.25)
		(keepout
			(tracks not_allowed)
			(vias allowed)
			(pads allowed)
			(copperpour not_allowed)
			(footprints allowed)
		)
		(placement
			(enabled no)
			(sheetname "")
		)
		(fill yes
			(thermal_gap 0.5)
			(thermal_bridge_width 0.5)
			(island_removal_mode 0)
		)
		(polygon
			(pts
				(arc
					(start 262.873998 -217.071448)
					(mid 262.888877 -217.107369)
					(end 262.924798 -217.122248)
				)
				(arc
					(start 264.324338 -217.122248)
					(mid 264.360259 -217.107369)
					(end 264.375138 -217.071448)
				)
				(arc
					(start 264.375138 -216.662508)
					(mid 264.360259 -216.626587)
					(end 264.324338 -216.611708)
				)
				(arc
					(start 262.924798 -216.611708)
					(mid 262.888877 -216.626587)
					(end 262.873998 -216.662508)
				)
			)
		)
	)
	(zone
		(layers "In1.Cu" "In2.Cu")
		(hatch none 0.5)
		(connect_pads
			(clearance 0)
		)
		(min_thickness 0.25)
		(keepout
			(tracks not_allowed)
			(vias allowed)
			(pads allowed)
			(copperpour not_allowed)
			(footprints allowed)
		)
		(placement
			(enabled no)
			(sheetname "")
		)
		(fill yes
			(thermal_gap 0.5)
			(thermal_bridge_width 0.5)
			(island_removal_mode 0)
		)
		(polygon
			(pts
				(arc
					(start 300.592998 -310.571388)
					(mid 300.607877 -310.607309)
					(end 300.643798 -310.622188)
				)
				(arc
					(start 302.043338 -310.622188)
					(mid 302.079259 -310.607309)
					(end 302.094138 -310.571388)
				)
				(arc
					(start 302.094138 -310.162448)
					(mid 302.079259 -310.126527)
					(end 302.043338 -310.111648)
				)
				(arc
					(start 300.643798 -310.111648)
					(mid 300.607877 -310.126527)
					(end 300.592998 -310.162448)
				)
			)
		)
	)
	(zone
		(layers "In1.Cu" "In2.Cu")
		(hatch none 0.5)
		(connect_pads
			(clearance 0)
		)
		(min_thickness 0.25)
		(keepout
			(tracks not_allowed)
			(vias allowed)
			(pads allowed)
			(copperpour not_allowed)
			(footprints allowed)
		)
		(placement
			(enabled no)
			(sheetname "")
		)
		(fill yes
			(thermal_gap 0.5)
			(thermal_bridge_width 0.5)
			(island_removal_mode 0)
		)
		(polygon
			(pts
				(arc
					(start 60.19673 -271.47139)
					(mid 60.211609 -271.507311)
					(end 60.24753 -271.52219)
				)
				(arc
					(start 61.64707 -271.52219)
					(mid 61.682991 -271.507311)
					(end 61.69787 -271.47139)
				)
				(arc
					(start 61.69787 -271.06245)
					(mid 61.682991 -271.026529)
					(end 61.64707 -271.01165)
				)
				(arc
					(start 60.24753 -271.01165)
					(mid 60.211609 -271.026529)
					(end 60.19673 -271.06245)
				)
			)
		)
	)
	(zone
		(layers "In1.Cu" "In2.Cu")
		(hatch none 0.5)
		(connect_pads
			(clearance 0)
		)
		(min_thickness 0.25)
		(keepout
			(tracks not_allowed)
			(vias allowed)
			(pads allowed)
			(copperpour not_allowed)
			(footprints allowed)
		)
		(placement
			(enabled no)
			(sheetname "")
		)
		(fill yes
			(thermal_gap 0.5)
			(thermal_bridge_width 0.5)
			(island_removal_mode 0)
		)
		(polygon
			(pts
				(arc
					(start 270.417798 -228.971348)
					(mid 270.432677 -229.007269)
					(end 270.468598 -229.022148)
				)
				(arc
					(start 271.868138 -229.022148)
					(mid 271.904059 -229.007269)
					(end 271.918938 -228.971348)
				)
				(arc
					(start 271.918938 -228.562408)
					(mid 271.904059 -228.526487)
					(end 271.868138 -228.511608)
				)
				(arc
					(start 270.468598 -228.511608)
					(mid 270.432677 -228.526487)
					(end 270.417798 -228.562408)
				)
			)
		)
	)
	(zone
		(layers "In1.Cu" "In2.Cu")
		(hatch none 0.5)
		(connect_pads
			(clearance 0)
		)
		(min_thickness 0.25)
		(keepout
			(tracks not_allowed)
			(vias allowed)
			(pads allowed)
			(copperpour not_allowed)
			(footprints allowed)
		)
		(placement
			(enabled no)
			(sheetname "")
		)
		(fill yes
			(thermal_gap 0.5)
			(thermal_bridge_width 0.5)
			(island_removal_mode 0)
		)
		(polygon
			(pts
				(arc
					(start 158.06293 -290.171378)
					(mid 158.077809 -290.207299)
					(end 158.11373 -290.222178)
				)
				(arc
					(start 159.51327 -290.222178)
					(mid 159.549191 -290.207299)
					(end 159.56407 -290.171378)
				)
				(arc
					(start 159.56407 -289.762438)
					(mid 159.549191 -289.726517)
					(end 159.51327 -289.711638)
				)
				(arc
					(start 158.11373 -289.711638)
					(mid 158.077809 -289.726517)
					(end 158.06293 -289.762438)
				)
			)
		)
	)
	(zone
		(layers "In1.Cu" "In2.Cu")
		(hatch none 0.5)
		(connect_pads
			(clearance 0)
		)
		(min_thickness 0.25)
		(keepout
			(tracks not_allowed)
			(vias allowed)
			(pads allowed)
			(copperpour not_allowed)
			(footprints allowed)
		)
		(placement
			(enabled no)
			(sheetname "")
		)
		(fill yes
			(thermal_gap 0.5)
			(thermal_bridge_width 0.5)
			(island_removal_mode 0)
		)
		(polygon
			(pts
				(arc
					(start 413.546798 -294.421306)
					(mid 413.561677 -294.457227)
					(end 413.597598 -294.472106)
				)
				(arc
					(start 414.997138 -294.472106)
					(mid 415.033059 -294.457227)
					(end 415.047938 -294.421306)
				)
				(arc
					(start 415.047938 -294.012366)
					(mid 415.033059 -293.976445)
					(end 414.997138 -293.961566)
				)
				(arc
					(start 413.597598 -293.961566)
					(mid 413.561677 -293.976445)
					(end 413.546798 -294.012366)
				)
			)
		)
	)
	(zone
		(layers "In1.Cu" "In2.Cu")
		(hatch none 0.5)
		(connect_pads
			(clearance 0)
		)
		(min_thickness 0.25)
		(keepout
			(tracks not_allowed)
			(vias allowed)
			(pads allowed)
			(copperpour not_allowed)
			(footprints allowed)
		)
		(placement
			(enabled no)
			(sheetname "")
		)
		(fill yes
			(thermal_gap 0.5)
			(thermal_bridge_width 0.5)
			(island_removal_mode 0)
		)
		(polygon
			(pts
				(arc
					(start 421.090598 -285.071312)
					(mid 421.105477 -285.107233)
					(end 421.141398 -285.122112)
				)
				(arc
					(start 422.540938 -285.122112)
					(mid 422.576859 -285.107233)
					(end 422.591738 -285.071312)
				)
				(arc
					(start 422.591738 -284.662372)
					(mid 422.576859 -284.626451)
					(end 422.540938 -284.611572)
				)
				(arc
					(start 421.141398 -284.611572)
					(mid 421.105477 -284.626451)
					(end 421.090598 -284.662372)
				)
			)
		)
	)
	(zone
		(layers "In1.Cu" "In2.Cu")
		(hatch none 0.5)
		(connect_pads
			(clearance 0)
		)
		(min_thickness 0.25)
		(keepout
			(tracks not_allowed)
			(vias allowed)
			(pads allowed)
			(copperpour not_allowed)
			(footprints allowed)
		)
		(placement
			(enabled no)
			(sheetname "")
		)
		(fill yes
			(thermal_gap 0.5)
			(thermal_bridge_width 0.5)
			(island_removal_mode 0)
		)
		(polygon
			(pts
				(arc
					(start 52.65293 -294.421306)
					(mid 52.667809 -294.457227)
					(end 52.70373 -294.472106)
				)
				(arc
					(start 54.10327 -294.472106)
					(mid 54.139191 -294.457227)
					(end 54.15407 -294.421306)
				)
				(arc
					(start 54.15407 -294.012366)
					(mid 54.139191 -293.976445)
					(end 54.10327 -293.961566)
				)
				(arc
					(start 52.70373 -293.961566)
					(mid 52.667809 -293.976445)
					(end 52.65293 -294.012366)
				)
			)
		)
	)
	(zone
		(layers "In1.Cu" "In2.Cu")
		(hatch none 0.5)
		(connect_pads
			(clearance 0)
		)
		(min_thickness 0.25)
		(keepout
			(tracks not_allowed)
			(vias allowed)
			(pads allowed)
			(copperpour not_allowed)
			(footprints allowed)
		)
		(placement
			(enabled no)
			(sheetname "")
		)
		(fill yes
			(thermal_gap 0.5)
			(thermal_bridge_width 0.5)
			(island_removal_mode 0)
		)
		(polygon
			(pts
				(arc
					(start 297.149266 -205.171548)
					(mid 297.164145 -205.207469)
					(end 297.200066 -205.222348)
				)
				(arc
					(start 298.599606 -205.222348)
					(mid 298.635527 -205.207469)
					(end 298.650406 -205.171548)
				)
				(arc
					(start 298.650406 -204.762608)
					(mid 298.635527 -204.726687)
					(end 298.599606 -204.711808)
				)
				(arc
					(start 297.200066 -204.711808)
					(mid 297.164145 -204.726687)
					(end 297.149266 -204.762608)
				)
			)
		)
	)
	(zone
		(layers "In1.Cu" "In2.Cu")
		(hatch none 0.5)
		(connect_pads
			(clearance 0)
		)
		(min_thickness 0.25)
		(keepout
			(tracks not_allowed)
			(vias allowed)
			(pads allowed)
			(copperpour not_allowed)
			(footprints allowed)
		)
		(placement
			(enabled no)
			(sheetname "")
		)
		(fill yes
			(thermal_gap 0.5)
			(thermal_bridge_width 0.5)
			(island_removal_mode 0)
		)
		(polygon
			(pts
				(arc
					(start 255.330198 -204.32141)
					(mid 255.345077 -204.357331)
					(end 255.380998 -204.37221)
				)
				(arc
					(start 256.780538 -204.37221)
					(mid 256.816459 -204.357331)
					(end 256.831338 -204.32141)
				)
				(arc
					(start 256.831338 -203.91247)
					(mid 256.816459 -203.876549)
					(end 256.780538 -203.86167)
				)
				(arc
					(start 255.380998 -203.86167)
					(mid 255.345077 -203.876549)
					(end 255.330198 -203.91247)
				)
			)
		)
	)
	(zone
		(layers "In1.Cu" "In2.Cu")
		(hatch none 0.5)
		(connect_pads
			(clearance 0)
		)
		(min_thickness 0.25)
		(keepout
			(tracks not_allowed)
			(vias allowed)
			(pads allowed)
			(copperpour not_allowed)
			(footprints allowed)
		)
		(placement
			(enabled no)
			(sheetname "")
		)
		(fill yes
			(thermal_gap 0.5)
			(thermal_bridge_width 0.5)
			(island_removal_mode 0)
		)
		(polygon
			(pts
				(arc
					(start 417.646866 -217.921332)
					(mid 417.661745 -217.957253)
					(end 417.697666 -217.972132)
				)
				(arc
					(start 419.097206 -217.972132)
					(mid 419.133127 -217.957253)
					(end 419.148006 -217.921332)
				)
				(arc
					(start 419.148006 -217.512392)
					(mid 419.133127 -217.476471)
					(end 419.097206 -217.461592)
				)
				(arc
					(start 417.697666 -217.461592)
					(mid 417.661745 -217.476471)
					(end 417.646866 -217.512392)
				)
			)
		)
	)
	(zone
		(layers "In1.Cu" "In2.Cu")
		(hatch none 0.5)
		(connect_pads
			(clearance 0)
		)
		(min_thickness 0.25)
		(keepout
			(tracks not_allowed)
			(vias allowed)
			(pads allowed)
			(copperpour not_allowed)
			(footprints allowed)
		)
		(placement
			(enabled no)
			(sheetname "")
		)
		(fill yes
			(thermal_gap 0.5)
			(thermal_bridge_width 0.5)
			(island_removal_mode 0)
		)
		(polygon
			(pts
				(arc
					(start 22.47773 -282.521406)
					(mid 22.492609 -282.557327)
					(end 22.52853 -282.572206)
				)
				(arc
					(start 23.92807 -282.572206)
					(mid 23.963991 -282.557327)
					(end 23.97887 -282.521406)
				)
				(arc
					(start 23.97887 -282.112466)
					(mid 23.963991 -282.076545)
					(end 23.92807 -282.061666)
				)
				(arc
					(start 22.52853 -282.061666)
					(mid 22.492609 -282.076545)
					(end 22.47773 -282.112466)
				)
			)
		)
	)
	(zone
		(layers "In1.Cu" "In2.Cu")
		(hatch none 0.5)
		(connect_pads
			(clearance 0)
		)
		(min_thickness 0.25)
		(keepout
			(tracks not_allowed)
			(vias allowed)
			(pads allowed)
			(copperpour not_allowed)
			(footprints allowed)
		)
		(placement
			(enabled no)
			(sheetname "")
		)
		(fill yes
			(thermal_gap 0.5)
			(thermal_bridge_width 0.5)
			(island_removal_mode 0)
		)
		(polygon
			(pts
				(arc
					(start 259.430266 -283.371544)
					(mid 259.445145 -283.407465)
					(end 259.481066 -283.422344)
				)
				(arc
					(start 260.880606 -283.422344)
					(mid 260.916527 -283.407465)
					(end 260.931406 -283.371544)
				)
				(arc
					(start 260.931406 -282.962604)
					(mid 260.916527 -282.926683)
					(end 260.880606 -282.911804)
				)
				(arc
					(start 259.481066 -282.911804)
					(mid 259.445145 -282.926683)
					(end 259.430266 -282.962604)
				)
			)
		)
	)
	(zone
		(layers "In1.Cu" "In2.Cu")
		(hatch none 0.5)
		(connect_pads
			(clearance 0)
		)
		(min_thickness 0.25)
		(keepout
			(tracks not_allowed)
			(vias allowed)
			(pads allowed)
			(copperpour not_allowed)
			(footprints allowed)
		)
		(placement
			(enabled no)
			(sheetname "")
		)
		(fill yes
			(thermal_gap 0.5)
			(thermal_bridge_width 0.5)
			(island_removal_mode 0)
		)
		(polygon
			(pts
				(arc
					(start 210.86953 -299.521372)
					(mid 210.884409 -299.557293)
					(end 210.92033 -299.572172)
				)
				(arc
					(start 212.31987 -299.572172)
					(mid 212.355791 -299.557293)
					(end 212.37067 -299.521372)
				)
				(arc
					(start 212.37067 -299.112432)
					(mid 212.355791 -299.076511)
					(end 212.31987 -299.061632)
				)
				(arc
					(start 210.92033 -299.061632)
					(mid 210.884409 -299.076511)
					(end 210.86953 -299.112432)
				)
			)
		)
	)
	(zone
		(layers "In1.Cu" "In2.Cu")
		(hatch none 0.5)
		(connect_pads
			(clearance 0)
		)
		(min_thickness 0.25)
		(keepout
			(tracks not_allowed)
			(vias allowed)
			(pads allowed)
			(copperpour not_allowed)
			(footprints allowed)
		)
		(placement
			(enabled no)
			(sheetname "")
		)
		(fill yes
			(thermal_gap 0.5)
			(thermal_bridge_width 0.5)
			(island_removal_mode 0)
		)
		(polygon
			(pts
				(arc
					(start 64.296798 -259.57149)
					(mid 64.311677 -259.607411)
					(end 64.347598 -259.62229)
				)
				(arc
					(start 65.747138 -259.62229)
					(mid 65.783059 -259.607411)
					(end 65.797938 -259.57149)
				)
				(arc
					(start 65.797938 -259.16255)
					(mid 65.783059 -259.126629)
					(end 65.747138 -259.11175)
				)
				(arc
					(start 64.347598 -259.11175)
					(mid 64.311677 -259.126629)
					(end 64.296798 -259.16255)
				)
			)
		)
	)
	(zone
		(layers "In1.Cu" "In2.Cu")
		(hatch none 0.5)
		(connect_pads
			(clearance 0)
		)
		(min_thickness 0.25)
		(keepout
			(tracks not_allowed)
			(vias allowed)
			(pads allowed)
			(copperpour not_allowed)
			(footprints allowed)
		)
		(placement
			(enabled no)
			(sheetname "")
		)
		(fill yes
			(thermal_gap 0.5)
			(thermal_bridge_width 0.5)
			(island_removal_mode 0)
		)
		(polygon
			(pts
				(arc
					(start 455.365866 -239.17148)
					(mid 455.380745 -239.207401)
					(end 455.416666 -239.22228)
				)
				(arc
					(start 456.816206 -239.22228)
					(mid 456.852127 -239.207401)
					(end 456.867006 -239.17148)
				)
				(arc
					(start 456.867006 -238.76254)
					(mid 456.852127 -238.726619)
					(end 456.816206 -238.71174)
				)
				(arc
					(start 455.416666 -238.71174)
					(mid 455.380745 -238.726619)
					(end 455.365866 -238.76254)
				)
			)
		)
	)
	(zone
		(layers "In1.Cu" "In2.Cu")
		(hatch none 0.5)
		(connect_pads
			(clearance 0)
		)
		(min_thickness 0.25)
		(keepout
			(tracks not_allowed)
			(vias allowed)
			(pads allowed)
			(copperpour not_allowed)
			(footprints allowed)
		)
		(placement
			(enabled no)
			(sheetname "")
		)
		(fill yes
			(thermal_gap 0.5)
			(thermal_bridge_width 0.5)
			(island_removal_mode 0)
		)
		(polygon
			(pts
				(arc
					(start 41.665398 -200.071482)
					(mid 41.680277 -200.107403)
					(end 41.716198 -200.122282)
				)
				(arc
					(start 43.115738 -200.122282)
					(mid 43.151659 -200.107403)
					(end 43.166538 -200.071482)
				)
				(arc
					(start 43.166538 -199.662542)
					(mid 43.151659 -199.626621)
					(end 43.115738 -199.611742)
				)
				(arc
					(start 41.716198 -199.611742)
					(mid 41.680277 -199.626621)
					(end 41.665398 -199.662542)
				)
			)
		)
	)
	(zone
		(layers "In1.Cu" "In2.Cu")
		(hatch none 0.5)
		(connect_pads
			(clearance 0)
		)
		(min_thickness 0.25)
		(keepout
			(tracks not_allowed)
			(vias allowed)
			(pads allowed)
			(copperpour not_allowed)
			(footprints allowed)
		)
		(placement
			(enabled no)
			(sheetname "")
		)
		(fill yes
			(thermal_gap 0.5)
			(thermal_bridge_width 0.5)
			(island_removal_mode 0)
		)
		(polygon
			(pts
				(arc
					(start 52.65293 -241.721386)
					(mid 52.667809 -241.757307)
					(end 52.70373 -241.772186)
				)
				(arc
					(start 54.10327 -241.772186)
					(mid 54.139191 -241.757307)
					(end 54.15407 -241.721386)
				)
				(arc
					(start 54.15407 -241.312446)
					(mid 54.139191 -241.276525)
					(end 54.10327 -241.261646)
				)
				(arc
					(start 52.70373 -241.261646)
					(mid 52.667809 -241.276525)
					(end 52.65293 -241.312446)
				)
			)
		)
	)
	(zone
		(layers "In1.Cu" "In2.Cu")
		(hatch none 0.5)
		(connect_pads
			(clearance 0)
		)
		(min_thickness 0.25)
		(keepout
			(tracks not_allowed)
			(vias allowed)
			(pads allowed)
			(copperpour not_allowed)
			(footprints allowed)
		)
		(placement
			(enabled no)
			(sheetname "")
		)
		(fill yes
			(thermal_gap 0.5)
			(thermal_bridge_width 0.5)
			(island_removal_mode 0)
		)
		(polygon
			(pts
				(arc
					(start 300.592998 -232.371392)
					(mid 300.607877 -232.407313)
					(end 300.643798 -232.422192)
				)
				(arc
					(start 302.043338 -232.422192)
					(mid 302.079259 -232.407313)
					(end 302.094138 -232.371392)
				)
				(arc
					(start 302.094138 -231.962452)
					(mid 302.079259 -231.926531)
					(end 302.043338 -231.911652)
				)
				(arc
					(start 300.643798 -231.911652)
					(mid 300.607877 -231.926531)
					(end 300.592998 -231.962452)
				)
			)
		)
	)
	(zone
		(layers "In1.Cu" "In2.Cu")
		(hatch none 0.5)
		(connect_pads
			(clearance 0)
		)
		(min_thickness 0.25)
		(keepout
			(tracks not_allowed)
			(vias allowed)
			(pads allowed)
			(copperpour not_allowed)
			(footprints allowed)
		)
		(placement
			(enabled no)
			(sheetname "")
		)
		(fill yes
			(thermal_gap 0.5)
			(thermal_bridge_width 0.5)
			(island_removal_mode 0)
		)
		(polygon
			(pts
				(arc
					(start 447.822066 -308.021482)
					(mid 447.836945 -308.057403)
					(end 447.872866 -308.072282)
				)
				(arc
					(start 449.272406 -308.072282)
					(mid 449.308327 -308.057403)
					(end 449.323206 -308.021482)
				)
				(arc
					(start 449.323206 -307.612542)
					(mid 449.308327 -307.576621)
					(end 449.272406 -307.561742)
				)
				(arc
					(start 447.872866 -307.561742)
					(mid 447.836945 -307.576621)
					(end 447.822066 -307.612542)
				)
			)
		)
	)
	(zone
		(layers "In1.Cu" "In2.Cu")
		(hatch none 0.5)
		(connect_pads
			(clearance 0)
		)
		(min_thickness 0.25)
		(keepout
			(tracks not_allowed)
			(vias allowed)
			(pads allowed)
			(copperpour not_allowed)
			(footprints allowed)
		)
		(placement
			(enabled no)
			(sheetname "")
		)
		(fill yes
			(thermal_gap 0.5)
			(thermal_bridge_width 0.5)
			(island_removal_mode 0)
		)
		(polygon
			(pts
				(arc
					(start 425.190666 -216.22131)
					(mid 425.205545 -216.257231)
					(end 425.241466 -216.27211)
				)
				(arc
					(start 426.641006 -216.27211)
					(mid 426.676927 -216.257231)
					(end 426.691806 -216.22131)
				)
				(arc
					(start 426.691806 -215.81237)
					(mid 426.676927 -215.776449)
					(end 426.641006 -215.76157)
				)
				(arc
					(start 425.241466 -215.76157)
					(mid 425.205545 -215.776449)
					(end 425.190666 -215.81237)
				)
			)
		)
	)
	(zone
		(layers "In1.Cu" "In2.Cu")
		(hatch none 0.5)
		(connect_pads
			(clearance 0)
		)
		(min_thickness 0.25)
		(keepout
			(tracks not_allowed)
			(vias allowed)
			(pads allowed)
			(copperpour not_allowed)
			(footprints allowed)
		)
		(placement
			(enabled no)
			(sheetname "")
		)
		(fill yes
			(thermal_gap 0.5)
			(thermal_bridge_width 0.5)
			(island_removal_mode 0)
		)
		(polygon
			(pts
				(arc
					(start 30.02153 -243.421408)
					(mid 30.036409 -243.457329)
					(end 30.07233 -243.472208)
				)
				(arc
					(start 31.47187 -243.472208)
					(mid 31.507791 -243.457329)
					(end 31.52267 -243.421408)
				)
				(arc
					(start 31.52267 -243.012468)
					(mid 31.507791 -242.976547)
					(end 31.47187 -242.961668)
				)
				(arc
					(start 30.07233 -242.961668)
					(mid 30.036409 -242.976547)
					(end 30.02153 -243.012468)
				)
			)
		)
	)
	(zone
		(layers "In1.Cu" "In2.Cu")
		(hatch none 0.5)
		(connect_pads
			(clearance 0)
		)
		(min_thickness 0.25)
		(keepout
			(tracks not_allowed)
			(vias allowed)
			(pads allowed)
			(copperpour not_allowed)
			(footprints allowed)
		)
		(placement
			(enabled no)
			(sheetname "")
		)
		(fill yes
			(thermal_gap 0.5)
			(thermal_bridge_width 0.5)
			(island_removal_mode 0)
		)
		(polygon
			(pts
				(arc
					(start 11.490198 -315.671454)
					(mid 11.505077 -315.707375)
					(end 11.540998 -315.722254)
				)
				(arc
					(start 12.940538 -315.722254)
					(mid 12.976459 -315.707375)
					(end 12.991338 -315.671454)
				)
				(arc
					(start 12.991338 -315.262514)
					(mid 12.976459 -315.226593)
					(end 12.940538 -315.211714)
				)
				(arc
					(start 11.540998 -315.211714)
					(mid 11.505077 -315.226593)
					(end 11.490198 -315.262514)
				)
			)
		)
	)
	(zone
		(layers "In1.Cu" "In2.Cu")
		(hatch none 0.5)
		(connect_pads
			(clearance 0)
		)
		(min_thickness 0.25)
		(keepout
			(tracks not_allowed)
			(vias allowed)
			(pads allowed)
			(copperpour not_allowed)
			(footprints allowed)
		)
		(placement
			(enabled no)
			(sheetname "")
		)
		(fill yes
			(thermal_gap 0.5)
			(thermal_bridge_width 0.5)
			(island_removal_mode 0)
		)
		(polygon
			(pts
				(arc
					(start 308.136798 -206.021432)
					(mid 308.151677 -206.057353)
					(end 308.187598 -206.072232)
				)
				(arc
					(start 309.587138 -206.072232)
					(mid 309.623059 -206.057353)
					(end 309.637938 -206.021432)
				)
				(arc
					(start 309.637938 -205.612492)
					(mid 309.623059 -205.576571)
					(end 309.587138 -205.561692)
				)
				(arc
					(start 308.187598 -205.561692)
					(mid 308.151677 -205.576571)
					(end 308.136798 -205.612492)
				)
			)
		)
	)
	(zone
		(layers "In1.Cu" "In2.Cu")
		(hatch none 0.5)
		(connect_pads
			(clearance 0)
		)
		(min_thickness 0.25)
		(keepout
			(tracks not_allowed)
			(vias allowed)
			(pads allowed)
			(copperpour not_allowed)
			(footprints allowed)
		)
		(placement
			(enabled no)
			(sheetname "")
		)
		(fill yes
			(thermal_gap 0.5)
			(thermal_bridge_width 0.5)
			(island_removal_mode 0)
		)
		(polygon
			(pts
				(arc
					(start 410.103066 -292.721538)
					(mid 410.117945 -292.757459)
					(end 410.153866 -292.772338)
				)
				(arc
					(start 411.553406 -292.772338)
					(mid 411.589327 -292.757459)
					(end 411.604206 -292.721538)
				)
				(arc
					(start 411.604206 -292.312598)
					(mid 411.589327 -292.276677)
					(end 411.553406 -292.261798)
				)
				(arc
					(start 410.153866 -292.261798)
					(mid 410.117945 -292.276677)
					(end 410.103066 -292.312598)
				)
			)
		)
	)
	(zone
		(layers "In1.Cu" "In2.Cu")
		(hatch none 0.5)
		(connect_pads
			(clearance 0)
		)
		(min_thickness 0.25)
		(keepout
			(tracks not_allowed)
			(vias allowed)
			(pads allowed)
			(copperpour not_allowed)
			(footprints allowed)
		)
		(placement
			(enabled no)
			(sheetname "")
		)
		(fill yes
			(thermal_gap 0.5)
			(thermal_bridge_width 0.5)
			(island_removal_mode 0)
		)
		(polygon
			(pts
				(arc
					(start 289.605466 -251.921518)
					(mid 289.620345 -251.957439)
					(end 289.656266 -251.972318)
				)
				(arc
					(start 291.055806 -251.972318)
					(mid 291.091727 -251.957439)
					(end 291.106606 -251.921518)
				)
				(arc
					(start 291.106606 -251.512578)
					(mid 291.091727 -251.476657)
					(end 291.055806 -251.461778)
				)
				(arc
					(start 289.656266 -251.461778)
					(mid 289.620345 -251.476657)
					(end 289.605466 -251.512578)
				)
			)
		)
	)
	(zone
		(layers "In1.Cu" "In2.Cu")
		(hatch none 0.5)
		(connect_pads
			(clearance 0)
		)
		(min_thickness 0.25)
		(keepout
			(tracks not_allowed)
			(vias allowed)
			(pads allowed)
			(copperpour not_allowed)
			(footprints allowed)
		)
		(placement
			(enabled no)
			(sheetname "")
		)
		(fill yes
			(thermal_gap 0.5)
			(thermal_bridge_width 0.5)
			(island_removal_mode 0)
		)
		(polygon
			(pts
				(arc
					(start 451.265798 -252.771402)
					(mid 451.280677 -252.807323)
					(end 451.316598 -252.822202)
				)
				(arc
					(start 452.716138 -252.822202)
					(mid 452.752059 -252.807323)
					(end 452.766938 -252.771402)
				)
				(arc
					(start 452.766938 -252.362462)
					(mid 452.752059 -252.326541)
					(end 452.716138 -252.311662)
				)
				(arc
					(start 451.316598 -252.311662)
					(mid 451.280677 -252.326541)
					(end 451.265798 -252.362462)
				)
			)
		)
	)
	(zone
		(layers "In1.Cu" "In2.Cu")
		(hatch none 0.5)
		(connect_pads
			(clearance 0)
		)
		(min_thickness 0.25)
		(keepout
			(tracks not_allowed)
			(vias allowed)
			(pads allowed)
			(copperpour not_allowed)
			(footprints allowed)
		)
		(placement
			(enabled no)
			(sheetname "")
		)
		(fill yes
			(thermal_gap 0.5)
			(thermal_bridge_width 0.5)
			(island_removal_mode 0)
		)
		(polygon
			(pts
				(arc
					(start 192.338198 -212.82152)
					(mid 192.353077 -212.857441)
					(end 192.388998 -212.87232)
				)
				(arc
					(start 193.788538 -212.87232)
					(mid 193.824459 -212.857441)
					(end 193.839338 -212.82152)
				)
				(arc
					(start 193.839338 -212.41258)
					(mid 193.824459 -212.376659)
					(end 193.788538 -212.36178)
				)
				(arc
					(start 192.388998 -212.36178)
					(mid 192.353077 -212.376659)
					(end 192.338198 -212.41258)
				)
			)
		)
	)
	(zone
		(layers "In1.Cu" "In2.Cu")
		(hatch none 0.5)
		(connect_pads
			(clearance 0)
		)
		(min_thickness 0.25)
		(keepout
			(tracks not_allowed)
			(vias allowed)
			(pads allowed)
			(copperpour not_allowed)
			(footprints allowed)
		)
		(placement
			(enabled no)
			(sheetname "")
		)
		(fill yes
			(thermal_gap 0.5)
			(thermal_bridge_width 0.5)
			(island_removal_mode 0)
		)
		(polygon
			(pts
				(arc
					(start 451.265798 -284.221428)
					(mid 451.280677 -284.257349)
					(end 451.316598 -284.272228)
				)
				(arc
					(start 452.716138 -284.272228)
					(mid 452.752059 -284.257349)
					(end 452.766938 -284.221428)
				)
				(arc
					(start 452.766938 -283.812488)
					(mid 452.752059 -283.776567)
					(end 452.716138 -283.761688)
				)
				(arc
					(start 451.316598 -283.761688)
					(mid 451.280677 -283.776567)
					(end 451.265798 -283.812488)
				)
			)
		)
	)
	(zone
		(layers "In1.Cu" "In2.Cu")
		(hatch none 0.5)
		(connect_pads
			(clearance 0)
		)
		(min_thickness 0.25)
		(keepout
			(tracks not_allowed)
			(vias allowed)
			(pads allowed)
			(copperpour not_allowed)
			(footprints allowed)
		)
		(placement
			(enabled no)
			(sheetname "")
		)
		(fill yes
			(thermal_gap 0.5)
			(thermal_bridge_width 0.5)
			(island_removal_mode 0)
		)
		(polygon
			(pts
				(arc
					(start 173.15053 -219.621354)
					(mid 173.165409 -219.657275)
					(end 173.20133 -219.672154)
				)
				(arc
					(start 174.60087 -219.672154)
					(mid 174.636791 -219.657275)
					(end 174.65167 -219.621354)
				)
				(arc
					(start 174.65167 -219.212414)
					(mid 174.636791 -219.176493)
					(end 174.60087 -219.161614)
				)
				(arc
					(start 173.20133 -219.161614)
					(mid 173.165409 -219.176493)
					(end 173.15053 -219.212414)
				)
			)
		)
	)
	(zone
		(layers "In1.Cu" "In2.Cu")
		(hatch none 0.5)
		(connect_pads
			(clearance 0)
		)
		(min_thickness 0.25)
		(keepout
			(tracks not_allowed)
			(vias allowed)
			(pads allowed)
			(copperpour not_allowed)
			(footprints allowed)
		)
		(placement
			(enabled no)
			(sheetname "")
		)
		(fill yes
			(thermal_gap 0.5)
			(thermal_bridge_width 0.5)
			(island_removal_mode 0)
		)
		(polygon
			(pts
				(arc
					(start 304.693066 -270.621506)
					(mid 304.707945 -270.657427)
					(end 304.743866 -270.672306)
				)
				(arc
					(start 306.143406 -270.672306)
					(mid 306.179327 -270.657427)
					(end 306.194206 -270.621506)
				)
				(arc
					(start 306.194206 -270.212566)
					(mid 306.179327 -270.176645)
					(end 306.143406 -270.161766)
				)
				(arc
					(start 304.743866 -270.161766)
					(mid 304.707945 -270.176645)
					(end 304.693066 -270.212566)
				)
			)
		)
	)
	(zone
		(layers "In1.Cu" "In2.Cu")
		(hatch none 0.5)
		(connect_pads
			(clearance 0)
		)
		(min_thickness 0.25)
		(keepout
			(tracks not_allowed)
			(vias allowed)
			(pads allowed)
			(copperpour not_allowed)
			(footprints allowed)
		)
		(placement
			(enabled no)
			(sheetname "")
		)
		(fill yes
			(thermal_gap 0.5)
			(thermal_bridge_width 0.5)
			(island_removal_mode 0)
		)
		(polygon
			(pts
				(arc
					(start 180.69433 -230.67137)
					(mid 180.709209 -230.707291)
					(end 180.74513 -230.72217)
				)
				(arc
					(start 182.14467 -230.72217)
					(mid 182.180591 -230.707291)
					(end 182.19547 -230.67137)
				)
				(arc
					(start 182.19547 -230.26243)
					(mid 182.180591 -230.226509)
					(end 182.14467 -230.21163)
				)
				(arc
					(start 180.74513 -230.21163)
					(mid 180.709209 -230.226509)
					(end 180.69433 -230.26243)
				)
			)
		)
	)
	(zone
		(layers "In1.Cu" "In2.Cu")
		(hatch none 0.5)
		(connect_pads
			(clearance 0)
		)
		(min_thickness 0.25)
		(keepout
			(tracks not_allowed)
			(vias allowed)
			(pads allowed)
			(copperpour not_allowed)
			(footprints allowed)
		)
		(placement
			(enabled no)
			(sheetname "")
		)
		(fill yes
			(thermal_gap 0.5)
			(thermal_bridge_width 0.5)
			(island_removal_mode 0)
		)
		(polygon
			(pts
				(arc
					(start 443.721998 -312.27141)
					(mid 443.736877 -312.307331)
					(end 443.772798 -312.32221)
				)
				(arc
					(start 445.172338 -312.32221)
					(mid 445.208259 -312.307331)
					(end 445.223138 -312.27141)
				)
				(arc
					(start 445.223138 -311.86247)
					(mid 445.208259 -311.826549)
					(end 445.172338 -311.81167)
				)
				(arc
					(start 443.772798 -311.81167)
					(mid 443.736877 -311.826549)
					(end 443.721998 -311.86247)
				)
			)
		)
	)
	(zone
		(layers "In1.Cu" "In2.Cu")
		(hatch none 0.5)
		(connect_pads
			(clearance 0)
		)
		(min_thickness 0.25)
		(keepout
			(tracks not_allowed)
			(vias allowed)
			(pads allowed)
			(copperpour not_allowed)
			(footprints allowed)
		)
		(placement
			(enabled no)
			(sheetname "")
		)
		(fill yes
			(thermal_gap 0.5)
			(thermal_bridge_width 0.5)
			(island_removal_mode 0)
		)
		(polygon
			(pts
				(arc
					(start 425.190666 -229.821486)
					(mid 425.205545 -229.857407)
					(end 425.241466 -229.872286)
				)
				(arc
					(start 426.641006 -229.872286)
					(mid 426.676927 -229.857407)
					(end 426.691806 -229.821486)
				)
				(arc
					(start 426.691806 -229.412546)
					(mid 426.676927 -229.376625)
					(end 426.641006 -229.361746)
				)
				(arc
					(start 425.241466 -229.361746)
					(mid 425.205545 -229.376625)
					(end 425.190666 -229.412546)
				)
			)
		)
	)
	(zone
		(layers "In1.Cu" "In2.Cu")
		(hatch none 0.5)
		(connect_pads
			(clearance 0)
		)
		(min_thickness 0.25)
		(keepout
			(tracks not_allowed)
			(vias allowed)
			(pads allowed)
			(copperpour not_allowed)
			(footprints allowed)
		)
		(placement
			(enabled no)
			(sheetname "")
		)
		(fill yes
			(thermal_gap 0.5)
			(thermal_bridge_width 0.5)
			(island_removal_mode 0)
		)
		(polygon
			(pts
				(arc
					(start 436.178198 -223.021398)
					(mid 436.193077 -223.057319)
					(end 436.228998 -223.072198)
				)
				(arc
					(start 437.628538 -223.072198)
					(mid 437.664459 -223.057319)
					(end 437.679338 -223.021398)
				)
				(arc
					(start 437.679338 -222.612458)
					(mid 437.664459 -222.576537)
					(end 437.628538 -222.561658)
				)
				(arc
					(start 436.228998 -222.561658)
					(mid 436.193077 -222.576537)
					(end 436.178198 -222.612458)
				)
			)
		)
	)
	(zone
		(layers "In1.Cu" "In2.Cu")
		(hatch none 0.5)
		(connect_pads
			(clearance 0)
		)
		(min_thickness 0.25)
		(keepout
			(tracks not_allowed)
			(vias allowed)
			(pads allowed)
			(copperpour not_allowed)
			(footprints allowed)
		)
		(placement
			(enabled no)
			(sheetname "")
		)
		(fill yes
			(thermal_gap 0.5)
			(thermal_bridge_width 0.5)
			(island_removal_mode 0)
		)
		(polygon
			(pts
				(arc
					(start 259.430266 -218.77147)
					(mid 259.445145 -218.807391)
					(end 259.481066 -218.82227)
				)
				(arc
					(start 260.880606 -218.82227)
					(mid 260.916527 -218.807391)
					(end 260.931406 -218.77147)
				)
				(arc
					(start 260.931406 -218.36253)
					(mid 260.916527 -218.326609)
					(end 260.880606 -218.31173)
				)
				(arc
					(start 259.481066 -218.31173)
					(mid 259.445145 -218.326609)
					(end 259.430266 -218.36253)
				)
			)
		)
	)
	(zone
		(layers "In1.Cu" "In2.Cu")
		(hatch none 0.5)
		(connect_pads
			(clearance 0)
		)
		(min_thickness 0.25)
		(keepout
			(tracks not_allowed)
			(vias allowed)
			(pads allowed)
			(copperpour not_allowed)
			(footprints allowed)
		)
		(placement
			(enabled no)
			(sheetname "")
		)
		(fill yes
			(thermal_gap 0.5)
			(thermal_bridge_width 0.5)
			(island_removal_mode 0)
		)
		(polygon
			(pts
				(arc
					(start 192.338198 -306.32146)
					(mid 192.353077 -306.357381)
					(end 192.388998 -306.37226)
				)
				(arc
					(start 193.788538 -306.37226)
					(mid 193.824459 -306.357381)
					(end 193.839338 -306.32146)
				)
				(arc
					(start 193.839338 -305.91252)
					(mid 193.824459 -305.876599)
					(end 193.788538 -305.86172)
				)
				(arc
					(start 192.388998 -305.86172)
					(mid 192.353077 -305.876599)
					(end 192.338198 -305.91252)
				)
			)
		)
	)
	(zone
		(layers "In1.Cu" "In2.Cu")
		(hatch none 0.5)
		(connect_pads
			(clearance 0)
		)
		(min_thickness 0.25)
		(keepout
			(tracks not_allowed)
			(vias allowed)
			(pads allowed)
			(copperpour not_allowed)
			(footprints allowed)
		)
		(placement
			(enabled no)
			(sheetname "")
		)
		(fill yes
			(thermal_gap 0.5)
			(thermal_bridge_width 0.5)
			(island_removal_mode 0)
		)
		(polygon
			(pts
				(arc
					(start 34.121598 -250.221496)
					(mid 34.136477 -250.257417)
					(end 34.172398 -250.272296)
				)
				(arc
					(start 35.571938 -250.272296)
					(mid 35.607859 -250.257417)
					(end 35.622738 -250.221496)
				)
				(arc
					(start 35.622738 -249.812556)
					(mid 35.607859 -249.776635)
					(end 35.571938 -249.761756)
				)
				(arc
					(start 34.172398 -249.761756)
					(mid 34.136477 -249.776635)
					(end 34.121598 -249.812556)
				)
			)
		)
	)
	(zone
		(layers "In1.Cu" "In2.Cu")
		(hatch none 0.5)
		(connect_pads
			(clearance 0)
		)
		(min_thickness 0.25)
		(keepout
			(tracks not_allowed)
			(vias allowed)
			(pads allowed)
			(copperpour not_allowed)
			(footprints allowed)
		)
		(placement
			(enabled no)
			(sheetname "")
		)
		(fill yes
			(thermal_gap 0.5)
			(thermal_bridge_width 0.5)
			(island_removal_mode 0)
		)
		(polygon
			(pts
				(arc
					(start 214.969598 -293.571422)
					(mid 214.984477 -293.607343)
					(end 215.020398 -293.622222)
				)
				(arc
					(start 216.419938 -293.622222)
					(mid 216.455859 -293.607343)
					(end 216.470738 -293.571422)
				)
				(arc
					(start 216.470738 -293.162482)
					(mid 216.455859 -293.126561)
					(end 216.419938 -293.111682)
				)
				(arc
					(start 215.020398 -293.111682)
					(mid 214.984477 -293.126561)
					(end 214.969598 -293.162482)
				)
			)
		)
	)
	(zone
		(layers "In1.Cu" "In2.Cu")
		(hatch none 0.5)
		(connect_pads
			(clearance 0)
		)
		(min_thickness 0.25)
		(keepout
			(tracks not_allowed)
			(vias allowed)
			(pads allowed)
			(copperpour not_allowed)
			(footprints allowed)
		)
		(placement
			(enabled no)
			(sheetname "")
		)
		(fill yes
			(thermal_gap 0.5)
			(thermal_bridge_width 0.5)
			(island_removal_mode 0)
		)
		(polygon
			(pts
				(arc
					(start 37.56533 -223.021398)
					(mid 37.580209 -223.057319)
					(end 37.61613 -223.072198)
				)
				(arc
					(start 39.01567 -223.072198)
					(mid 39.051591 -223.057319)
					(end 39.06647 -223.021398)
				)
				(arc
					(start 39.06647 -222.612458)
					(mid 39.051591 -222.576537)
					(end 39.01567 -222.561658)
				)
				(arc
					(start 37.61613 -222.561658)
					(mid 37.580209 -222.576537)
					(end 37.56533 -222.612458)
				)
			)
		)
	)
	(zone
		(layers "In1.Cu" "In2.Cu")
		(hatch none 0.5)
		(connect_pads
			(clearance 0)
		)
		(min_thickness 0.25)
		(keepout
			(tracks not_allowed)
			(vias allowed)
			(pads allowed)
			(copperpour not_allowed)
			(footprints allowed)
		)
		(placement
			(enabled no)
			(sheetname "")
		)
		(fill yes
			(thermal_gap 0.5)
			(thermal_bridge_width 0.5)
			(island_removal_mode 0)
		)
		(polygon
			(pts
				(arc
					(start 312.236866 -276.571456)
					(mid 312.251745 -276.607377)
					(end 312.287666 -276.622256)
				)
				(arc
					(start 313.687206 -276.622256)
					(mid 313.723127 -276.607377)
					(end 313.738006 -276.571456)
				)
				(arc
					(start 313.738006 -276.162516)
					(mid 313.723127 -276.126595)
					(end 313.687206 -276.111716)
				)
				(arc
					(start 312.287666 -276.111716)
					(mid 312.251745 -276.126595)
					(end 312.236866 -276.162516)
				)
			)
		)
	)
	(zone
		(layers "In1.Cu" "In2.Cu")
		(hatch none 0.5)
		(connect_pads
			(clearance 0)
		)
		(min_thickness 0.25)
		(keepout
			(tracks not_allowed)
			(vias allowed)
			(pads allowed)
			(copperpour not_allowed)
			(footprints allowed)
		)
		(placement
			(enabled no)
			(sheetname "")
		)
		(fill yes
			(thermal_gap 0.5)
			(thermal_bridge_width 0.5)
			(island_removal_mode 0)
		)
		(polygon
			(pts
				(arc
					(start 277.961598 -268.071346)
					(mid 277.976477 -268.107267)
					(end 278.012398 -268.122146)
				)
				(arc
					(start 279.411938 -268.122146)
					(mid 279.447859 -268.107267)
					(end 279.462738 -268.071346)
				)
				(arc
					(start 279.462738 -267.662406)
					(mid 279.447859 -267.626485)
					(end 279.411938 -267.611606)
				)
				(arc
					(start 278.012398 -267.611606)
					(mid 277.976477 -267.626485)
					(end 277.961598 -267.662406)
				)
			)
		)
	)
	(zone
		(layers "In1.Cu" "In2.Cu")
		(hatch none 0.5)
		(connect_pads
			(clearance 0)
		)
		(min_thickness 0.25)
		(keepout
			(tracks not_allowed)
			(vias allowed)
			(pads allowed)
			(copperpour not_allowed)
			(footprints allowed)
		)
		(placement
			(enabled no)
			(sheetname "")
		)
		(fill yes
			(thermal_gap 0.5)
			(thermal_bridge_width 0.5)
			(island_removal_mode 0)
		)
		(polygon
			(pts
				(arc
					(start 285.505398 -211.971382)
					(mid 285.520277 -212.007303)
					(end 285.556198 -212.022182)
				)
				(arc
					(start 286.955738 -212.022182)
					(mid 286.991659 -212.007303)
					(end 287.006538 -211.971382)
				)
				(arc
					(start 287.006538 -211.562442)
					(mid 286.991659 -211.526521)
					(end 286.955738 -211.511642)
				)
				(arc
					(start 285.556198 -211.511642)
					(mid 285.520277 -211.526521)
					(end 285.505398 -211.562442)
				)
			)
		)
	)
	(zone
		(layers "In1.Cu" "In2.Cu")
		(hatch none 0.5)
		(connect_pads
			(clearance 0)
		)
		(min_thickness 0.25)
		(keepout
			(tracks not_allowed)
			(vias allowed)
			(pads allowed)
			(copperpour not_allowed)
			(footprints allowed)
		)
		(placement
			(enabled no)
			(sheetname "")
		)
		(fill yes
			(thermal_gap 0.5)
			(thermal_bridge_width 0.5)
			(island_removal_mode 0)
		)
		(polygon
			(pts
				(arc
					(start 443.721998 -247.671336)
					(mid 443.736877 -247.707257)
					(end 443.772798 -247.722136)
				)
				(arc
					(start 445.172338 -247.722136)
					(mid 445.208259 -247.707257)
					(end 445.223138 -247.671336)
				)
				(arc
					(start 445.223138 -247.262396)
					(mid 445.208259 -247.226475)
					(end 445.172338 -247.211596)
				)
				(arc
					(start 443.772798 -247.211596)
					(mid 443.736877 -247.226475)
					(end 443.721998 -247.262396)
				)
			)
		)
	)
	(zone
		(layers "In1.Cu" "In2.Cu")
		(hatch none 0.5)
		(connect_pads
			(clearance 0)
		)
		(min_thickness 0.25)
		(keepout
			(tracks not_allowed)
			(vias allowed)
			(pads allowed)
			(copperpour not_allowed)
			(footprints allowed)
		)
		(placement
			(enabled no)
			(sheetname "")
		)
		(fill yes
			(thermal_gap 0.5)
			(thermal_bridge_width 0.5)
			(island_removal_mode 0)
		)
		(polygon
			(pts
				(arc
					(start 177.250598 -228.121464)
					(mid 177.265477 -228.157385)
					(end 177.301398 -228.172264)
				)
				(arc
					(start 178.700938 -228.172264)
					(mid 178.736859 -228.157385)
					(end 178.751738 -228.121464)
				)
				(arc
					(start 178.751738 -227.712524)
					(mid 178.736859 -227.676603)
					(end 178.700938 -227.661724)
				)
				(arc
					(start 177.301398 -227.661724)
					(mid 177.265477 -227.676603)
					(end 177.250598 -227.712524)
				)
			)
		)
	)
	(zone
		(layers "In1.Cu" "In2.Cu")
		(hatch none 0.5)
		(connect_pads
			(clearance 0)
		)
		(min_thickness 0.25)
		(keepout
			(tracks not_allowed)
			(vias allowed)
			(pads allowed)
			(copperpour not_allowed)
			(footprints allowed)
		)
		(placement
			(enabled no)
			(sheetname "")
		)
		(fill yes
			(thermal_gap 0.5)
			(thermal_bridge_width 0.5)
			(island_removal_mode 0)
		)
		(polygon
			(pts
				(arc
					(start 60.19673 -245.971314)
					(mid 60.211609 -246.007235)
					(end 60.24753 -246.022114)
				)
				(arc
					(start 61.64707 -246.022114)
					(mid 61.682991 -246.007235)
					(end 61.69787 -245.971314)
				)
				(arc
					(start 61.69787 -245.562374)
					(mid 61.682991 -245.526453)
					(end 61.64707 -245.511574)
				)
				(arc
					(start 60.24753 -245.511574)
					(mid 60.211609 -245.526453)
					(end 60.19673 -245.562374)
				)
			)
		)
	)
	(zone
		(layers "In1.Cu" "In2.Cu")
		(hatch none 0.5)
		(connect_pads
			(clearance 0)
		)
		(min_thickness 0.25)
		(keepout
			(tracks not_allowed)
			(vias allowed)
			(pads allowed)
			(copperpour not_allowed)
			(footprints allowed)
		)
		(placement
			(enabled no)
			(sheetname "")
		)
		(fill yes
			(thermal_gap 0.5)
			(thermal_bridge_width 0.5)
			(island_removal_mode 0)
		)
		(polygon
			(pts
				(arc
					(start 300.592998 -209.421476)
					(mid 300.607877 -209.457397)
					(end 300.643798 -209.472276)
				)
				(arc
					(start 302.043338 -209.472276)
					(mid 302.079259 -209.457397)
					(end 302.094138 -209.421476)
				)
				(arc
					(start 302.094138 -209.012536)
					(mid 302.079259 -208.976615)
					(end 302.043338 -208.961736)
				)
				(arc
					(start 300.643798 -208.961736)
					(mid 300.607877 -208.976615)
					(end 300.592998 -209.012536)
				)
			)
		)
	)
	(zone
		(layers "In1.Cu" "In2.Cu")
		(hatch none 0.5)
		(connect_pads
			(clearance 0)
		)
		(min_thickness 0.25)
		(keepout
			(tracks not_allowed)
			(vias allowed)
			(pads allowed)
			(copperpour not_allowed)
			(footprints allowed)
		)
		(placement
			(enabled no)
			(sheetname "")
		)
		(fill yes
			(thermal_gap 0.5)
			(thermal_bridge_width 0.5)
			(island_removal_mode 0)
		)
		(polygon
			(pts
				(arc
					(start 188.23813 -200.071482)
					(mid 188.253009 -200.107403)
					(end 188.28893 -200.122282)
				)
				(arc
					(start 189.68847 -200.122282)
					(mid 189.724391 -200.107403)
					(end 189.73927 -200.071482)
				)
				(arc
					(start 189.73927 -199.662542)
					(mid 189.724391 -199.626621)
					(end 189.68847 -199.611742)
				)
				(arc
					(start 188.28893 -199.611742)
					(mid 188.253009 -199.626621)
					(end 188.23813 -199.662542)
				)
			)
		)
	)
	(zone
		(layers "In1.Cu" "In2.Cu")
		(hatch none 0.5)
		(connect_pads
			(clearance 0)
		)
		(min_thickness 0.25)
		(keepout
			(tracks not_allowed)
			(vias allowed)
			(pads allowed)
			(copperpour not_allowed)
			(footprints allowed)
		)
		(placement
			(enabled no)
			(sheetname "")
		)
		(fill yes
			(thermal_gap 0.5)
			(thermal_bridge_width 0.5)
			(island_removal_mode 0)
		)
		(polygon
			(pts
				(arc
					(start 255.330198 -279.121362)
					(mid 255.345077 -279.157283)
					(end 255.380998 -279.172162)
				)
				(arc
					(start 256.780538 -279.172162)
					(mid 256.816459 -279.157283)
					(end 256.831338 -279.121362)
				)
				(arc
					(start 256.831338 -278.712422)
					(mid 256.816459 -278.676501)
					(end 256.780538 -278.661622)
				)
				(arc
					(start 255.380998 -278.661622)
					(mid 255.345077 -278.676501)
					(end 255.330198 -278.712422)
				)
			)
		)
	)
	(zone
		(layers "In1.Cu" "In2.Cu")
		(hatch none 0.5)
		(connect_pads
			(clearance 0)
		)
		(min_thickness 0.25)
		(keepout
			(tracks not_allowed)
			(vias allowed)
			(pads allowed)
			(copperpour not_allowed)
			(footprints allowed)
		)
		(placement
			(enabled no)
			(sheetname "")
		)
		(fill yes
			(thermal_gap 0.5)
			(thermal_bridge_width 0.5)
			(island_removal_mode 0)
		)
		(polygon
			(pts
				(arc
					(start 410.103066 -236.62132)
					(mid 410.117945 -236.657241)
					(end 410.153866 -236.67212)
				)
				(arc
					(start 411.553406 -236.67212)
					(mid 411.589327 -236.657241)
					(end 411.604206 -236.62132)
				)
				(arc
					(start 411.604206 -236.21238)
					(mid 411.589327 -236.176459)
					(end 411.553406 -236.16158)
				)
				(arc
					(start 410.153866 -236.16158)
					(mid 410.117945 -236.176459)
					(end 410.103066 -236.21238)
				)
			)
		)
	)
	(zone
		(layers "In1.Cu" "In2.Cu")
		(hatch none 0.5)
		(connect_pads
			(clearance 0)
		)
		(min_thickness 0.25)
		(keepout
			(tracks not_allowed)
			(vias allowed)
			(pads allowed)
			(copperpour not_allowed)
			(footprints allowed)
		)
		(placement
			(enabled no)
			(sheetname "")
		)
		(fill yes
			(thermal_gap 0.5)
			(thermal_bridge_width 0.5)
			(island_removal_mode 0)
		)
		(polygon
			(pts
				(arc
					(start 173.15053 -269.771368)
					(mid 173.165409 -269.807289)
					(end 173.20133 -269.822168)
				)
				(arc
					(start 174.60087 -269.822168)
					(mid 174.636791 -269.807289)
					(end 174.65167 -269.771368)
				)
				(arc
					(start 174.65167 -269.362428)
					(mid 174.636791 -269.326507)
					(end 174.60087 -269.311628)
				)
				(arc
					(start 173.20133 -269.311628)
					(mid 173.165409 -269.326507)
					(end 173.15053 -269.362428)
				)
			)
		)
	)
	(zone
		(layers "In1.Cu" "In2.Cu")
		(hatch none 0.5)
		(connect_pads
			(clearance 0)
		)
		(min_thickness 0.25)
		(keepout
			(tracks not_allowed)
			(vias allowed)
			(pads allowed)
			(copperpour not_allowed)
			(footprints allowed)
		)
		(placement
			(enabled no)
			(sheetname "")
		)
		(fill yes
			(thermal_gap 0.5)
			(thermal_bridge_width 0.5)
			(island_removal_mode 0)
		)
		(polygon
			(pts
				(arc
					(start 14.93393 -307.171344)
					(mid 14.948809 -307.207265)
					(end 14.98473 -307.222144)
				)
				(arc
					(start 16.38427 -307.222144)
					(mid 16.420191 -307.207265)
					(end 16.43507 -307.171344)
				)
				(arc
					(start 16.43507 -306.762404)
					(mid 16.420191 -306.726483)
					(end 16.38427 -306.711604)
				)
				(arc
					(start 14.98473 -306.711604)
					(mid 14.948809 -306.726483)
					(end 14.93393 -306.762404)
				)
			)
		)
	)
	(zone
		(layers "In1.Cu" "In2.Cu")
		(hatch none 0.5)
		(connect_pads
			(clearance 0)
		)
		(min_thickness 0.25)
		(keepout
			(tracks not_allowed)
			(vias allowed)
			(pads allowed)
			(copperpour not_allowed)
			(footprints allowed)
		)
		(placement
			(enabled no)
			(sheetname "")
		)
		(fill yes
			(thermal_gap 0.5)
			(thermal_bridge_width 0.5)
			(island_removal_mode 0)
		)
		(polygon
			(pts
				(arc
					(start 259.430266 -302.071532)
					(mid 259.445145 -302.107453)
					(end 259.481066 -302.122332)
				)
				(arc
					(start 260.880606 -302.122332)
					(mid 260.916527 -302.107453)
					(end 260.931406 -302.071532)
				)
				(arc
					(start 260.931406 -301.662592)
					(mid 260.916527 -301.626671)
					(end 260.880606 -301.611792)
				)
				(arc
					(start 259.481066 -301.611792)
					(mid 259.445145 -301.626671)
					(end 259.430266 -301.662592)
				)
			)
		)
	)
	(zone
		(layers "In1.Cu" "In2.Cu")
		(hatch none 0.5)
		(connect_pads
			(clearance 0)
		)
		(min_thickness 0.25)
		(keepout
			(tracks not_allowed)
			(vias allowed)
			(pads allowed)
			(copperpour not_allowed)
			(footprints allowed)
		)
		(placement
			(enabled no)
			(sheetname "")
		)
		(fill yes
			(thermal_gap 0.5)
			(thermal_bridge_width 0.5)
			(island_removal_mode 0)
		)
		(polygon
			(pts
				(arc
					(start 277.961598 -243.421408)
					(mid 277.976477 -243.457329)
					(end 278.012398 -243.472208)
				)
				(arc
					(start 279.411938 -243.472208)
					(mid 279.447859 -243.457329)
					(end 279.462738 -243.421408)
				)
				(arc
					(start 279.462738 -243.012468)
					(mid 279.447859 -242.976547)
					(end 279.411938 -242.961668)
				)
				(arc
					(start 278.012398 -242.961668)
					(mid 277.976477 -242.976547)
					(end 277.961598 -243.012468)
				)
			)
		)
	)
	(zone
		(layers "In1.Cu" "In2.Cu")
		(hatch none 0.5)
		(connect_pads
			(clearance 0)
		)
		(min_thickness 0.25)
		(keepout
			(tracks not_allowed)
			(vias allowed)
			(pads allowed)
			(copperpour not_allowed)
			(footprints allowed)
		)
		(placement
			(enabled no)
			(sheetname "")
		)
		(fill yes
			(thermal_gap 0.5)
			(thermal_bridge_width 0.5)
			(island_removal_mode 0)
		)
		(polygon
			(pts
				(arc
					(start 443.721998 -207.721454)
					(mid 443.736877 -207.757375)
					(end 443.772798 -207.772254)
				)
				(arc
					(start 445.172338 -207.772254)
					(mid 445.208259 -207.757375)
					(end 445.223138 -207.721454)
				)
				(arc
					(start 445.223138 -207.312514)
					(mid 445.208259 -207.276593)
					(end 445.172338 -207.261714)
				)
				(arc
					(start 443.772798 -207.261714)
					(mid 443.736877 -207.276593)
					(end 443.721998 -207.312514)
				)
			)
		)
	)
	(zone
		(layers "In1.Cu" "In2.Cu")
		(hatch none 0.5)
		(connect_pads
			(clearance 0)
		)
		(min_thickness 0.25)
		(keepout
			(tracks not_allowed)
			(vias allowed)
			(pads allowed)
			(copperpour not_allowed)
			(footprints allowed)
		)
		(placement
			(enabled no)
			(sheetname "")
		)
		(fill yes
			(thermal_gap 0.5)
			(thermal_bridge_width 0.5)
			(island_removal_mode 0)
		)
		(polygon
			(pts
				(arc
					(start 262.873998 -211.971382)
					(mid 262.888877 -212.007303)
					(end 262.924798 -212.022182)
				)
				(arc
					(start 264.324338 -212.022182)
					(mid 264.360259 -212.007303)
					(end 264.375138 -211.971382)
				)
				(arc
					(start 264.375138 -211.562442)
					(mid 264.360259 -211.526521)
					(end 264.324338 -211.511642)
				)
				(arc
					(start 262.924798 -211.511642)
					(mid 262.888877 -211.526521)
					(end 262.873998 -211.562442)
				)
			)
		)
	)
	(zone
		(layers "In1.Cu" "In2.Cu")
		(hatch none 0.5)
		(connect_pads
			(clearance 0)
		)
		(min_thickness 0.25)
		(keepout
			(tracks not_allowed)
			(vias allowed)
			(pads allowed)
			(copperpour not_allowed)
			(footprints allowed)
		)
		(placement
			(enabled no)
			(sheetname "")
		)
		(fill yes
			(thermal_gap 0.5)
			(thermal_bridge_width 0.5)
			(island_removal_mode 0)
		)
		(polygon
			(pts
				(arc
					(start 22.47773 -296.121328)
					(mid 22.492609 -296.157249)
					(end 22.52853 -296.172128)
				)
				(arc
					(start 23.92807 -296.172128)
					(mid 23.963991 -296.157249)
					(end 23.97887 -296.121328)
				)
				(arc
					(start 23.97887 -295.712388)
					(mid 23.963991 -295.676467)
					(end 23.92807 -295.661588)
				)
				(arc
					(start 22.52853 -295.661588)
					(mid 22.492609 -295.676467)
					(end 22.47773 -295.712388)
				)
			)
		)
	)
	(zone
		(layers "In1.Cu" "In2.Cu")
		(hatch none 0.5)
		(connect_pads
			(clearance 0)
		)
		(min_thickness 0.25)
		(keepout
			(tracks not_allowed)
			(vias allowed)
			(pads allowed)
			(copperpour not_allowed)
			(footprints allowed)
		)
		(placement
			(enabled no)
			(sheetname "")
		)
		(fill yes
			(thermal_gap 0.5)
			(thermal_bridge_width 0.5)
			(island_removal_mode 0)
		)
		(polygon
			(pts
				(arc
					(start 289.605466 -260.421374)
					(mid 289.620345 -260.457295)
					(end 289.656266 -260.472174)
				)
				(arc
					(start 291.055806 -260.472174)
					(mid 291.091727 -260.457295)
					(end 291.106606 -260.421374)
				)
				(arc
					(start 291.106606 -260.012434)
					(mid 291.091727 -259.976513)
					(end 291.055806 -259.961634)
				)
				(arc
					(start 289.656266 -259.961634)
					(mid 289.620345 -259.976513)
					(end 289.605466 -260.012434)
				)
			)
		)
	)
	(zone
		(layers "In1.Cu" "In2.Cu")
		(hatch none 0.5)
		(connect_pads
			(clearance 0)
		)
		(min_thickness 0.25)
		(keepout
			(tracks not_allowed)
			(vias allowed)
			(pads allowed)
			(copperpour not_allowed)
			(footprints allowed)
		)
		(placement
			(enabled no)
			(sheetname "")
		)
		(fill yes
			(thermal_gap 0.5)
			(thermal_bridge_width 0.5)
			(island_removal_mode 0)
		)
		(polygon
			(pts
				(arc
					(start 195.78193 -264.671302)
					(mid 195.796809 -264.707223)
					(end 195.83273 -264.722102)
				)
				(arc
					(start 197.23227 -264.722102)
					(mid 197.268191 -264.707223)
					(end 197.28307 -264.671302)
				)
				(arc
					(start 197.28307 -264.262362)
					(mid 197.268191 -264.226441)
					(end 197.23227 -264.211562)
				)
				(arc
					(start 195.83273 -264.211562)
					(mid 195.796809 -264.226441)
					(end 195.78193 -264.262362)
				)
			)
		)
	)
	(zone
		(layers "In1.Cu" "In2.Cu")
		(hatch none 0.5)
		(connect_pads
			(clearance 0)
		)
		(min_thickness 0.25)
		(keepout
			(tracks not_allowed)
			(vias allowed)
			(pads allowed)
			(copperpour not_allowed)
			(footprints allowed)
		)
		(placement
			(enabled no)
			(sheetname "")
		)
		(fill yes
			(thermal_gap 0.5)
			(thermal_bridge_width 0.5)
			(island_removal_mode 0)
		)
		(polygon
			(pts
				(arc
					(start 19.033998 -251.921518)
					(mid 19.048877 -251.957439)
					(end 19.084798 -251.972318)
				)
				(arc
					(start 20.484338 -251.972318)
					(mid 20.520259 -251.957439)
					(end 20.535138 -251.921518)
				)
				(arc
					(start 20.535138 -251.512578)
					(mid 20.520259 -251.476657)
					(end 20.484338 -251.461778)
				)
				(arc
					(start 19.084798 -251.461778)
					(mid 19.048877 -251.476657)
					(end 19.033998 -251.512578)
				)
			)
		)
	)
	(zone
		(layers "In1.Cu" "In2.Cu")
		(hatch none 0.5)
		(connect_pads
			(clearance 0)
		)
		(min_thickness 0.25)
		(keepout
			(tracks not_allowed)
			(vias allowed)
			(pads allowed)
			(copperpour not_allowed)
			(footprints allowed)
		)
		(placement
			(enabled no)
			(sheetname "")
		)
		(fill yes
			(thermal_gap 0.5)
			(thermal_bridge_width 0.5)
			(island_removal_mode 0)
		)
		(polygon
			(pts
				(arc
					(start 300.592998 -279.121362)
					(mid 300.607877 -279.157283)
					(end 300.643798 -279.172162)
				)
				(arc
					(start 302.043338 -279.172162)
					(mid 302.079259 -279.157283)
					(end 302.094138 -279.121362)
				)
				(arc
					(start 302.094138 -278.712422)
					(mid 302.079259 -278.676501)
					(end 302.043338 -278.661622)
				)
				(arc
					(start 300.643798 -278.661622)
					(mid 300.607877 -278.676501)
					(end 300.592998 -278.712422)
				)
			)
		)
	)
	(zone
		(layers "In1.Cu" "In2.Cu")
		(hatch none 0.5)
		(connect_pads
			(clearance 0)
		)
		(min_thickness 0.25)
		(keepout
			(tracks not_allowed)
			(vias allowed)
			(pads allowed)
			(copperpour not_allowed)
			(footprints allowed)
		)
		(placement
			(enabled no)
			(sheetname "")
		)
		(fill yes
			(thermal_gap 0.5)
			(thermal_bridge_width 0.5)
			(island_removal_mode 0)
		)
		(polygon
			(pts
				(arc
					(start 207.425798 -218.77147)
					(mid 207.440677 -218.807391)
					(end 207.476598 -218.82227)
				)
				(arc
					(start 208.876138 -218.82227)
					(mid 208.912059 -218.807391)
					(end 208.926938 -218.77147)
				)
				(arc
					(start 208.926938 -218.36253)
					(mid 208.912059 -218.326609)
					(end 208.876138 -218.31173)
				)
				(arc
					(start 207.476598 -218.31173)
					(mid 207.440677 -218.326609)
					(end 207.425798 -218.36253)
				)
			)
		)
	)
	(zone
		(layers "In1.Cu" "In2.Cu")
		(hatch none 0.5)
		(connect_pads
			(clearance 0)
		)
		(min_thickness 0.25)
		(keepout
			(tracks not_allowed)
			(vias allowed)
			(pads allowed)
			(copperpour not_allowed)
			(footprints allowed)
		)
		(placement
			(enabled no)
			(sheetname "")
		)
		(fill yes
			(thermal_gap 0.5)
			(thermal_bridge_width 0.5)
			(island_removal_mode 0)
		)
		(polygon
			(pts
				(arc
					(start 37.56533 -213.671404)
					(mid 37.580209 -213.707325)
					(end 37.61613 -213.722204)
				)
				(arc
					(start 39.01567 -213.722204)
					(mid 39.051591 -213.707325)
					(end 39.06647 -213.671404)
				)
				(arc
					(start 39.06647 -213.262464)
					(mid 39.051591 -213.226543)
					(end 39.01567 -213.211664)
				)
				(arc
					(start 37.61613 -213.211664)
					(mid 37.580209 -213.226543)
					(end 37.56533 -213.262464)
				)
			)
		)
	)
	(zone
		(layers "In1.Cu" "In2.Cu")
		(hatch none 0.5)
		(connect_pads
			(clearance 0)
		)
		(min_thickness 0.25)
		(keepout
			(tracks not_allowed)
			(vias allowed)
			(pads allowed)
			(copperpour not_allowed)
			(footprints allowed)
		)
		(placement
			(enabled no)
			(sheetname "")
		)
		(fill yes
			(thermal_gap 0.5)
			(thermal_bridge_width 0.5)
			(island_removal_mode 0)
		)
		(polygon
			(pts
				(arc
					(start 22.47773 -275.721318)
					(mid 22.492609 -275.757239)
					(end 22.52853 -275.772118)
				)
				(arc
					(start 23.92807 -275.772118)
					(mid 23.963991 -275.757239)
					(end 23.97887 -275.721318)
				)
				(arc
					(start 23.97887 -275.312378)
					(mid 23.963991 -275.276457)
					(end 23.92807 -275.261578)
				)
				(arc
					(start 22.52853 -275.261578)
					(mid 22.492609 -275.276457)
					(end 22.47773 -275.312378)
				)
			)
		)
	)
	(zone
		(layers "In1.Cu" "In2.Cu")
		(hatch none 0.5)
		(connect_pads
			(clearance 0)
		)
		(min_thickness 0.25)
		(keepout
			(tracks not_allowed)
			(vias allowed)
			(pads allowed)
			(copperpour not_allowed)
			(footprints allowed)
		)
		(placement
			(enabled no)
			(sheetname "")
		)
		(fill yes
			(thermal_gap 0.5)
			(thermal_bridge_width 0.5)
			(island_removal_mode 0)
		)
		(polygon
			(pts
				(arc
					(start 41.665398 -248.521474)
					(mid 41.680277 -248.557395)
					(end 41.716198 -248.572274)
				)
				(arc
					(start 43.115738 -248.572274)
					(mid 43.151659 -248.557395)
					(end 43.166538 -248.521474)
				)
				(arc
					(start 43.166538 -248.112534)
					(mid 43.151659 -248.076613)
					(end 43.115738 -248.061734)
				)
				(arc
					(start 41.716198 -248.061734)
					(mid 41.680277 -248.076613)
					(end 41.665398 -248.112534)
				)
			)
		)
	)
	(zone
		(layers "In1.Cu" "In2.Cu")
		(hatch none 0.5)
		(connect_pads
			(clearance 0)
		)
		(min_thickness 0.25)
		(keepout
			(tracks not_allowed)
			(vias allowed)
			(pads allowed)
			(copperpour not_allowed)
			(footprints allowed)
		)
		(placement
			(enabled no)
			(sheetname "")
		)
		(fill yes
			(thermal_gap 0.5)
			(thermal_bridge_width 0.5)
			(island_removal_mode 0)
		)
		(polygon
			(pts
				(arc
					(start 425.190666 -251.921518)
					(mid 425.205545 -251.957439)
					(end 425.241466 -251.972318)
				)
				(arc
					(start 426.641006 -251.972318)
					(mid 426.676927 -251.957439)
					(end 426.691806 -251.921518)
				)
				(arc
					(start 426.691806 -251.512578)
					(mid 426.676927 -251.476657)
					(end 426.641006 -251.461778)
				)
				(arc
					(start 425.241466 -251.461778)
					(mid 425.205545 -251.476657)
					(end 425.190666 -251.512578)
				)
			)
		)
	)
	(zone
		(layers "In1.Cu" "In2.Cu")
		(hatch none 0.5)
		(connect_pads
			(clearance 0)
		)
		(min_thickness 0.25)
		(keepout
			(tracks not_allowed)
			(vias allowed)
			(pads allowed)
			(copperpour not_allowed)
			(footprints allowed)
		)
		(placement
			(enabled no)
			(sheetname "")
		)
		(fill yes
			(thermal_gap 0.5)
			(thermal_bridge_width 0.5)
			(island_removal_mode 0)
		)
		(polygon
			(pts
				(arc
					(start 421.090598 -204.32141)
					(mid 421.105477 -204.357331)
					(end 421.141398 -204.37221)
				)
				(arc
					(start 422.540938 -204.37221)
					(mid 422.576859 -204.357331)
					(end 422.591738 -204.32141)
				)
				(arc
					(start 422.591738 -203.91247)
					(mid 422.576859 -203.876549)
					(end 422.540938 -203.86167)
				)
				(arc
					(start 421.141398 -203.86167)
					(mid 421.105477 -203.876549)
					(end 421.090598 -203.91247)
				)
			)
		)
	)
	(zone
		(layers "In1.Cu" "In2.Cu")
		(hatch none 0.5)
		(connect_pads
			(clearance 0)
		)
		(min_thickness 0.25)
		(keepout
			(tracks not_allowed)
			(vias allowed)
			(pads allowed)
			(copperpour not_allowed)
			(footprints allowed)
		)
		(placement
			(enabled no)
			(sheetname "")
		)
		(fill yes
			(thermal_gap 0.5)
			(thermal_bridge_width 0.5)
			(island_removal_mode 0)
		)
		(polygon
			(pts
				(arc
					(start 443.721998 -277.42134)
					(mid 443.736877 -277.457261)
					(end 443.772798 -277.47214)
				)
				(arc
					(start 445.172338 -277.47214)
					(mid 445.208259 -277.457261)
					(end 445.223138 -277.42134)
				)
				(arc
					(start 445.223138 -277.0124)
					(mid 445.208259 -276.976479)
					(end 445.172338 -276.9616)
				)
				(arc
					(start 443.772798 -276.9616)
					(mid 443.736877 -276.976479)
					(end 443.721998 -277.0124)
				)
			)
		)
	)
	(zone
		(layers "In1.Cu" "In2.Cu")
		(hatch none 0.5)
		(connect_pads
			(clearance 0)
		)
		(min_thickness 0.25)
		(keepout
			(tracks not_allowed)
			(vias allowed)
			(pads allowed)
			(copperpour not_allowed)
			(footprints allowed)
		)
		(placement
			(enabled no)
			(sheetname "")
		)
		(fill yes
			(thermal_gap 0.5)
			(thermal_bridge_width 0.5)
			(island_removal_mode 0)
		)
		(polygon
			(pts
				(arc
					(start 436.178198 -247.671336)
					(mid 436.193077 -247.707257)
					(end 436.228998 -247.722136)
				)
				(arc
					(start 437.628538 -247.722136)
					(mid 437.664459 -247.707257)
					(end 437.679338 -247.671336)
				)
				(arc
					(start 437.679338 -247.262396)
					(mid 437.664459 -247.226475)
					(end 437.628538 -247.211596)
				)
				(arc
					(start 436.228998 -247.211596)
					(mid 436.193077 -247.226475)
					(end 436.178198 -247.262396)
				)
			)
		)
	)
	(zone
		(layers "In1.Cu" "In2.Cu")
		(hatch none 0.5)
		(connect_pads
			(clearance 0)
		)
		(min_thickness 0.25)
		(keepout
			(tracks not_allowed)
			(vias allowed)
			(pads allowed)
			(copperpour not_allowed)
			(footprints allowed)
		)
		(placement
			(enabled no)
			(sheetname "")
		)
		(fill yes
			(thermal_gap 0.5)
			(thermal_bridge_width 0.5)
			(island_removal_mode 0)
		)
		(polygon
			(pts
				(arc
					(start 192.338198 -222.171514)
					(mid 192.353077 -222.207435)
					(end 192.388998 -222.222314)
				)
				(arc
					(start 193.788538 -222.222314)
					(mid 193.824459 -222.207435)
					(end 193.839338 -222.171514)
				)
				(arc
					(start 193.839338 -221.762574)
					(mid 193.824459 -221.726653)
					(end 193.788538 -221.711774)
				)
				(arc
					(start 192.388998 -221.711774)
					(mid 192.353077 -221.726653)
					(end 192.338198 -221.762574)
				)
			)
		)
	)
	(zone
		(layers "In1.Cu" "In2.Cu")
		(hatch none 0.5)
		(connect_pads
			(clearance 0)
		)
		(min_thickness 0.25)
		(keepout
			(tracks not_allowed)
			(vias allowed)
			(pads allowed)
			(copperpour not_allowed)
			(footprints allowed)
		)
		(placement
			(enabled no)
			(sheetname "")
		)
		(fill yes
			(thermal_gap 0.5)
			(thermal_bridge_width 0.5)
			(island_removal_mode 0)
		)
		(polygon
			(pts
				(arc
					(start 192.338198 -272.321528)
					(mid 192.353077 -272.357449)
					(end 192.388998 -272.372328)
				)
				(arc
					(start 193.788538 -272.372328)
					(mid 193.824459 -272.357449)
					(end 193.839338 -272.321528)
				)
				(arc
					(start 193.839338 -271.912588)
					(mid 193.824459 -271.876667)
					(end 193.788538 -271.861788)
				)
				(arc
					(start 192.388998 -271.861788)
					(mid 192.353077 -271.876667)
					(end 192.338198 -271.912588)
				)
			)
		)
	)
	(zone
		(layers "In1.Cu" "In2.Cu")
		(hatch none 0.5)
		(connect_pads
			(clearance 0)
		)
		(min_thickness 0.25)
		(keepout
			(tracks not_allowed)
			(vias allowed)
			(pads allowed)
			(copperpour not_allowed)
			(footprints allowed)
		)
		(placement
			(enabled no)
			(sheetname "")
		)
		(fill yes
			(thermal_gap 0.5)
			(thermal_bridge_width 0.5)
			(island_removal_mode 0)
		)
		(polygon
			(pts
				(arc
					(start 421.090598 -221.321376)
					(mid 421.105477 -221.357297)
					(end 421.141398 -221.372176)
				)
				(arc
					(start 422.540938 -221.372176)
					(mid 422.576859 -221.357297)
					(end 422.591738 -221.321376)
				)
				(arc
					(start 422.591738 -220.912436)
					(mid 422.576859 -220.876515)
					(end 422.540938 -220.861636)
				)
				(arc
					(start 421.141398 -220.861636)
					(mid 421.105477 -220.876515)
					(end 421.090598 -220.912436)
				)
			)
		)
	)
	(zone
		(layers "In1.Cu" "In2.Cu")
		(hatch none 0.5)
		(connect_pads
			(clearance 0)
		)
		(min_thickness 0.25)
		(keepout
			(tracks not_allowed)
			(vias allowed)
			(pads allowed)
			(copperpour not_allowed)
			(footprints allowed)
		)
		(placement
			(enabled no)
			(sheetname "")
		)
		(fill yes
			(thermal_gap 0.5)
			(thermal_bridge_width 0.5)
			(island_removal_mode 0)
		)
		(polygon
			(pts
				(arc
					(start 188.23813 -284.221428)
					(mid 188.253009 -284.257349)
					(end 188.28893 -284.272228)
				)
				(arc
					(start 189.68847 -284.272228)
					(mid 189.724391 -284.257349)
					(end 189.73927 -284.221428)
				)
				(arc
					(start 189.73927 -283.812488)
					(mid 189.724391 -283.776567)
					(end 189.68847 -283.761688)
				)
				(arc
					(start 188.28893 -283.761688)
					(mid 188.253009 -283.776567)
					(end 188.23813 -283.812488)
				)
			)
		)
	)
	(zone
		(layers "In1.Cu" "In2.Cu")
		(hatch none 0.5)
		(connect_pads
			(clearance 0)
		)
		(min_thickness 0.25)
		(keepout
			(tracks not_allowed)
			(vias allowed)
			(pads allowed)
			(copperpour not_allowed)
			(footprints allowed)
		)
		(placement
			(enabled no)
			(sheetname "")
		)
		(fill yes
			(thermal_gap 0.5)
			(thermal_bridge_width 0.5)
			(island_removal_mode 0)
		)
		(polygon
			(pts
				(arc
					(start 277.961598 -245.971314)
					(mid 277.976477 -246.007235)
					(end 278.012398 -246.022114)
				)
				(arc
					(start 279.411938 -246.022114)
					(mid 279.447859 -246.007235)
					(end 279.462738 -245.971314)
				)
				(arc
					(start 279.462738 -245.562374)
					(mid 279.447859 -245.526453)
					(end 279.411938 -245.511574)
				)
				(arc
					(start 278.012398 -245.511574)
					(mid 277.976477 -245.526453)
					(end 277.961598 -245.562374)
				)
			)
		)
	)
	(zone
		(layers "In1.Cu" "In2.Cu")
		(hatch none 0.5)
		(connect_pads
			(clearance 0)
		)
		(min_thickness 0.25)
		(keepout
			(tracks not_allowed)
			(vias allowed)
			(pads allowed)
			(copperpour not_allowed)
			(footprints allowed)
		)
		(placement
			(enabled no)
			(sheetname "")
		)
		(fill yes
			(thermal_gap 0.5)
			(thermal_bridge_width 0.5)
			(island_removal_mode 0)
		)
		(polygon
			(pts
				(arc
					(start 26.577798 -293.571422)
					(mid 26.592677 -293.607343)
					(end 26.628598 -293.622222)
				)
				(arc
					(start 28.028138 -293.622222)
					(mid 28.064059 -293.607343)
					(end 28.078938 -293.571422)
				)
				(arc
					(start 28.078938 -293.162482)
					(mid 28.064059 -293.126561)
					(end 28.028138 -293.111682)
				)
				(arc
					(start 26.628598 -293.111682)
					(mid 26.592677 -293.126561)
					(end 26.577798 -293.162482)
				)
			)
		)
	)
	(zone
		(layers "In1.Cu" "In2.Cu")
		(hatch none 0.5)
		(connect_pads
			(clearance 0)
		)
		(min_thickness 0.25)
		(keepout
			(tracks not_allowed)
			(vias allowed)
			(pads allowed)
			(copperpour not_allowed)
			(footprints allowed)
		)
		(placement
			(enabled no)
			(sheetname "")
		)
		(fill yes
			(thermal_gap 0.5)
			(thermal_bridge_width 0.5)
			(island_removal_mode 0)
		)
		(polygon
			(pts
				(arc
					(start 207.425798 -298.671488)
					(mid 207.440677 -298.707409)
					(end 207.476598 -298.722288)
				)
				(arc
					(start 208.876138 -298.722288)
					(mid 208.912059 -298.707409)
					(end 208.926938 -298.671488)
				)
				(arc
					(start 208.926938 -298.262548)
					(mid 208.912059 -298.226627)
					(end 208.876138 -298.211748)
				)
				(arc
					(start 207.476598 -298.211748)
					(mid 207.440677 -298.226627)
					(end 207.425798 -298.262548)
				)
			)
		)
	)
	(zone
		(layers "In1.Cu" "In2.Cu")
		(hatch none 0.5)
		(connect_pads
			(clearance 0)
		)
		(min_thickness 0.25)
		(keepout
			(tracks not_allowed)
			(vias allowed)
			(pads allowed)
			(copperpour not_allowed)
			(footprints allowed)
		)
		(placement
			(enabled no)
			(sheetname "")
		)
		(fill yes
			(thermal_gap 0.5)
			(thermal_bridge_width 0.5)
			(island_removal_mode 0)
		)
		(polygon
			(pts
				(arc
					(start 60.19673 -279.121362)
					(mid 60.211609 -279.157283)
					(end 60.24753 -279.172162)
				)
				(arc
					(start 61.64707 -279.172162)
					(mid 61.682991 -279.157283)
					(end 61.69787 -279.121362)
				)
				(arc
					(start 61.69787 -278.712422)
					(mid 61.682991 -278.676501)
					(end 61.64707 -278.661622)
				)
				(arc
					(start 60.24753 -278.661622)
					(mid 60.211609 -278.676501)
					(end 60.19673 -278.712422)
				)
			)
		)
	)
	(zone
		(layers "In1.Cu" "In2.Cu")
		(hatch none 0.5)
		(connect_pads
			(clearance 0)
		)
		(min_thickness 0.25)
		(keepout
			(tracks not_allowed)
			(vias allowed)
			(pads allowed)
			(copperpour not_allowed)
			(footprints allowed)
		)
		(placement
			(enabled no)
			(sheetname "")
		)
		(fill yes
			(thermal_gap 0.5)
			(thermal_bridge_width 0.5)
			(island_removal_mode 0)
		)
		(polygon
			(pts
				(arc
					(start 11.490198 -289.321494)
					(mid 11.505077 -289.357415)
					(end 11.540998 -289.372294)
				)
				(arc
					(start 12.940538 -289.372294)
					(mid 12.976459 -289.357415)
					(end 12.991338 -289.321494)
				)
				(arc
					(start 12.991338 -288.912554)
					(mid 12.976459 -288.876633)
					(end 12.940538 -288.861754)
				)
				(arc
					(start 11.540998 -288.861754)
					(mid 11.505077 -288.876633)
					(end 11.490198 -288.912554)
				)
			)
		)
	)
	(zone
		(layers "In1.Cu" "In2.Cu")
		(hatch none 0.5)
		(connect_pads
			(clearance 0)
		)
		(min_thickness 0.25)
		(keepout
			(tracks not_allowed)
			(vias allowed)
			(pads allowed)
			(copperpour not_allowed)
			(footprints allowed)
		)
		(placement
			(enabled no)
			(sheetname "")
		)
		(fill yes
			(thermal_gap 0.5)
			(thermal_bridge_width 0.5)
			(island_removal_mode 0)
		)
		(polygon
			(pts
				(arc
					(start 451.265798 -285.071312)
					(mid 451.280677 -285.107233)
					(end 451.316598 -285.122112)
				)
				(arc
					(start 452.716138 -285.122112)
					(mid 452.752059 -285.107233)
					(end 452.766938 -285.071312)
				)
				(arc
					(start 452.766938 -284.662372)
					(mid 452.752059 -284.626451)
					(end 452.716138 -284.611572)
				)
				(arc
					(start 451.316598 -284.611572)
					(mid 451.280677 -284.626451)
					(end 451.265798 -284.662372)
				)
			)
		)
	)
	(zone
		(layers "In1.Cu" "In2.Cu")
		(hatch none 0.5)
		(connect_pads
			(clearance 0)
		)
		(min_thickness 0.25)
		(keepout
			(tracks not_allowed)
			(vias allowed)
			(pads allowed)
			(copperpour not_allowed)
			(footprints allowed)
		)
		(placement
			(enabled no)
			(sheetname "")
		)
		(fill yes
			(thermal_gap 0.5)
			(thermal_bridge_width 0.5)
			(island_removal_mode 0)
		)
		(polygon
			(pts
				(arc
					(start 177.250598 -298.671488)
					(mid 177.265477 -298.707409)
					(end 177.301398 -298.722288)
				)
				(arc
					(start 178.700938 -298.722288)
					(mid 178.736859 -298.707409)
					(end 178.751738 -298.671488)
				)
				(arc
					(start 178.751738 -298.262548)
					(mid 178.736859 -298.226627)
					(end 178.700938 -298.211748)
				)
				(arc
					(start 177.301398 -298.211748)
					(mid 177.265477 -298.226627)
					(end 177.250598 -298.262548)
				)
			)
		)
	)
	(zone
		(layers "In1.Cu" "In2.Cu")
		(hatch none 0.5)
		(connect_pads
			(clearance 0)
		)
		(min_thickness 0.25)
		(keepout
			(tracks not_allowed)
			(vias allowed)
			(pads allowed)
			(copperpour not_allowed)
			(footprints allowed)
		)
		(placement
			(enabled no)
			(sheetname "")
		)
		(fill yes
			(thermal_gap 0.5)
			(thermal_bridge_width 0.5)
			(island_removal_mode 0)
		)
		(polygon
			(pts
				(arc
					(start 282.061666 -212.82152)
					(mid 282.076545 -212.857441)
					(end 282.112466 -212.87232)
				)
				(arc
					(start 283.512006 -212.87232)
					(mid 283.547927 -212.857441)
					(end 283.562806 -212.82152)
				)
				(arc
					(start 283.562806 -212.41258)
					(mid 283.547927 -212.376659)
					(end 283.512006 -212.36178)
				)
				(arc
					(start 282.112466 -212.36178)
					(mid 282.076545 -212.376659)
					(end 282.061666 -212.41258)
				)
			)
		)
	)
	(zone
		(layers "In1.Cu" "In2.Cu")
		(hatch none 0.5)
		(connect_pads
			(clearance 0)
		)
		(min_thickness 0.25)
		(keepout
			(tracks not_allowed)
			(vias allowed)
			(pads allowed)
			(copperpour not_allowed)
			(footprints allowed)
		)
		(placement
			(enabled no)
			(sheetname "")
		)
		(fill yes
			(thermal_gap 0.5)
			(thermal_bridge_width 0.5)
			(island_removal_mode 0)
		)
		(polygon
			(pts
				(arc
					(start 451.265798 -293.571422)
					(mid 451.280677 -293.607343)
					(end 451.316598 -293.622222)
				)
				(arc
					(start 452.716138 -293.622222)
					(mid 452.752059 -293.607343)
					(end 452.766938 -293.571422)
				)
				(arc
					(start 452.766938 -293.162482)
					(mid 452.752059 -293.126561)
					(end 452.716138 -293.111682)
				)
				(arc
					(start 451.316598 -293.111682)
					(mid 451.280677 -293.126561)
					(end 451.265798 -293.162482)
				)
			)
		)
	)
	(zone
		(layers "In1.Cu" "In2.Cu")
		(hatch none 0.5)
		(connect_pads
			(clearance 0)
		)
		(min_thickness 0.25)
		(keepout
			(tracks not_allowed)
			(vias allowed)
			(pads allowed)
			(copperpour not_allowed)
			(footprints allowed)
		)
		(placement
			(enabled no)
			(sheetname "")
		)
		(fill yes
			(thermal_gap 0.5)
			(thermal_bridge_width 0.5)
			(island_removal_mode 0)
		)
		(polygon
			(pts
				(arc
					(start 34.121598 -245.12143)
					(mid 34.136477 -245.157351)
					(end 34.172398 -245.17223)
				)
				(arc
					(start 35.571938 -245.17223)
					(mid 35.607859 -245.157351)
					(end 35.622738 -245.12143)
				)
				(arc
					(start 35.622738 -244.71249)
					(mid 35.607859 -244.676569)
					(end 35.571938 -244.66169)
				)
				(arc
					(start 34.172398 -244.66169)
					(mid 34.136477 -244.676569)
					(end 34.121598 -244.71249)
				)
			)
		)
	)
	(zone
		(layers "In1.Cu" "In2.Cu")
		(hatch none 0.5)
		(connect_pads
			(clearance 0)
		)
		(min_thickness 0.25)
		(keepout
			(tracks not_allowed)
			(vias allowed)
			(pads allowed)
			(copperpour not_allowed)
			(footprints allowed)
		)
		(placement
			(enabled no)
			(sheetname "")
		)
		(fill yes
			(thermal_gap 0.5)
			(thermal_bridge_width 0.5)
			(island_removal_mode 0)
		)
		(polygon
			(pts
				(arc
					(start 19.033998 -211.121498)
					(mid 19.048877 -211.157419)
					(end 19.084798 -211.172298)
				)
				(arc
					(start 20.484338 -211.172298)
					(mid 20.520259 -211.157419)
					(end 20.535138 -211.121498)
				)
				(arc
					(start 20.535138 -210.712558)
					(mid 20.520259 -210.676637)
					(end 20.484338 -210.661758)
				)
				(arc
					(start 19.084798 -210.661758)
					(mid 19.048877 -210.676637)
					(end 19.033998 -210.712558)
				)
			)
		)
	)
	(zone
		(layers "In1.Cu" "In2.Cu")
		(hatch none 0.5)
		(connect_pads
			(clearance 0)
		)
		(min_thickness 0.25)
		(keepout
			(tracks not_allowed)
			(vias allowed)
			(pads allowed)
			(copperpour not_allowed)
			(footprints allowed)
		)
		(placement
			(enabled no)
			(sheetname "")
		)
		(fill yes
			(thermal_gap 0.5)
			(thermal_bridge_width 0.5)
			(island_removal_mode 0)
		)
		(polygon
			(pts
				(arc
					(start 455.365866 -263.821418)
					(mid 455.380745 -263.857339)
					(end 455.416666 -263.872218)
				)
				(arc
					(start 456.816206 -263.872218)
					(mid 456.852127 -263.857339)
					(end 456.867006 -263.821418)
				)
				(arc
					(start 456.867006 -263.412478)
					(mid 456.852127 -263.376557)
					(end 456.816206 -263.361678)
				)
				(arc
					(start 455.416666 -263.361678)
					(mid 455.380745 -263.376557)
					(end 455.365866 -263.412478)
				)
			)
		)
	)
	(zone
		(layers "In1.Cu" "In2.Cu")
		(hatch none 0.5)
		(connect_pads
			(clearance 0)
		)
		(min_thickness 0.25)
		(keepout
			(tracks not_allowed)
			(vias allowed)
			(pads allowed)
			(copperpour not_allowed)
			(footprints allowed)
		)
		(placement
			(enabled no)
			(sheetname "")
		)
		(fill yes
			(thermal_gap 0.5)
			(thermal_bridge_width 0.5)
			(island_removal_mode 0)
		)
		(polygon
			(pts
				(arc
					(start 266.974066 -259.57149)
					(mid 266.988945 -259.607411)
					(end 267.024866 -259.62229)
				)
				(arc
					(start 268.424406 -259.62229)
					(mid 268.460327 -259.607411)
					(end 268.475206 -259.57149)
				)
				(arc
					(start 268.475206 -259.16255)
					(mid 268.460327 -259.126629)
					(end 268.424406 -259.11175)
				)
				(arc
					(start 267.024866 -259.11175)
					(mid 266.988945 -259.126629)
					(end 266.974066 -259.16255)
				)
			)
		)
	)
	(zone
		(layers "In1.Cu" "In2.Cu")
		(hatch none 0.5)
		(connect_pads
			(clearance 0)
		)
		(min_thickness 0.25)
		(keepout
			(tracks not_allowed)
			(vias allowed)
			(pads allowed)
			(copperpour not_allowed)
			(footprints allowed)
		)
		(placement
			(enabled no)
			(sheetname "")
		)
		(fill yes
			(thermal_gap 0.5)
			(thermal_bridge_width 0.5)
			(island_removal_mode 0)
		)
		(polygon
			(pts
				(arc
					(start 203.32573 -241.721386)
					(mid 203.340609 -241.757307)
					(end 203.37653 -241.772186)
				)
				(arc
					(start 204.77607 -241.772186)
					(mid 204.811991 -241.757307)
					(end 204.82687 -241.721386)
				)
				(arc
					(start 204.82687 -241.312446)
					(mid 204.811991 -241.276525)
					(end 204.77607 -241.261646)
				)
				(arc
					(start 203.37653 -241.261646)
					(mid 203.340609 -241.276525)
					(end 203.32573 -241.312446)
				)
			)
		)
	)
	(zone
		(layers "In1.Cu" "In2.Cu")
		(hatch none 0.5)
		(connect_pads
			(clearance 0)
		)
		(min_thickness 0.25)
		(keepout
			(tracks not_allowed)
			(vias allowed)
			(pads allowed)
			(copperpour not_allowed)
			(footprints allowed)
		)
		(placement
			(enabled no)
			(sheetname "")
		)
		(fill yes
			(thermal_gap 0.5)
			(thermal_bridge_width 0.5)
			(island_removal_mode 0)
		)
		(polygon
			(pts
				(arc
					(start 312.236866 -302.071532)
					(mid 312.251745 -302.107453)
					(end 312.287666 -302.122332)
				)
				(arc
					(start 313.687206 -302.122332)
					(mid 313.723127 -302.107453)
					(end 313.738006 -302.071532)
				)
				(arc
					(start 313.738006 -301.662592)
					(mid 313.723127 -301.626671)
					(end 313.687206 -301.611792)
				)
				(arc
					(start 312.287666 -301.611792)
					(mid 312.251745 -301.626671)
					(end 312.236866 -301.662592)
				)
			)
		)
	)
	(zone
		(layers "In1.Cu" "In2.Cu")
		(hatch none 0.5)
		(connect_pads
			(clearance 0)
		)
		(min_thickness 0.25)
		(keepout
			(tracks not_allowed)
			(vias allowed)
			(pads allowed)
			(copperpour not_allowed)
			(footprints allowed)
		)
		(placement
			(enabled no)
			(sheetname "")
		)
		(fill yes
			(thermal_gap 0.5)
			(thermal_bridge_width 0.5)
			(island_removal_mode 0)
		)
		(polygon
			(pts
				(arc
					(start 14.93393 -284.221428)
					(mid 14.948809 -284.257349)
					(end 14.98473 -284.272228)
				)
				(arc
					(start 16.38427 -284.272228)
					(mid 16.420191 -284.257349)
					(end 16.43507 -284.221428)
				)
				(arc
					(start 16.43507 -283.812488)
					(mid 16.420191 -283.776567)
					(end 16.38427 -283.761688)
				)
				(arc
					(start 14.98473 -283.761688)
					(mid 14.948809 -283.776567)
					(end 14.93393 -283.812488)
				)
			)
		)
	)
	(zone
		(layers "In1.Cu" "In2.Cu")
		(hatch none 0.5)
		(connect_pads
			(clearance 0)
		)
		(min_thickness 0.25)
		(keepout
			(tracks not_allowed)
			(vias allowed)
			(pads allowed)
			(copperpour not_allowed)
			(footprints allowed)
		)
		(placement
			(enabled no)
			(sheetname "")
		)
		(fill yes
			(thermal_gap 0.5)
			(thermal_bridge_width 0.5)
			(island_removal_mode 0)
		)
		(polygon
			(pts
				(arc
					(start 297.149266 -278.271478)
					(mid 297.164145 -278.307399)
					(end 297.200066 -278.322278)
				)
				(arc
					(start 298.599606 -278.322278)
					(mid 298.635527 -278.307399)
					(end 298.650406 -278.271478)
				)
				(arc
					(start 298.650406 -277.862538)
					(mid 298.635527 -277.826617)
					(end 298.599606 -277.811738)
				)
				(arc
					(start 297.200066 -277.811738)
					(mid 297.164145 -277.826617)
					(end 297.149266 -277.862538)
				)
			)
		)
	)
	(zone
		(layers "In1.Cu" "In2.Cu")
		(hatch none 0.5)
		(connect_pads
			(clearance 0)
		)
		(min_thickness 0.25)
		(keepout
			(tracks not_allowed)
			(vias allowed)
			(pads allowed)
			(copperpour not_allowed)
			(footprints allowed)
		)
		(placement
			(enabled no)
			(sheetname "")
		)
		(fill yes
			(thermal_gap 0.5)
			(thermal_bridge_width 0.5)
			(island_removal_mode 0)
		)
		(polygon
			(pts
				(arc
					(start 199.881998 -209.421476)
					(mid 199.896877 -209.457397)
					(end 199.932798 -209.472276)
				)
				(arc
					(start 201.332338 -209.472276)
					(mid 201.368259 -209.457397)
					(end 201.383138 -209.421476)
				)
				(arc
					(start 201.383138 -209.012536)
					(mid 201.368259 -208.976615)
					(end 201.332338 -208.961736)
				)
				(arc
					(start 199.932798 -208.961736)
					(mid 199.896877 -208.976615)
					(end 199.881998 -209.012536)
				)
			)
		)
	)
	(zone
		(layers "In1.Cu" "In2.Cu")
		(hatch none 0.5)
		(connect_pads
			(clearance 0)
		)
		(min_thickness 0.25)
		(keepout
			(tracks not_allowed)
			(vias allowed)
			(pads allowed)
			(copperpour not_allowed)
			(footprints allowed)
		)
		(placement
			(enabled no)
			(sheetname "")
		)
		(fill yes
			(thermal_gap 0.5)
			(thermal_bridge_width 0.5)
			(island_removal_mode 0)
		)
		(polygon
			(pts
				(arc
					(start 417.646866 -265.52144)
					(mid 417.661745 -265.557361)
					(end 417.697666 -265.57224)
				)
				(arc
					(start 419.097206 -265.57224)
					(mid 419.133127 -265.557361)
					(end 419.148006 -265.52144)
				)
				(arc
					(start 419.148006 -265.1125)
					(mid 419.133127 -265.076579)
					(end 419.097206 -265.0617)
				)
				(arc
					(start 417.697666 -265.0617)
					(mid 417.661745 -265.076579)
					(end 417.646866 -265.1125)
				)
			)
		)
	)
	(zone
		(layers "In1.Cu" "In2.Cu")
		(hatch none 0.5)
		(connect_pads
			(clearance 0)
		)
		(min_thickness 0.25)
		(keepout
			(tracks not_allowed)
			(vias allowed)
			(pads allowed)
			(copperpour not_allowed)
			(footprints allowed)
		)
		(placement
			(enabled no)
			(sheetname "")
		)
		(fill yes
			(thermal_gap 0.5)
			(thermal_bridge_width 0.5)
			(island_removal_mode 0)
		)
		(polygon
			(pts
				(arc
					(start 410.103066 -209.421476)
					(mid 410.117945 -209.457397)
					(end 410.153866 -209.472276)
				)
				(arc
					(start 411.553406 -209.472276)
					(mid 411.589327 -209.457397)
					(end 411.604206 -209.421476)
				)
				(arc
					(start 411.604206 -209.012536)
					(mid 411.589327 -208.976615)
					(end 411.553406 -208.961736)
				)
				(arc
					(start 410.153866 -208.961736)
					(mid 410.117945 -208.976615)
					(end 410.103066 -209.012536)
				)
			)
		)
	)
	(zone
		(layers "In1.Cu" "In2.Cu")
		(hatch none 0.5)
		(connect_pads
			(clearance 0)
		)
		(min_thickness 0.25)
		(keepout
			(tracks not_allowed)
			(vias allowed)
			(pads allowed)
			(copperpour not_allowed)
			(footprints allowed)
		)
		(placement
			(enabled no)
			(sheetname "")
		)
		(fill yes
			(thermal_gap 0.5)
			(thermal_bridge_width 0.5)
			(island_removal_mode 0)
		)
		(polygon
			(pts
				(arc
					(start 199.881998 -245.12143)
					(mid 199.896877 -245.157351)
					(end 199.932798 -245.17223)
				)
				(arc
					(start 201.332338 -245.17223)
					(mid 201.368259 -245.157351)
					(end 201.383138 -245.12143)
				)
				(arc
					(start 201.383138 -244.71249)
					(mid 201.368259 -244.676569)
					(end 201.332338 -244.66169)
				)
				(arc
					(start 199.932798 -244.66169)
					(mid 199.896877 -244.676569)
					(end 199.881998 -244.71249)
				)
			)
		)
	)
	(zone
		(layers "In1.Cu" "In2.Cu")
		(hatch none 0.5)
		(connect_pads
			(clearance 0)
		)
		(min_thickness 0.25)
		(keepout
			(tracks not_allowed)
			(vias allowed)
			(pads allowed)
			(copperpour not_allowed)
			(footprints allowed)
		)
		(placement
			(enabled no)
			(sheetname "")
		)
		(fill yes
			(thermal_gap 0.5)
			(thermal_bridge_width 0.5)
			(island_removal_mode 0)
		)
		(polygon
			(pts
				(arc
					(start 177.250598 -236.62132)
					(mid 177.265477 -236.657241)
					(end 177.301398 -236.67212)
				)
				(arc
					(start 178.700938 -236.67212)
					(mid 178.736859 -236.657241)
					(end 178.751738 -236.62132)
				)
				(arc
					(start 178.751738 -236.21238)
					(mid 178.736859 -236.176459)
					(end 178.700938 -236.16158)
				)
				(arc
					(start 177.301398 -236.16158)
					(mid 177.265477 -236.176459)
					(end 177.250598 -236.21238)
				)
			)
		)
	)
	(zone
		(layers "In1.Cu" "In2.Cu")
		(hatch none 0.5)
		(connect_pads
			(clearance 0)
		)
		(min_thickness 0.25)
		(keepout
			(tracks not_allowed)
			(vias allowed)
			(pads allowed)
			(copperpour not_allowed)
			(footprints allowed)
		)
		(placement
			(enabled no)
			(sheetname "")
		)
		(fill yes
			(thermal_gap 0.5)
			(thermal_bridge_width 0.5)
			(island_removal_mode 0)
		)
		(polygon
			(pts
				(arc
					(start 214.969598 -304.621438)
					(mid 214.984477 -304.657359)
					(end 215.020398 -304.672238)
				)
				(arc
					(start 216.419938 -304.672238)
					(mid 216.455859 -304.657359)
					(end 216.470738 -304.621438)
				)
				(arc
					(start 216.470738 -304.212498)
					(mid 216.455859 -304.176577)
					(end 216.419938 -304.161698)
				)
				(arc
					(start 215.020398 -304.161698)
					(mid 214.984477 -304.176577)
					(end 214.969598 -304.212498)
				)
			)
		)
	)
	(zone
		(layers "In1.Cu" "In2.Cu")
		(hatch none 0.5)
		(connect_pads
			(clearance 0)
		)
		(min_thickness 0.25)
		(keepout
			(tracks not_allowed)
			(vias allowed)
			(pads allowed)
			(copperpour not_allowed)
			(footprints allowed)
		)
		(placement
			(enabled no)
			(sheetname "")
		)
		(fill yes
			(thermal_gap 0.5)
			(thermal_bridge_width 0.5)
			(island_removal_mode 0)
		)
		(polygon
			(pts
				(arc
					(start 37.56533 -302.921416)
					(mid 37.580209 -302.957337)
					(end 37.61613 -302.972216)
				)
				(arc
					(start 39.01567 -302.972216)
					(mid 39.051591 -302.957337)
					(end 39.06647 -302.921416)
				)
				(arc
					(start 39.06647 -302.512476)
					(mid 39.051591 -302.476555)
					(end 39.01567 -302.461676)
				)
				(arc
					(start 37.61613 -302.461676)
					(mid 37.580209 -302.476555)
					(end 37.56533 -302.512476)
				)
			)
		)
	)
	(zone
		(layers "In1.Cu" "In2.Cu")
		(hatch none 0.5)
		(connect_pads
			(clearance 0)
		)
		(min_thickness 0.25)
		(keepout
			(tracks not_allowed)
			(vias allowed)
			(pads allowed)
			(copperpour not_allowed)
			(footprints allowed)
		)
		(placement
			(enabled no)
			(sheetname "")
		)
		(fill yes
			(thermal_gap 0.5)
			(thermal_bridge_width 0.5)
			(island_removal_mode 0)
		)
		(polygon
			(pts
				(arc
					(start 312.236866 -283.371544)
					(mid 312.251745 -283.407465)
					(end 312.287666 -283.422344)
				)
				(arc
					(start 313.687206 -283.422344)
					(mid 313.723127 -283.407465)
					(end 313.738006 -283.371544)
				)
				(arc
					(start 313.738006 -282.962604)
					(mid 313.723127 -282.926683)
					(end 313.687206 -282.911804)
				)
				(arc
					(start 312.287666 -282.911804)
					(mid 312.251745 -282.926683)
					(end 312.236866 -282.962604)
				)
			)
		)
	)
	(zone
		(layers "In1.Cu" "In2.Cu")
		(hatch none 0.5)
		(connect_pads
			(clearance 0)
		)
		(min_thickness 0.25)
		(keepout
			(tracks not_allowed)
			(vias allowed)
			(pads allowed)
			(copperpour not_allowed)
			(footprints allowed)
		)
		(placement
			(enabled no)
			(sheetname "")
		)
		(fill yes
			(thermal_gap 0.5)
			(thermal_bridge_width 0.5)
			(island_removal_mode 0)
		)
		(polygon
			(pts
				(arc
					(start 11.490198 -217.921332)
					(mid 11.505077 -217.957253)
					(end 11.540998 -217.972132)
				)
				(arc
					(start 12.940538 -217.972132)
					(mid 12.976459 -217.957253)
					(end 12.991338 -217.921332)
				)
				(arc
					(start 12.991338 -217.512392)
					(mid 12.976459 -217.476471)
					(end 12.940538 -217.461592)
				)
				(arc
					(start 11.540998 -217.461592)
					(mid 11.505077 -217.476471)
					(end 11.490198 -217.512392)
				)
			)
		)
	)
	(zone
		(layers "In1.Cu" "In2.Cu")
		(hatch none 0.5)
		(connect_pads
			(clearance 0)
		)
		(min_thickness 0.25)
		(keepout
			(tracks not_allowed)
			(vias allowed)
			(pads allowed)
			(copperpour not_allowed)
			(footprints allowed)
		)
		(placement
			(enabled no)
			(sheetname "")
		)
		(fill yes
			(thermal_gap 0.5)
			(thermal_bridge_width 0.5)
			(island_removal_mode 0)
		)
		(polygon
			(pts
				(arc
					(start 410.103066 -306.32146)
					(mid 410.117945 -306.357381)
					(end 410.153866 -306.37226)
				)
				(arc
					(start 411.553406 -306.37226)
					(mid 411.589327 -306.357381)
					(end 411.604206 -306.32146)
				)
				(arc
					(start 411.604206 -305.91252)
					(mid 411.589327 -305.876599)
					(end 411.553406 -305.86172)
				)
				(arc
					(start 410.153866 -305.86172)
					(mid 410.117945 -305.876599)
					(end 410.103066 -305.91252)
				)
			)
		)
	)
	(zone
		(layers "In1.Cu" "In2.Cu")
		(hatch none 0.5)
		(connect_pads
			(clearance 0)
		)
		(min_thickness 0.25)
		(keepout
			(tracks not_allowed)
			(vias allowed)
			(pads allowed)
			(copperpour not_allowed)
			(footprints allowed)
		)
		(placement
			(enabled no)
			(sheetname "")
		)
		(fill yes
			(thermal_gap 0.5)
			(thermal_bridge_width 0.5)
			(island_removal_mode 0)
		)
		(polygon
			(pts
				(arc
					(start 7.39013 -200.071482)
					(mid 7.405009 -200.107403)
					(end 7.44093 -200.122282)
				)
				(arc
					(start 8.84047 -200.122282)
					(mid 8.876391 -200.107403)
					(end 8.89127 -200.071482)
				)
				(arc
					(start 8.89127 -199.662542)
					(mid 8.876391 -199.626621)
					(end 8.84047 -199.611742)
				)
				(arc
					(start 7.44093 -199.611742)
					(mid 7.405009 -199.626621)
					(end 7.39013 -199.662542)
				)
			)
		)
	)
	(zone
		(layers "In1.Cu" "In2.Cu")
		(hatch none 0.5)
		(connect_pads
			(clearance 0)
		)
		(min_thickness 0.25)
		(keepout
			(tracks not_allowed)
			(vias allowed)
			(pads allowed)
			(copperpour not_allowed)
			(footprints allowed)
		)
		(placement
			(enabled no)
			(sheetname "")
		)
		(fill yes
			(thermal_gap 0.5)
			(thermal_bridge_width 0.5)
			(island_removal_mode 0)
		)
		(polygon
			(pts
				(arc
					(start 428.634398 -271.47139)
					(mid 428.649277 -271.507311)
					(end 428.685198 -271.52219)
				)
				(arc
					(start 430.084738 -271.52219)
					(mid 430.120659 -271.507311)
					(end 430.135538 -271.47139)
				)
				(arc
					(start 430.135538 -271.06245)
					(mid 430.120659 -271.026529)
					(end 430.084738 -271.01165)
				)
				(arc
					(start 428.685198 -271.01165)
					(mid 428.649277 -271.026529)
					(end 428.634398 -271.06245)
				)
			)
		)
	)
	(zone
		(layers "In1.Cu" "In2.Cu")
		(hatch none 0.5)
		(connect_pads
			(clearance 0)
		)
		(min_thickness 0.25)
		(keepout
			(tracks not_allowed)
			(vias allowed)
			(pads allowed)
			(copperpour not_allowed)
			(footprints allowed)
		)
		(placement
			(enabled no)
			(sheetname "")
		)
		(fill yes
			(thermal_gap 0.5)
			(thermal_bridge_width 0.5)
			(island_removal_mode 0)
		)
		(polygon
			(pts
				(arc
					(start 270.417798 -219.621354)
					(mid 270.432677 -219.657275)
					(end 270.468598 -219.672154)
				)
				(arc
					(start 271.868138 -219.672154)
					(mid 271.904059 -219.657275)
					(end 271.918938 -219.621354)
				)
				(arc
					(start 271.918938 -219.212414)
					(mid 271.904059 -219.176493)
					(end 271.868138 -219.161614)
				)
				(arc
					(start 270.468598 -219.161614)
					(mid 270.432677 -219.176493)
					(end 270.417798 -219.212414)
				)
			)
		)
	)
	(zone
		(layers "In1.Cu" "In2.Cu")
		(hatch none 0.5)
		(connect_pads
			(clearance 0)
		)
		(min_thickness 0.25)
		(keepout
			(tracks not_allowed)
			(vias allowed)
			(pads allowed)
			(copperpour not_allowed)
			(footprints allowed)
		)
		(placement
			(enabled no)
			(sheetname "")
		)
		(fill yes
			(thermal_gap 0.5)
			(thermal_bridge_width 0.5)
			(island_removal_mode 0)
		)
		(polygon
			(pts
				(arc
					(start 30.02153 -308.871366)
					(mid 30.036409 -308.907287)
					(end 30.07233 -308.922166)
				)
				(arc
					(start 31.47187 -308.922166)
					(mid 31.507791 -308.907287)
					(end 31.52267 -308.871366)
				)
				(arc
					(start 31.52267 -308.462426)
					(mid 31.507791 -308.426505)
					(end 31.47187 -308.411626)
				)
				(arc
					(start 30.07233 -308.411626)
					(mid 30.036409 -308.426505)
					(end 30.02153 -308.462426)
				)
			)
		)
	)
	(zone
		(layers "In1.Cu" "In2.Cu")
		(hatch none 0.5)
		(connect_pads
			(clearance 0)
		)
		(min_thickness 0.25)
		(keepout
			(tracks not_allowed)
			(vias allowed)
			(pads allowed)
			(copperpour not_allowed)
			(footprints allowed)
		)
		(placement
			(enabled no)
			(sheetname "")
		)
		(fill yes
			(thermal_gap 0.5)
			(thermal_bridge_width 0.5)
			(island_removal_mode 0)
		)
		(polygon
			(pts
				(arc
					(start 45.10913 -313.121294)
					(mid 45.124009 -313.157215)
					(end 45.15993 -313.172094)
				)
				(arc
					(start 46.55947 -313.172094)
					(mid 46.595391 -313.157215)
					(end 46.61027 -313.121294)
				)
				(arc
					(start 46.61027 -312.712354)
					(mid 46.595391 -312.676433)
					(end 46.55947 -312.661554)
				)
				(arc
					(start 45.15993 -312.661554)
					(mid 45.124009 -312.676433)
					(end 45.10913 -312.712354)
				)
			)
		)
	)
	(zone
		(layers "In1.Cu" "In2.Cu")
		(hatch none 0.5)
		(connect_pads
			(clearance 0)
		)
		(min_thickness 0.25)
		(keepout
			(tracks not_allowed)
			(vias allowed)
			(pads allowed)
			(copperpour not_allowed)
			(footprints allowed)
		)
		(placement
			(enabled no)
			(sheetname "")
		)
		(fill yes
			(thermal_gap 0.5)
			(thermal_bridge_width 0.5)
			(island_removal_mode 0)
		)
		(polygon
			(pts
				(arc
					(start 37.56533 -310.571388)
					(mid 37.580209 -310.607309)
					(end 37.61613 -310.622188)
				)
				(arc
					(start 39.01567 -310.622188)
					(mid 39.051591 -310.607309)
					(end 39.06647 -310.571388)
				)
				(arc
					(start 39.06647 -310.162448)
					(mid 39.051591 -310.126527)
					(end 39.01567 -310.111648)
				)
				(arc
					(start 37.61613 -310.111648)
					(mid 37.580209 -310.126527)
					(end 37.56533 -310.162448)
				)
			)
		)
	)
	(zone
		(layers "In1.Cu" "In2.Cu")
		(hatch none 0.5)
		(connect_pads
			(clearance 0)
		)
		(min_thickness 0.25)
		(keepout
			(tracks not_allowed)
			(vias allowed)
			(pads allowed)
			(copperpour not_allowed)
			(footprints allowed)
		)
		(placement
			(enabled no)
			(sheetname "")
		)
		(fill yes
			(thermal_gap 0.5)
			(thermal_bridge_width 0.5)
			(island_removal_mode 0)
		)
		(polygon
			(pts
				(arc
					(start 52.65293 -271.47139)
					(mid 52.667809 -271.507311)
					(end 52.70373 -271.52219)
				)
				(arc
					(start 54.10327 -271.52219)
					(mid 54.139191 -271.507311)
					(end 54.15407 -271.47139)
				)
				(arc
					(start 54.15407 -271.06245)
					(mid 54.139191 -271.026529)
					(end 54.10327 -271.01165)
				)
				(arc
					(start 52.70373 -271.01165)
					(mid 52.667809 -271.026529)
					(end 52.65293 -271.06245)
				)
			)
		)
	)
	(zone
		(layers "In1.Cu" "In2.Cu")
		(hatch none 0.5)
		(connect_pads
			(clearance 0)
		)
		(min_thickness 0.25)
		(keepout
			(tracks not_allowed)
			(vias allowed)
			(pads allowed)
			(copperpour not_allowed)
			(footprints allowed)
		)
		(placement
			(enabled no)
			(sheetname "")
		)
		(fill yes
			(thermal_gap 0.5)
			(thermal_bridge_width 0.5)
			(island_removal_mode 0)
		)
		(polygon
			(pts
				(arc
					(start 14.93393 -296.121328)
					(mid 14.948809 -296.157249)
					(end 14.98473 -296.172128)
				)
				(arc
					(start 16.38427 -296.172128)
					(mid 16.420191 -296.157249)
					(end 16.43507 -296.121328)
				)
				(arc
					(start 16.43507 -295.712388)
					(mid 16.420191 -295.676467)
					(end 16.38427 -295.661588)
				)
				(arc
					(start 14.98473 -295.661588)
					(mid 14.948809 -295.676467)
					(end 14.93393 -295.712388)
				)
			)
		)
	)
	(zone
		(layers "In1.Cu" "In2.Cu")
		(hatch none 0.5)
		(connect_pads
			(clearance 0)
		)
		(min_thickness 0.25)
		(keepout
			(tracks not_allowed)
			(vias allowed)
			(pads allowed)
			(copperpour not_allowed)
			(footprints allowed)
		)
		(placement
			(enabled no)
			(sheetname "")
		)
		(fill yes
			(thermal_gap 0.5)
			(thermal_bridge_width 0.5)
			(island_removal_mode 0)
		)
		(polygon
			(pts
				(arc
					(start 41.665398 -276.571456)
					(mid 41.680277 -276.607377)
					(end 41.716198 -276.622256)
				)
				(arc
					(start 43.115738 -276.622256)
					(mid 43.151659 -276.607377)
					(end 43.166538 -276.571456)
				)
				(arc
					(start 43.166538 -276.162516)
					(mid 43.151659 -276.126595)
					(end 43.115738 -276.111716)
				)
				(arc
					(start 41.716198 -276.111716)
					(mid 41.680277 -276.126595)
					(end 41.665398 -276.162516)
				)
			)
		)
	)
	(zone
		(layers "In1.Cu" "In2.Cu")
		(hatch none 0.5)
		(connect_pads
			(clearance 0)
		)
		(min_thickness 0.25)
		(keepout
			(tracks not_allowed)
			(vias allowed)
			(pads allowed)
			(copperpour not_allowed)
			(footprints allowed)
		)
		(placement
			(enabled no)
			(sheetname "")
		)
		(fill yes
			(thermal_gap 0.5)
			(thermal_bridge_width 0.5)
			(island_removal_mode 0)
		)
		(polygon
			(pts
				(arc
					(start 173.15053 -230.67137)
					(mid 173.165409 -230.707291)
					(end 173.20133 -230.72217)
				)
				(arc
					(start 174.60087 -230.72217)
					(mid 174.636791 -230.707291)
					(end 174.65167 -230.67137)
				)
				(arc
					(start 174.65167 -230.26243)
					(mid 174.636791 -230.226509)
					(end 174.60087 -230.21163)
				)
				(arc
					(start 173.20133 -230.21163)
					(mid 173.165409 -230.226509)
					(end 173.15053 -230.26243)
				)
			)
		)
	)
	(zone
		(layers "In1.Cu" "In2.Cu")
		(hatch none 0.5)
		(connect_pads
			(clearance 0)
		)
		(min_thickness 0.25)
		(keepout
			(tracks not_allowed)
			(vias allowed)
			(pads allowed)
			(copperpour not_allowed)
			(footprints allowed)
		)
		(placement
			(enabled no)
			(sheetname "")
		)
		(fill yes
			(thermal_gap 0.5)
			(thermal_bridge_width 0.5)
			(island_removal_mode 0)
		)
		(polygon
			(pts
				(arc
					(start 22.47773 -228.121464)
					(mid 22.492609 -228.157385)
					(end 22.52853 -228.172264)
				)
				(arc
					(start 23.92807 -228.172264)
					(mid 23.963991 -228.157385)
					(end 23.97887 -228.121464)
				)
				(arc
					(start 23.97887 -227.712524)
					(mid 23.963991 -227.676603)
					(end 23.92807 -227.661724)
				)
				(arc
					(start 22.52853 -227.661724)
					(mid 22.492609 -227.676603)
					(end 22.47773 -227.712524)
				)
			)
		)
	)
	(zone
		(layers "In1.Cu" "In2.Cu")
		(hatch none 0.5)
		(connect_pads
			(clearance 0)
		)
		(min_thickness 0.25)
		(keepout
			(tracks not_allowed)
			(vias allowed)
			(pads allowed)
			(copperpour not_allowed)
			(footprints allowed)
		)
		(placement
			(enabled no)
			(sheetname "")
		)
		(fill yes
			(thermal_gap 0.5)
			(thermal_bridge_width 0.5)
			(island_removal_mode 0)
		)
		(polygon
			(pts
				(arc
					(start 421.090598 -218.77147)
					(mid 421.105477 -218.807391)
					(end 421.141398 -218.82227)
				)
				(arc
					(start 422.540938 -218.82227)
					(mid 422.576859 -218.807391)
					(end 422.591738 -218.77147)
				)
				(arc
					(start 422.591738 -218.36253)
					(mid 422.576859 -218.326609)
					(end 422.540938 -218.31173)
				)
				(arc
					(start 421.141398 -218.31173)
					(mid 421.105477 -218.326609)
					(end 421.090598 -218.36253)
				)
			)
		)
	)
	(zone
		(layers "In1.Cu" "In2.Cu")
		(hatch none 0.5)
		(connect_pads
			(clearance 0)
		)
		(min_thickness 0.25)
		(keepout
			(tracks not_allowed)
			(vias allowed)
			(pads allowed)
			(copperpour not_allowed)
			(footprints allowed)
		)
		(placement
			(enabled no)
			(sheetname "")
		)
		(fill yes
			(thermal_gap 0.5)
			(thermal_bridge_width 0.5)
			(island_removal_mode 0)
		)
		(polygon
			(pts
				(arc
					(start 34.121598 -267.221462)
					(mid 34.136477 -267.257383)
					(end 34.172398 -267.272262)
				)
				(arc
					(start 35.571938 -267.272262)
					(mid 35.607859 -267.257383)
					(end 35.622738 -267.221462)
				)
				(arc
					(start 35.622738 -266.812522)
					(mid 35.607859 -266.776601)
					(end 35.571938 -266.761722)
				)
				(arc
					(start 34.172398 -266.761722)
					(mid 34.136477 -266.776601)
					(end 34.121598 -266.812522)
				)
			)
		)
	)
	(zone
		(layers "In1.Cu" "In2.Cu")
		(hatch none 0.5)
		(connect_pads
			(clearance 0)
		)
		(min_thickness 0.25)
		(keepout
			(tracks not_allowed)
			(vias allowed)
			(pads allowed)
			(copperpour not_allowed)
			(footprints allowed)
		)
		(placement
			(enabled no)
			(sheetname "")
		)
		(fill yes
			(thermal_gap 0.5)
			(thermal_bridge_width 0.5)
			(island_removal_mode 0)
		)
		(polygon
			(pts
				(arc
					(start 421.090598 -313.121294)
					(mid 421.105477 -313.157215)
					(end 421.141398 -313.172094)
				)
				(arc
					(start 422.540938 -313.172094)
					(mid 422.576859 -313.157215)
					(end 422.591738 -313.121294)
				)
				(arc
					(start 422.591738 -312.712354)
					(mid 422.576859 -312.676433)
					(end 422.540938 -312.661554)
				)
				(arc
					(start 421.141398 -312.661554)
					(mid 421.105477 -312.676433)
					(end 421.090598 -312.712354)
				)
			)
		)
	)
	(zone
		(layers "In1.Cu" "In2.Cu")
		(hatch none 0.5)
		(connect_pads
			(clearance 0)
		)
		(min_thickness 0.25)
		(keepout
			(tracks not_allowed)
			(vias allowed)
			(pads allowed)
			(copperpour not_allowed)
			(footprints allowed)
		)
		(placement
			(enabled no)
			(sheetname "")
		)
		(fill yes
			(thermal_gap 0.5)
			(thermal_bridge_width 0.5)
			(island_removal_mode 0)
		)
		(polygon
			(pts
				(arc
					(start 413.546798 -238.321342)
					(mid 413.561677 -238.357263)
					(end 413.597598 -238.372142)
				)
				(arc
					(start 414.997138 -238.372142)
					(mid 415.033059 -238.357263)
					(end 415.047938 -238.321342)
				)
				(arc
					(start 415.047938 -237.912402)
					(mid 415.033059 -237.876481)
					(end 414.997138 -237.861602)
				)
				(arc
					(start 413.597598 -237.861602)
					(mid 413.561677 -237.876481)
					(end 413.546798 -237.912402)
				)
			)
		)
	)
	(zone
		(layers "In1.Cu" "In2.Cu")
		(hatch none 0.5)
		(connect_pads
			(clearance 0)
		)
		(min_thickness 0.25)
		(keepout
			(tracks not_allowed)
			(vias allowed)
			(pads allowed)
			(copperpour not_allowed)
			(footprints allowed)
		)
		(placement
			(enabled no)
			(sheetname "")
		)
		(fill yes
			(thermal_gap 0.5)
			(thermal_bridge_width 0.5)
			(island_removal_mode 0)
		)
		(polygon
			(pts
				(arc
					(start 188.23813 -249.371358)
					(mid 188.253009 -249.407279)
					(end 188.28893 -249.422158)
				)
				(arc
					(start 189.68847 -249.422158)
					(mid 189.724391 -249.407279)
					(end 189.73927 -249.371358)
				)
				(arc
					(start 189.73927 -248.962418)
					(mid 189.724391 -248.926497)
					(end 189.68847 -248.911618)
				)
				(arc
					(start 188.28893 -248.911618)
					(mid 188.253009 -248.926497)
					(end 188.23813 -248.962418)
				)
			)
		)
	)
	(zone
		(layers "In1.Cu" "In2.Cu")
		(hatch none 0.5)
		(connect_pads
			(clearance 0)
		)
		(min_thickness 0.25)
		(keepout
			(tracks not_allowed)
			(vias allowed)
			(pads allowed)
			(copperpour not_allowed)
			(footprints allowed)
		)
		(placement
			(enabled no)
			(sheetname "")
		)
		(fill yes
			(thermal_gap 0.5)
			(thermal_bridge_width 0.5)
			(island_removal_mode 0)
		)
		(polygon
			(pts
				(arc
					(start 184.794398 -195.821554)
					(mid 184.809277 -195.857475)
					(end 184.845198 -195.872354)
				)
				(arc
					(start 186.244738 -195.872354)
					(mid 186.280659 -195.857475)
					(end 186.295538 -195.821554)
				)
				(arc
					(start 186.295538 -195.412614)
					(mid 186.280659 -195.376693)
					(end 186.244738 -195.361814)
				)
				(arc
					(start 184.845198 -195.361814)
					(mid 184.809277 -195.376693)
					(end 184.794398 -195.412614)
				)
			)
		)
	)
	(zone
		(layers "In1.Cu" "In2.Cu")
		(hatch none 0.5)
		(connect_pads
			(clearance 0)
		)
		(min_thickness 0.25)
		(keepout
			(tracks not_allowed)
			(vias allowed)
			(pads allowed)
			(copperpour not_allowed)
			(footprints allowed)
		)
		(placement
			(enabled no)
			(sheetname "")
		)
		(fill yes
			(thermal_gap 0.5)
			(thermal_bridge_width 0.5)
			(island_removal_mode 0)
		)
		(polygon
			(pts
				(arc
					(start 458.809598 -219.621354)
					(mid 458.824477 -219.657275)
					(end 458.860398 -219.672154)
				)
				(arc
					(start 460.259938 -219.672154)
					(mid 460.295859 -219.657275)
					(end 460.310738 -219.621354)
				)
				(arc
					(start 460.310738 -219.212414)
					(mid 460.295859 -219.176493)
					(end 460.259938 -219.161614)
				)
				(arc
					(start 458.860398 -219.161614)
					(mid 458.824477 -219.176493)
					(end 458.809598 -219.212414)
				)
			)
		)
	)
	(zone
		(layers "In1.Cu" "In2.Cu")
		(hatch none 0.5)
		(connect_pads
			(clearance 0)
		)
		(min_thickness 0.25)
		(keepout
			(tracks not_allowed)
			(vias allowed)
			(pads allowed)
			(copperpour not_allowed)
			(footprints allowed)
		)
		(placement
			(enabled no)
			(sheetname "")
		)
		(fill yes
			(thermal_gap 0.5)
			(thermal_bridge_width 0.5)
			(island_removal_mode 0)
		)
		(polygon
			(pts
				(arc
					(start 210.86953 -228.971348)
					(mid 210.884409 -229.007269)
					(end 210.92033 -229.022148)
				)
				(arc
					(start 212.31987 -229.022148)
					(mid 212.355791 -229.007269)
					(end 212.37067 -228.971348)
				)
				(arc
					(start 212.37067 -228.562408)
					(mid 212.355791 -228.526487)
					(end 212.31987 -228.511608)
				)
				(arc
					(start 210.92033 -228.511608)
					(mid 210.884409 -228.526487)
					(end 210.86953 -228.562408)
				)
			)
		)
	)
	(zone
		(layers "In1.Cu" "In2.Cu")
		(hatch none 0.5)
		(connect_pads
			(clearance 0)
		)
		(min_thickness 0.25)
		(keepout
			(tracks not_allowed)
			(vias allowed)
			(pads allowed)
			(copperpour not_allowed)
			(footprints allowed)
		)
		(placement
			(enabled no)
			(sheetname "")
		)
		(fill yes
			(thermal_gap 0.5)
			(thermal_bridge_width 0.5)
			(island_removal_mode 0)
		)
		(polygon
			(pts
				(arc
					(start 277.961598 -235.771436)
					(mid 277.976477 -235.807357)
					(end 278.012398 -235.822236)
				)
				(arc
					(start 279.411938 -235.822236)
					(mid 279.447859 -235.807357)
					(end 279.462738 -235.771436)
				)
				(arc
					(start 279.462738 -235.362496)
					(mid 279.447859 -235.326575)
					(end 279.411938 -235.311696)
				)
				(arc
					(start 278.012398 -235.311696)
					(mid 277.976477 -235.326575)
					(end 277.961598 -235.362496)
				)
			)
		)
	)
	(zone
		(layers "In1.Cu" "In2.Cu")
		(hatch none 0.5)
		(connect_pads
			(clearance 0)
		)
		(min_thickness 0.25)
		(keepout
			(tracks not_allowed)
			(vias allowed)
			(pads allowed)
			(copperpour not_allowed)
			(footprints allowed)
		)
		(placement
			(enabled no)
			(sheetname "")
		)
		(fill yes
			(thermal_gap 0.5)
			(thermal_bridge_width 0.5)
			(island_removal_mode 0)
		)
		(polygon
			(pts
				(arc
					(start 421.090598 -200.071482)
					(mid 421.105477 -200.107403)
					(end 421.141398 -200.122282)
				)
				(arc
					(start 422.540938 -200.122282)
					(mid 422.576859 -200.107403)
					(end 422.591738 -200.071482)
				)
				(arc
					(start 422.591738 -199.662542)
					(mid 422.576859 -199.626621)
					(end 422.540938 -199.611742)
				)
				(arc
					(start 421.141398 -199.611742)
					(mid 421.105477 -199.626621)
					(end 421.090598 -199.662542)
				)
			)
		)
	)
	(zone
		(layers "In1.Cu" "In2.Cu")
		(hatch none 0.5)
		(connect_pads
			(clearance 0)
		)
		(min_thickness 0.25)
		(keepout
			(tracks not_allowed)
			(vias allowed)
			(pads allowed)
			(copperpour not_allowed)
			(footprints allowed)
		)
		(placement
			(enabled no)
			(sheetname "")
		)
		(fill yes
			(thermal_gap 0.5)
			(thermal_bridge_width 0.5)
			(island_removal_mode 0)
		)
		(polygon
			(pts
				(arc
					(start 52.65293 -243.421408)
					(mid 52.667809 -243.457329)
					(end 52.70373 -243.472208)
				)
				(arc
					(start 54.10327 -243.472208)
					(mid 54.139191 -243.457329)
					(end 54.15407 -243.421408)
				)
				(arc
					(start 54.15407 -243.012468)
					(mid 54.139191 -242.976547)
					(end 54.10327 -242.961668)
				)
				(arc
					(start 52.70373 -242.961668)
					(mid 52.667809 -242.976547)
					(end 52.65293 -243.012468)
				)
			)
		)
	)
	(zone
		(layers "In1.Cu" "In2.Cu")
		(hatch none 0.5)
		(connect_pads
			(clearance 0)
		)
		(min_thickness 0.25)
		(keepout
			(tracks not_allowed)
			(vias allowed)
			(pads allowed)
			(copperpour not_allowed)
			(footprints allowed)
		)
		(placement
			(enabled no)
			(sheetname "")
		)
		(fill yes
			(thermal_gap 0.5)
			(thermal_bridge_width 0.5)
			(island_removal_mode 0)
		)
		(polygon
			(pts
				(arc
					(start 165.60673 -259.57149)
					(mid 165.621609 -259.607411)
					(end 165.65753 -259.62229)
				)
				(arc
					(start 167.05707 -259.62229)
					(mid 167.092991 -259.607411)
					(end 167.10787 -259.57149)
				)
				(arc
					(start 167.10787 -259.16255)
					(mid 167.092991 -259.126629)
					(end 167.05707 -259.11175)
				)
				(arc
					(start 165.65753 -259.11175)
					(mid 165.621609 -259.126629)
					(end 165.60673 -259.16255)
				)
			)
		)
	)
	(zone
		(layers "In1.Cu" "In2.Cu")
		(hatch none 0.5)
		(connect_pads
			(clearance 0)
		)
		(min_thickness 0.25)
		(keepout
			(tracks not_allowed)
			(vias allowed)
			(pads allowed)
			(copperpour not_allowed)
			(footprints allowed)
		)
		(placement
			(enabled no)
			(sheetname "")
		)
		(fill yes
			(thermal_gap 0.5)
			(thermal_bridge_width 0.5)
			(island_removal_mode 0)
		)
		(polygon
			(pts
				(arc
					(start 49.209198 -203.471526)
					(mid 49.224077 -203.507447)
					(end 49.259998 -203.522326)
				)
				(arc
					(start 50.659538 -203.522326)
					(mid 50.695459 -203.507447)
					(end 50.710338 -203.471526)
				)
				(arc
					(start 50.710338 -203.062586)
					(mid 50.695459 -203.026665)
					(end 50.659538 -203.011786)
				)
				(arc
					(start 49.259998 -203.011786)
					(mid 49.224077 -203.026665)
					(end 49.209198 -203.062586)
				)
			)
		)
	)
	(zone
		(layers "In1.Cu" "In2.Cu")
		(hatch none 0.5)
		(connect_pads
			(clearance 0)
		)
		(min_thickness 0.25)
		(keepout
			(tracks not_allowed)
			(vias allowed)
			(pads allowed)
			(copperpour not_allowed)
			(footprints allowed)
		)
		(placement
			(enabled no)
			(sheetname "")
		)
		(fill yes
			(thermal_gap 0.5)
			(thermal_bridge_width 0.5)
			(island_removal_mode 0)
		)
		(polygon
			(pts
				(arc
					(start 184.794398 -201.771504)
					(mid 184.809277 -201.807425)
					(end 184.845198 -201.822304)
				)
				(arc
					(start 186.244738 -201.822304)
					(mid 186.280659 -201.807425)
					(end 186.295538 -201.771504)
				)
				(arc
					(start 186.295538 -201.362564)
					(mid 186.280659 -201.326643)
					(end 186.244738 -201.311764)
				)
				(arc
					(start 184.845198 -201.311764)
					(mid 184.809277 -201.326643)
					(end 184.794398 -201.362564)
				)
			)
		)
	)
	(zone
		(layers "In1.Cu" "In2.Cu")
		(hatch none 0.5)
		(connect_pads
			(clearance 0)
		)
		(min_thickness 0.25)
		(keepout
			(tracks not_allowed)
			(vias allowed)
			(pads allowed)
			(copperpour not_allowed)
			(footprints allowed)
		)
		(placement
			(enabled no)
			(sheetname "")
		)
		(fill yes
			(thermal_gap 0.5)
			(thermal_bridge_width 0.5)
			(island_removal_mode 0)
		)
		(polygon
			(pts
				(arc
					(start 41.665398 -222.171514)
					(mid 41.680277 -222.207435)
					(end 41.716198 -222.222314)
				)
				(arc
					(start 43.115738 -222.222314)
					(mid 43.151659 -222.207435)
					(end 43.166538 -222.171514)
				)
				(arc
					(start 43.166538 -221.762574)
					(mid 43.151659 -221.726653)
					(end 43.115738 -221.711774)
				)
				(arc
					(start 41.716198 -221.711774)
					(mid 41.680277 -221.726653)
					(end 41.665398 -221.762574)
				)
			)
		)
	)
	(zone
		(layers "In1.Cu" "In2.Cu")
		(hatch none 0.5)
		(connect_pads
			(clearance 0)
		)
		(min_thickness 0.25)
		(keepout
			(tracks not_allowed)
			(vias allowed)
			(pads allowed)
			(copperpour not_allowed)
			(footprints allowed)
		)
		(placement
			(enabled no)
			(sheetname "")
		)
		(fill yes
			(thermal_gap 0.5)
			(thermal_bridge_width 0.5)
			(island_removal_mode 0)
		)
		(polygon
			(pts
				(arc
					(start 285.505398 -308.871366)
					(mid 285.520277 -308.907287)
					(end 285.556198 -308.922166)
				)
				(arc
					(start 286.955738 -308.922166)
					(mid 286.991659 -308.907287)
					(end 287.006538 -308.871366)
				)
				(arc
					(start 287.006538 -308.462426)
					(mid 286.991659 -308.426505)
					(end 286.955738 -308.411626)
				)
				(arc
					(start 285.556198 -308.411626)
					(mid 285.520277 -308.426505)
					(end 285.505398 -308.462426)
				)
			)
		)
	)
	(zone
		(layers "In1.Cu" "In2.Cu")
		(hatch none 0.5)
		(connect_pads
			(clearance 0)
		)
		(min_thickness 0.25)
		(keepout
			(tracks not_allowed)
			(vias allowed)
			(pads allowed)
			(copperpour not_allowed)
			(footprints allowed)
		)
		(placement
			(enabled no)
			(sheetname "")
		)
		(fill yes
			(thermal_gap 0.5)
			(thermal_bridge_width 0.5)
			(island_removal_mode 0)
		)
		(polygon
			(pts
				(arc
					(start 162.162998 -245.12143)
					(mid 162.177877 -245.157351)
					(end 162.213798 -245.17223)
				)
				(arc
					(start 163.613338 -245.17223)
					(mid 163.649259 -245.157351)
					(end 163.664138 -245.12143)
				)
				(arc
					(start 163.664138 -244.71249)
					(mid 163.649259 -244.676569)
					(end 163.613338 -244.66169)
				)
				(arc
					(start 162.213798 -244.66169)
					(mid 162.177877 -244.676569)
					(end 162.162998 -244.71249)
				)
			)
		)
	)
	(zone
		(layers "In1.Cu" "In2.Cu")
		(hatch none 0.5)
		(connect_pads
			(clearance 0)
		)
		(min_thickness 0.25)
		(keepout
			(tracks not_allowed)
			(vias allowed)
			(pads allowed)
			(copperpour not_allowed)
			(footprints allowed)
		)
		(placement
			(enabled no)
			(sheetname "")
		)
		(fill yes
			(thermal_gap 0.5)
			(thermal_bridge_width 0.5)
			(island_removal_mode 0)
		)
		(polygon
			(pts
				(arc
					(start 199.881998 -304.621438)
					(mid 199.896877 -304.657359)
					(end 199.932798 -304.672238)
				)
				(arc
					(start 201.332338 -304.672238)
					(mid 201.368259 -304.657359)
					(end 201.383138 -304.621438)
				)
				(arc
					(start 201.383138 -304.212498)
					(mid 201.368259 -304.176577)
					(end 201.332338 -304.161698)
				)
				(arc
					(start 199.932798 -304.161698)
					(mid 199.896877 -304.176577)
					(end 199.881998 -304.212498)
				)
			)
		)
	)
	(zone
		(layers "In1.Cu" "In2.Cu")
		(hatch none 0.5)
		(connect_pads
			(clearance 0)
		)
		(min_thickness 0.25)
		(keepout
			(tracks not_allowed)
			(vias allowed)
			(pads allowed)
			(copperpour not_allowed)
			(footprints allowed)
		)
		(placement
			(enabled no)
			(sheetname "")
		)
		(fill yes
			(thermal_gap 0.5)
			(thermal_bridge_width 0.5)
			(island_removal_mode 0)
		)
		(polygon
			(pts
				(arc
					(start 199.881998 -262.121396)
					(mid 199.896877 -262.157317)
					(end 199.932798 -262.172196)
				)
				(arc
					(start 201.332338 -262.172196)
					(mid 201.368259 -262.157317)
					(end 201.383138 -262.121396)
				)
				(arc
					(start 201.383138 -261.712456)
					(mid 201.368259 -261.676535)
					(end 201.332338 -261.661656)
				)
				(arc
					(start 199.932798 -261.661656)
					(mid 199.896877 -261.676535)
					(end 199.881998 -261.712456)
				)
			)
		)
	)
	(zone
		(layers "In1.Cu" "In2.Cu")
		(hatch none 0.5)
		(connect_pads
			(clearance 0)
		)
		(min_thickness 0.25)
		(keepout
			(tracks not_allowed)
			(vias allowed)
			(pads allowed)
			(copperpour not_allowed)
			(footprints allowed)
		)
		(placement
			(enabled no)
			(sheetname "")
		)
		(fill yes
			(thermal_gap 0.5)
			(thermal_bridge_width 0.5)
			(island_removal_mode 0)
		)
		(polygon
			(pts
				(arc
					(start 49.209198 -265.52144)
					(mid 49.224077 -265.557361)
					(end 49.259998 -265.57224)
				)
				(arc
					(start 50.659538 -265.57224)
					(mid 50.695459 -265.557361)
					(end 50.710338 -265.52144)
				)
				(arc
					(start 50.710338 -265.1125)
					(mid 50.695459 -265.076579)
					(end 50.659538 -265.0617)
				)
				(arc
					(start 49.259998 -265.0617)
					(mid 49.224077 -265.076579)
					(end 49.209198 -265.1125)
				)
			)
		)
	)
	(zone
		(layers "In1.Cu" "In2.Cu")
		(hatch none 0.5)
		(connect_pads
			(clearance 0)
		)
		(min_thickness 0.25)
		(keepout
			(tracks not_allowed)
			(vias allowed)
			(pads allowed)
			(copperpour not_allowed)
			(footprints allowed)
		)
		(placement
			(enabled no)
			(sheetname "")
		)
		(fill yes
			(thermal_gap 0.5)
			(thermal_bridge_width 0.5)
			(island_removal_mode 0)
		)
		(polygon
			(pts
				(arc
					(start 52.65293 -202.621388)
					(mid 52.667809 -202.657309)
					(end 52.70373 -202.672188)
				)
				(arc
					(start 54.10327 -202.672188)
					(mid 54.139191 -202.657309)
					(end 54.15407 -202.621388)
				)
				(arc
					(start 54.15407 -202.212448)
					(mid 54.139191 -202.176527)
					(end 54.10327 -202.161648)
				)
				(arc
					(start 52.70373 -202.161648)
					(mid 52.667809 -202.176527)
					(end 52.65293 -202.212448)
				)
			)
		)
	)
	(zone
		(layers "In1.Cu" "In2.Cu")
		(hatch none 0.5)
		(connect_pads
			(clearance 0)
		)
		(min_thickness 0.25)
		(keepout
			(tracks not_allowed)
			(vias allowed)
			(pads allowed)
			(copperpour not_allowed)
			(footprints allowed)
		)
		(placement
			(enabled no)
			(sheetname "")
		)
		(fill yes
			(thermal_gap 0.5)
			(thermal_bridge_width 0.5)
			(island_removal_mode 0)
		)
		(polygon
			(pts
				(arc
					(start 162.162998 -283.371544)
					(mid 162.177877 -283.407465)
					(end 162.213798 -283.422344)
				)
				(arc
					(start 163.613338 -283.422344)
					(mid 163.649259 -283.407465)
					(end 163.664138 -283.371544)
				)
				(arc
					(start 163.664138 -282.962604)
					(mid 163.649259 -282.926683)
					(end 163.613338 -282.911804)
				)
				(arc
					(start 162.213798 -282.911804)
					(mid 162.177877 -282.926683)
					(end 162.162998 -282.962604)
				)
			)
		)
	)
	(zone
		(layers "In1.Cu" "In2.Cu")
		(hatch none 0.5)
		(connect_pads
			(clearance 0)
		)
		(min_thickness 0.25)
		(keepout
			(tracks not_allowed)
			(vias allowed)
			(pads allowed)
			(copperpour not_allowed)
			(footprints allowed)
		)
		(placement
			(enabled no)
			(sheetname "")
		)
		(fill yes
			(thermal_gap 0.5)
			(thermal_bridge_width 0.5)
			(island_removal_mode 0)
		)
		(polygon
			(pts
				(arc
					(start 425.190666 -292.721538)
					(mid 425.205545 -292.757459)
					(end 425.241466 -292.772338)
				)
				(arc
					(start 426.641006 -292.772338)
					(mid 426.676927 -292.757459)
					(end 426.691806 -292.721538)
				)
				(arc
					(start 426.691806 -292.312598)
					(mid 426.676927 -292.276677)
					(end 426.641006 -292.261798)
				)
				(arc
					(start 425.241466 -292.261798)
					(mid 425.205545 -292.276677)
					(end 425.190666 -292.312598)
				)
			)
		)
	)
	(zone
		(layers "In1.Cu" "In2.Cu")
		(hatch none 0.5)
		(connect_pads
			(clearance 0)
		)
		(min_thickness 0.25)
		(keepout
			(tracks not_allowed)
			(vias allowed)
			(pads allowed)
			(copperpour not_allowed)
			(footprints allowed)
		)
		(placement
			(enabled no)
			(sheetname "")
		)
		(fill yes
			(thermal_gap 0.5)
			(thermal_bridge_width 0.5)
			(island_removal_mode 0)
		)
		(polygon
			(pts
				(arc
					(start 300.592998 -275.721318)
					(mid 300.607877 -275.757239)
					(end 300.643798 -275.772118)
				)
				(arc
					(start 302.043338 -275.772118)
					(mid 302.079259 -275.757239)
					(end 302.094138 -275.721318)
				)
				(arc
					(start 302.094138 -275.312378)
					(mid 302.079259 -275.276457)
					(end 302.043338 -275.261578)
				)
				(arc
					(start 300.643798 -275.261578)
					(mid 300.607877 -275.276457)
					(end 300.592998 -275.312378)
				)
			)
		)
	)
	(zone
		(layers "In1.Cu" "In2.Cu")
		(hatch none 0.5)
		(connect_pads
			(clearance 0)
		)
		(min_thickness 0.25)
		(keepout
			(tracks not_allowed)
			(vias allowed)
			(pads allowed)
			(copperpour not_allowed)
			(footprints allowed)
		)
		(placement
			(enabled no)
			(sheetname "")
		)
		(fill yes
			(thermal_gap 0.5)
			(thermal_bridge_width 0.5)
			(island_removal_mode 0)
		)
		(polygon
			(pts
				(arc
					(start 169.706798 -263.821418)
					(mid 169.721677 -263.857339)
					(end 169.757598 -263.872218)
				)
				(arc
					(start 171.157138 -263.872218)
					(mid 171.193059 -263.857339)
					(end 171.207938 -263.821418)
				)
				(arc
					(start 171.207938 -263.412478)
					(mid 171.193059 -263.376557)
					(end 171.157138 -263.361678)
				)
				(arc
					(start 169.757598 -263.361678)
					(mid 169.721677 -263.376557)
					(end 169.706798 -263.412478)
				)
			)
		)
	)
	(zone
		(layers "In1.Cu" "In2.Cu")
		(hatch none 0.5)
		(connect_pads
			(clearance 0)
		)
		(min_thickness 0.25)
		(keepout
			(tracks not_allowed)
			(vias allowed)
			(pads allowed)
			(copperpour not_allowed)
			(footprints allowed)
		)
		(placement
			(enabled no)
			(sheetname "")
		)
		(fill yes
			(thermal_gap 0.5)
			(thermal_bridge_width 0.5)
			(island_removal_mode 0)
		)
		(polygon
			(pts
				(arc
					(start 60.19673 -307.171344)
					(mid 60.211609 -307.207265)
					(end 60.24753 -307.222144)
				)
				(arc
					(start 61.64707 -307.222144)
					(mid 61.682991 -307.207265)
					(end 61.69787 -307.171344)
				)
				(arc
					(start 61.69787 -306.762404)
					(mid 61.682991 -306.726483)
					(end 61.64707 -306.711604)
				)
				(arc
					(start 60.24753 -306.711604)
					(mid 60.211609 -306.726483)
					(end 60.19673 -306.762404)
				)
			)
		)
	)
	(zone
		(layers "In1.Cu" "In2.Cu")
		(hatch none 0.5)
		(connect_pads
			(clearance 0)
		)
		(min_thickness 0.25)
		(keepout
			(tracks not_allowed)
			(vias allowed)
			(pads allowed)
			(copperpour not_allowed)
			(footprints allowed)
		)
		(placement
			(enabled no)
			(sheetname "")
		)
		(fill yes
			(thermal_gap 0.5)
			(thermal_bridge_width 0.5)
			(island_removal_mode 0)
		)
		(polygon
			(pts
				(arc
					(start 304.693066 -248.521474)
					(mid 304.707945 -248.557395)
					(end 304.743866 -248.572274)
				)
				(arc
					(start 306.143406 -248.572274)
					(mid 306.179327 -248.557395)
					(end 306.194206 -248.521474)
				)
				(arc
					(start 306.194206 -248.112534)
					(mid 306.179327 -248.076613)
					(end 306.143406 -248.061734)
				)
				(arc
					(start 304.743866 -248.061734)
					(mid 304.707945 -248.076613)
					(end 304.693066 -248.112534)
				)
			)
		)
	)
	(zone
		(layers "In1.Cu" "In2.Cu")
		(hatch none 0.5)
		(connect_pads
			(clearance 0)
		)
		(min_thickness 0.25)
		(keepout
			(tracks not_allowed)
			(vias allowed)
			(pads allowed)
			(copperpour not_allowed)
			(footprints allowed)
		)
		(placement
			(enabled no)
			(sheetname "")
		)
		(fill yes
			(thermal_gap 0.5)
			(thermal_bridge_width 0.5)
			(island_removal_mode 0)
		)
		(polygon
			(pts
				(arc
					(start 49.209198 -293.571422)
					(mid 49.224077 -293.607343)
					(end 49.259998 -293.622222)
				)
				(arc
					(start 50.659538 -293.622222)
					(mid 50.695459 -293.607343)
					(end 50.710338 -293.571422)
				)
				(arc
					(start 50.710338 -293.162482)
					(mid 50.695459 -293.126561)
					(end 50.659538 -293.111682)
				)
				(arc
					(start 49.259998 -293.111682)
					(mid 49.224077 -293.126561)
					(end 49.209198 -293.162482)
				)
			)
		)
	)
	(zone
		(layers "In1.Cu" "In2.Cu")
		(hatch none 0.5)
		(connect_pads
			(clearance 0)
		)
		(min_thickness 0.25)
		(keepout
			(tracks not_allowed)
			(vias allowed)
			(pads allowed)
			(copperpour not_allowed)
			(footprints allowed)
		)
		(placement
			(enabled no)
			(sheetname "")
		)
		(fill yes
			(thermal_gap 0.5)
			(thermal_bridge_width 0.5)
			(island_removal_mode 0)
		)
		(polygon
			(pts
				(arc
					(start 34.121598 -293.571422)
					(mid 34.136477 -293.607343)
					(end 34.172398 -293.622222)
				)
				(arc
					(start 35.571938 -293.622222)
					(mid 35.607859 -293.607343)
					(end 35.622738 -293.571422)
				)
				(arc
					(start 35.622738 -293.162482)
					(mid 35.607859 -293.126561)
					(end 35.571938 -293.111682)
				)
				(arc
					(start 34.172398 -293.111682)
					(mid 34.136477 -293.126561)
					(end 34.121598 -293.162482)
				)
			)
		)
	)
	(zone
		(layers "In1.Cu" "In2.Cu")
		(hatch none 0.5)
		(connect_pads
			(clearance 0)
		)
		(min_thickness 0.25)
		(keepout
			(tracks not_allowed)
			(vias allowed)
			(pads allowed)
			(copperpour not_allowed)
			(footprints allowed)
		)
		(placement
			(enabled no)
			(sheetname "")
		)
		(fill yes
			(thermal_gap 0.5)
			(thermal_bridge_width 0.5)
			(island_removal_mode 0)
		)
		(polygon
			(pts
				(arc
					(start 214.969598 -285.92145)
					(mid 214.984477 -285.957371)
					(end 215.020398 -285.97225)
				)
				(arc
					(start 216.419938 -285.97225)
					(mid 216.455859 -285.957371)
					(end 216.470738 -285.92145)
				)
				(arc
					(start 216.470738 -285.51251)
					(mid 216.455859 -285.476589)
					(end 216.419938 -285.46171)
				)
				(arc
					(start 215.020398 -285.46171)
					(mid 214.984477 -285.476589)
					(end 214.969598 -285.51251)
				)
			)
		)
	)
	(zone
		(layers "In1.Cu" "In2.Cu")
		(hatch none 0.5)
		(connect_pads
			(clearance 0)
		)
		(min_thickness 0.25)
		(keepout
			(tracks not_allowed)
			(vias allowed)
			(pads allowed)
			(copperpour not_allowed)
			(footprints allowed)
		)
		(placement
			(enabled no)
			(sheetname "")
		)
		(fill yes
			(thermal_gap 0.5)
			(thermal_bridge_width 0.5)
			(island_removal_mode 0)
		)
		(polygon
			(pts
				(arc
					(start 458.809598 -211.971382)
					(mid 458.824477 -212.007303)
					(end 458.860398 -212.022182)
				)
				(arc
					(start 460.259938 -212.022182)
					(mid 460.295859 -212.007303)
					(end 460.310738 -211.971382)
				)
				(arc
					(start 460.310738 -211.562442)
					(mid 460.295859 -211.526521)
					(end 460.259938 -211.511642)
				)
				(arc
					(start 458.860398 -211.511642)
					(mid 458.824477 -211.526521)
					(end 458.809598 -211.562442)
				)
			)
		)
	)
	(zone
		(layers "In1.Cu" "In2.Cu")
		(hatch none 0.5)
		(connect_pads
			(clearance 0)
		)
		(min_thickness 0.25)
		(keepout
			(tracks not_allowed)
			(vias allowed)
			(pads allowed)
			(copperpour not_allowed)
			(footprints allowed)
		)
		(placement
			(enabled no)
			(sheetname "")
		)
		(fill yes
			(thermal_gap 0.5)
			(thermal_bridge_width 0.5)
			(island_removal_mode 0)
		)
		(polygon
			(pts
				(arc
					(start 207.425798 -293.571422)
					(mid 207.440677 -293.607343)
					(end 207.476598 -293.622222)
				)
				(arc
					(start 208.876138 -293.622222)
					(mid 208.912059 -293.607343)
					(end 208.926938 -293.571422)
				)
				(arc
					(start 208.926938 -293.162482)
					(mid 208.912059 -293.126561)
					(end 208.876138 -293.111682)
				)
				(arc
					(start 207.476598 -293.111682)
					(mid 207.440677 -293.126561)
					(end 207.425798 -293.162482)
				)
			)
		)
	)
	(zone
		(layers "In1.Cu" "In2.Cu")
		(hatch none 0.5)
		(connect_pads
			(clearance 0)
		)
		(min_thickness 0.25)
		(keepout
			(tracks not_allowed)
			(vias allowed)
			(pads allowed)
			(copperpour not_allowed)
			(footprints allowed)
		)
		(placement
			(enabled no)
			(sheetname "")
		)
		(fill yes
			(thermal_gap 0.5)
			(thermal_bridge_width 0.5)
			(island_removal_mode 0)
		)
		(polygon
			(pts
				(arc
					(start 41.665398 -234.921298)
					(mid 41.680277 -234.957219)
					(end 41.716198 -234.972098)
				)
				(arc
					(start 43.115738 -234.972098)
					(mid 43.151659 -234.957219)
					(end 43.166538 -234.921298)
				)
				(arc
					(start 43.166538 -234.512358)
					(mid 43.151659 -234.476437)
					(end 43.115738 -234.461558)
				)
				(arc
					(start 41.716198 -234.461558)
					(mid 41.680277 -234.476437)
					(end 41.665398 -234.512358)
				)
			)
		)
	)
	(zone
		(layers "In1.Cu" "In2.Cu")
		(hatch none 0.5)
		(connect_pads
			(clearance 0)
		)
		(min_thickness 0.25)
		(keepout
			(tracks not_allowed)
			(vias allowed)
			(pads allowed)
			(copperpour not_allowed)
			(footprints allowed)
		)
		(placement
			(enabled no)
			(sheetname "")
		)
		(fill yes
			(thermal_gap 0.5)
			(thermal_bridge_width 0.5)
			(island_removal_mode 0)
		)
		(polygon
			(pts
				(arc
					(start 440.278266 -274.871434)
					(mid 440.293145 -274.907355)
					(end 440.329066 -274.922234)
				)
				(arc
					(start 441.728606 -274.922234)
					(mid 441.764527 -274.907355)
					(end 441.779406 -274.871434)
				)
				(arc
					(start 441.779406 -274.462494)
					(mid 441.764527 -274.426573)
					(end 441.728606 -274.411694)
				)
				(arc
					(start 440.329066 -274.411694)
					(mid 440.293145 -274.426573)
					(end 440.278266 -274.462494)
				)
			)
		)
	)
	(zone
		(layers "In1.Cu" "In2.Cu")
		(hatch none 0.5)
		(connect_pads
			(clearance 0)
		)
		(min_thickness 0.25)
		(keepout
			(tracks not_allowed)
			(vias allowed)
			(pads allowed)
			(copperpour not_allowed)
			(footprints allowed)
		)
		(placement
			(enabled no)
			(sheetname "")
		)
		(fill yes
			(thermal_gap 0.5)
			(thermal_bridge_width 0.5)
			(island_removal_mode 0)
		)
		(polygon
			(pts
				(arc
					(start 262.873998 -271.47139)
					(mid 262.888877 -271.507311)
					(end 262.924798 -271.52219)
				)
				(arc
					(start 264.324338 -271.52219)
					(mid 264.360259 -271.507311)
					(end 264.375138 -271.47139)
				)
				(arc
					(start 264.375138 -271.06245)
					(mid 264.360259 -271.026529)
					(end 264.324338 -271.01165)
				)
				(arc
					(start 262.924798 -271.01165)
					(mid 262.888877 -271.026529)
					(end 262.873998 -271.06245)
				)
			)
		)
	)
	(zone
		(layers "In1.Cu" "In2.Cu")
		(hatch none 0.5)
		(connect_pads
			(clearance 0)
		)
		(min_thickness 0.25)
		(keepout
			(tracks not_allowed)
			(vias allowed)
			(pads allowed)
			(copperpour not_allowed)
			(footprints allowed)
		)
		(placement
			(enabled no)
			(sheetname "")
		)
		(fill yes
			(thermal_gap 0.5)
			(thermal_bridge_width 0.5)
			(island_removal_mode 0)
		)
		(polygon
			(pts
				(arc
					(start 259.430266 -217.921332)
					(mid 259.445145 -217.957253)
					(end 259.481066 -217.972132)
				)
				(arc
					(start 260.880606 -217.972132)
					(mid 260.916527 -217.957253)
					(end 260.931406 -217.921332)
				)
				(arc
					(start 260.931406 -217.512392)
					(mid 260.916527 -217.476471)
					(end 260.880606 -217.461592)
				)
				(arc
					(start 259.481066 -217.461592)
					(mid 259.445145 -217.476471)
					(end 259.430266 -217.512392)
				)
			)
		)
	)
	(zone
		(layers "In1.Cu" "In2.Cu")
		(hatch none 0.5)
		(connect_pads
			(clearance 0)
		)
		(min_thickness 0.25)
		(keepout
			(tracks not_allowed)
			(vias allowed)
			(pads allowed)
			(copperpour not_allowed)
			(footprints allowed)
		)
		(placement
			(enabled no)
			(sheetname "")
		)
		(fill yes
			(thermal_gap 0.5)
			(thermal_bridge_width 0.5)
			(island_removal_mode 0)
		)
		(polygon
			(pts
				(arc
					(start 262.873998 -308.871366)
					(mid 262.888877 -308.907287)
					(end 262.924798 -308.922166)
				)
				(arc
					(start 264.324338 -308.922166)
					(mid 264.360259 -308.907287)
					(end 264.375138 -308.871366)
				)
				(arc
					(start 264.375138 -308.462426)
					(mid 264.360259 -308.426505)
					(end 264.324338 -308.411626)
				)
				(arc
					(start 262.924798 -308.411626)
					(mid 262.888877 -308.426505)
					(end 262.873998 -308.462426)
				)
			)
		)
	)
	(zone
		(layers "In1.Cu" "In2.Cu")
		(hatch none 0.5)
		(connect_pads
			(clearance 0)
		)
		(min_thickness 0.25)
		(keepout
			(tracks not_allowed)
			(vias allowed)
			(pads allowed)
			(copperpour not_allowed)
			(footprints allowed)
		)
		(placement
			(enabled no)
			(sheetname "")
		)
		(fill yes
			(thermal_gap 0.5)
			(thermal_bridge_width 0.5)
			(island_removal_mode 0)
		)
		(polygon
			(pts
				(arc
					(start 203.32573 -301.221394)
					(mid 203.340609 -301.257315)
					(end 203.37653 -301.272194)
				)
				(arc
					(start 204.77607 -301.272194)
					(mid 204.811991 -301.257315)
					(end 204.82687 -301.221394)
				)
				(arc
					(start 204.82687 -300.812454)
					(mid 204.811991 -300.776533)
					(end 204.77607 -300.761654)
				)
				(arc
					(start 203.37653 -300.761654)
					(mid 203.340609 -300.776533)
					(end 203.32573 -300.812454)
				)
			)
		)
	)
	(zone
		(layers "In1.Cu" "In2.Cu")
		(hatch none 0.5)
		(connect_pads
			(clearance 0)
		)
		(min_thickness 0.25)
		(keepout
			(tracks not_allowed)
			(vias allowed)
			(pads allowed)
			(copperpour not_allowed)
			(footprints allowed)
		)
		(placement
			(enabled no)
			(sheetname "")
		)
		(fill yes
			(thermal_gap 0.5)
			(thermal_bridge_width 0.5)
			(island_removal_mode 0)
		)
		(polygon
			(pts
				(arc
					(start 270.417798 -261.271512)
					(mid 270.432677 -261.307433)
					(end 270.468598 -261.322312)
				)
				(arc
					(start 271.868138 -261.322312)
					(mid 271.904059 -261.307433)
					(end 271.918938 -261.271512)
				)
				(arc
					(start 271.918938 -260.862572)
					(mid 271.904059 -260.826651)
					(end 271.868138 -260.811772)
				)
				(arc
					(start 270.468598 -260.811772)
					(mid 270.432677 -260.826651)
					(end 270.417798 -260.862572)
				)
			)
		)
	)
	(zone
		(layers "In1.Cu" "In2.Cu")
		(hatch none 0.5)
		(connect_pads
			(clearance 0)
		)
		(min_thickness 0.25)
		(keepout
			(tracks not_allowed)
			(vias allowed)
			(pads allowed)
			(copperpour not_allowed)
			(footprints allowed)
		)
		(placement
			(enabled no)
			(sheetname "")
		)
		(fill yes
			(thermal_gap 0.5)
			(thermal_bridge_width 0.5)
			(island_removal_mode 0)
		)
		(polygon
			(pts
				(arc
					(start 37.56533 -274.871434)
					(mid 37.580209 -274.907355)
					(end 37.61613 -274.922234)
				)
				(arc
					(start 39.01567 -274.922234)
					(mid 39.051591 -274.907355)
					(end 39.06647 -274.871434)
				)
				(arc
					(start 39.06647 -274.462494)
					(mid 39.051591 -274.426573)
					(end 39.01567 -274.411694)
				)
				(arc
					(start 37.61613 -274.411694)
					(mid 37.580209 -274.426573)
					(end 37.56533 -274.462494)
				)
			)
		)
	)
	(zone
		(layers "In1.Cu" "In2.Cu")
		(hatch none 0.5)
		(connect_pads
			(clearance 0)
		)
		(min_thickness 0.25)
		(keepout
			(tracks not_allowed)
			(vias allowed)
			(pads allowed)
			(copperpour not_allowed)
			(footprints allowed)
		)
		(placement
			(enabled no)
			(sheetname "")
		)
		(fill yes
			(thermal_gap 0.5)
			(thermal_bridge_width 0.5)
			(island_removal_mode 0)
		)
		(polygon
			(pts
				(arc
					(start 312.236866 -218.77147)
					(mid 312.251745 -218.807391)
					(end 312.287666 -218.82227)
				)
				(arc
					(start 313.687206 -218.82227)
					(mid 313.723127 -218.807391)
					(end 313.738006 -218.77147)
				)
				(arc
					(start 313.738006 -218.36253)
					(mid 313.723127 -218.326609)
					(end 313.687206 -218.31173)
				)
				(arc
					(start 312.287666 -218.31173)
					(mid 312.251745 -218.326609)
					(end 312.236866 -218.36253)
				)
			)
		)
	)
	(zone
		(layers "In1.Cu" "In2.Cu")
		(hatch none 0.5)
		(connect_pads
			(clearance 0)
		)
		(min_thickness 0.25)
		(keepout
			(tracks not_allowed)
			(vias allowed)
			(pads allowed)
			(copperpour not_allowed)
			(footprints allowed)
		)
		(placement
			(enabled no)
			(sheetname "")
		)
		(fill yes
			(thermal_gap 0.5)
			(thermal_bridge_width 0.5)
			(island_removal_mode 0)
		)
		(polygon
			(pts
				(arc
					(start 195.78193 -301.221394)
					(mid 195.796809 -301.257315)
					(end 195.83273 -301.272194)
				)
				(arc
					(start 197.23227 -301.272194)
					(mid 197.268191 -301.257315)
					(end 197.28307 -301.221394)
				)
				(arc
					(start 197.28307 -300.812454)
					(mid 197.268191 -300.776533)
					(end 197.23227 -300.761654)
				)
				(arc
					(start 195.83273 -300.761654)
					(mid 195.796809 -300.776533)
					(end 195.78193 -300.812454)
				)
			)
		)
	)
	(zone
		(layers "In1.Cu" "In2.Cu")
		(hatch none 0.5)
		(connect_pads
			(clearance 0)
		)
		(min_thickness 0.25)
		(keepout
			(tracks not_allowed)
			(vias allowed)
			(pads allowed)
			(copperpour not_allowed)
			(footprints allowed)
		)
		(placement
			(enabled no)
			(sheetname "")
		)
		(fill yes
			(thermal_gap 0.5)
			(thermal_bridge_width 0.5)
			(island_removal_mode 0)
		)
		(polygon
			(pts
				(arc
					(start 428.634398 -307.171344)
					(mid 428.649277 -307.207265)
					(end 428.685198 -307.222144)
				)
				(arc
					(start 430.084738 -307.222144)
					(mid 430.120659 -307.207265)
					(end 430.135538 -307.171344)
				)
				(arc
					(start 430.135538 -306.762404)
					(mid 430.120659 -306.726483)
					(end 430.084738 -306.711604)
				)
				(arc
					(start 428.685198 -306.711604)
					(mid 428.649277 -306.726483)
					(end 428.634398 -306.762404)
				)
			)
		)
	)
	(zone
		(layers "In1.Cu" "In2.Cu")
		(hatch none 0.5)
		(connect_pads
			(clearance 0)
		)
		(min_thickness 0.25)
		(keepout
			(tracks not_allowed)
			(vias allowed)
			(pads allowed)
			(copperpour not_allowed)
			(footprints allowed)
		)
		(placement
			(enabled no)
			(sheetname "")
		)
		(fill yes
			(thermal_gap 0.5)
			(thermal_bridge_width 0.5)
			(island_removal_mode 0)
		)
		(polygon
			(pts
				(arc
					(start 274.517866 -197.521322)
					(mid 274.532745 -197.557243)
					(end 274.568666 -197.572122)
				)
				(arc
					(start 275.968206 -197.572122)
					(mid 276.004127 -197.557243)
					(end 276.019006 -197.521322)
				)
				(arc
					(start 276.019006 -197.112382)
					(mid 276.004127 -197.076461)
					(end 275.968206 -197.061582)
				)
				(arc
					(start 274.568666 -197.061582)
					(mid 274.532745 -197.076461)
					(end 274.517866 -197.112382)
				)
			)
		)
	)
	(zone
		(layers "In1.Cu" "In2.Cu")
		(hatch none 0.5)
		(connect_pads
			(clearance 0)
		)
		(min_thickness 0.25)
		(keepout
			(tracks not_allowed)
			(vias allowed)
			(pads allowed)
			(copperpour not_allowed)
			(footprints allowed)
		)
		(placement
			(enabled no)
			(sheetname "")
		)
		(fill yes
			(thermal_gap 0.5)
			(thermal_bridge_width 0.5)
			(island_removal_mode 0)
		)
		(polygon
			(pts
				(arc
					(start 255.330198 -274.871434)
					(mid 255.345077 -274.907355)
					(end 255.380998 -274.922234)
				)
				(arc
					(start 256.780538 -274.922234)
					(mid 256.816459 -274.907355)
					(end 256.831338 -274.871434)
				)
				(arc
					(start 256.831338 -274.462494)
					(mid 256.816459 -274.426573)
					(end 256.780538 -274.411694)
				)
				(arc
					(start 255.380998 -274.411694)
					(mid 255.345077 -274.426573)
					(end 255.330198 -274.462494)
				)
			)
		)
	)
	(zone
		(layers "In1.Cu" "In2.Cu")
		(hatch none 0.5)
		(connect_pads
			(clearance 0)
		)
		(min_thickness 0.25)
		(keepout
			(tracks not_allowed)
			(vias allowed)
			(pads allowed)
			(copperpour not_allowed)
			(footprints allowed)
		)
		(placement
			(enabled no)
			(sheetname "")
		)
		(fill yes
			(thermal_gap 0.5)
			(thermal_bridge_width 0.5)
			(island_removal_mode 0)
		)
		(polygon
			(pts
				(arc
					(start 207.425798 -284.221428)
					(mid 207.440677 -284.257349)
					(end 207.476598 -284.272228)
				)
				(arc
					(start 208.876138 -284.272228)
					(mid 208.912059 -284.257349)
					(end 208.926938 -284.221428)
				)
				(arc
					(start 208.926938 -283.812488)
					(mid 208.912059 -283.776567)
					(end 208.876138 -283.761688)
				)
				(arc
					(start 207.476598 -283.761688)
					(mid 207.440677 -283.776567)
					(end 207.425798 -283.812488)
				)
			)
		)
	)
	(zone
		(layers "In1.Cu" "In2.Cu")
		(hatch none 0.5)
		(connect_pads
			(clearance 0)
		)
		(min_thickness 0.25)
		(keepout
			(tracks not_allowed)
			(vias allowed)
			(pads allowed)
			(copperpour not_allowed)
			(footprints allowed)
		)
		(placement
			(enabled no)
			(sheetname "")
		)
		(fill yes
			(thermal_gap 0.5)
			(thermal_bridge_width 0.5)
			(island_removal_mode 0)
		)
		(polygon
			(pts
				(arc
					(start 300.592998 -211.971382)
					(mid 300.607877 -212.007303)
					(end 300.643798 -212.022182)
				)
				(arc
					(start 302.043338 -212.022182)
					(mid 302.079259 -212.007303)
					(end 302.094138 -211.971382)
				)
				(arc
					(start 302.094138 -211.562442)
					(mid 302.079259 -211.526521)
					(end 302.043338 -211.511642)
				)
				(arc
					(start 300.643798 -211.511642)
					(mid 300.607877 -211.526521)
					(end 300.592998 -211.562442)
				)
			)
		)
	)
	(zone
		(layers "In1.Cu" "In2.Cu")
		(hatch none 0.5)
		(connect_pads
			(clearance 0)
		)
		(min_thickness 0.25)
		(keepout
			(tracks not_allowed)
			(vias allowed)
			(pads allowed)
			(copperpour not_allowed)
			(footprints allowed)
		)
		(placement
			(enabled no)
			(sheetname "")
		)
		(fill yes
			(thermal_gap 0.5)
			(thermal_bridge_width 0.5)
			(island_removal_mode 0)
		)
		(polygon
			(pts
				(arc
					(start 308.136798 -291.8714)
					(mid 308.151677 -291.907321)
					(end 308.187598 -291.9222)
				)
				(arc
					(start 309.587138 -291.9222)
					(mid 309.623059 -291.907321)
					(end 309.637938 -291.8714)
				)
				(arc
					(start 309.637938 -291.46246)
					(mid 309.623059 -291.426539)
					(end 309.587138 -291.41166)
				)
				(arc
					(start 308.187598 -291.41166)
					(mid 308.151677 -291.426539)
					(end 308.136798 -291.46246)
				)
			)
		)
	)
	(zone
		(layers "In1.Cu" "In2.Cu")
		(hatch none 0.5)
		(connect_pads
			(clearance 0)
		)
		(min_thickness 0.25)
		(keepout
			(tracks not_allowed)
			(vias allowed)
			(pads allowed)
			(copperpour not_allowed)
			(footprints allowed)
		)
		(placement
			(enabled no)
			(sheetname "")
		)
		(fill yes
			(thermal_gap 0.5)
			(thermal_bridge_width 0.5)
			(island_removal_mode 0)
		)
		(polygon
			(pts
				(arc
					(start 417.646866 -278.271478)
					(mid 417.661745 -278.307399)
					(end 417.697666 -278.322278)
				)
				(arc
					(start 419.097206 -278.322278)
					(mid 419.133127 -278.307399)
					(end 419.148006 -278.271478)
				)
				(arc
					(start 419.148006 -277.862538)
					(mid 419.133127 -277.826617)
					(end 419.097206 -277.811738)
				)
				(arc
					(start 417.697666 -277.811738)
					(mid 417.661745 -277.826617)
					(end 417.646866 -277.862538)
				)
			)
		)
	)
	(zone
		(layers "In1.Cu" "In2.Cu")
		(hatch none 0.5)
		(connect_pads
			(clearance 0)
		)
		(min_thickness 0.25)
		(keepout
			(tracks not_allowed)
			(vias allowed)
			(pads allowed)
			(copperpour not_allowed)
			(footprints allowed)
		)
		(placement
			(enabled no)
			(sheetname "")
		)
		(fill yes
			(thermal_gap 0.5)
			(thermal_bridge_width 0.5)
			(island_removal_mode 0)
		)
		(polygon
			(pts
				(arc
					(start 203.32573 -204.32141)
					(mid 203.340609 -204.357331)
					(end 203.37653 -204.37221)
				)
				(arc
					(start 204.77607 -204.37221)
					(mid 204.811991 -204.357331)
					(end 204.82687 -204.32141)
				)
				(arc
					(start 204.82687 -203.91247)
					(mid 204.811991 -203.876549)
					(end 204.77607 -203.86167)
				)
				(arc
					(start 203.37653 -203.86167)
					(mid 203.340609 -203.876549)
					(end 203.32573 -203.91247)
				)
			)
		)
	)
	(zone
		(layers "In1.Cu" "In2.Cu")
		(hatch none 0.5)
		(connect_pads
			(clearance 0)
		)
		(min_thickness 0.25)
		(keepout
			(tracks not_allowed)
			(vias allowed)
			(pads allowed)
			(copperpour not_allowed)
			(footprints allowed)
		)
		(placement
			(enabled no)
			(sheetname "")
		)
		(fill yes
			(thermal_gap 0.5)
			(thermal_bridge_width 0.5)
			(island_removal_mode 0)
		)
		(polygon
			(pts
				(arc
					(start 22.47773 -202.621388)
					(mid 22.492609 -202.657309)
					(end 22.52853 -202.672188)
				)
				(arc
					(start 23.92807 -202.672188)
					(mid 23.963991 -202.657309)
					(end 23.97887 -202.621388)
				)
				(arc
					(start 23.97887 -202.212448)
					(mid 23.963991 -202.176527)
					(end 23.92807 -202.161648)
				)
				(arc
					(start 22.52853 -202.161648)
					(mid 22.492609 -202.176527)
					(end 22.47773 -202.212448)
				)
			)
		)
	)
	(zone
		(layers "In1.Cu" "In2.Cu")
		(hatch none 0.5)
		(connect_pads
			(clearance 0)
		)
		(min_thickness 0.25)
		(keepout
			(tracks not_allowed)
			(vias allowed)
			(pads allowed)
			(copperpour not_allowed)
			(footprints allowed)
		)
		(placement
			(enabled no)
			(sheetname "")
		)
		(fill yes
			(thermal_gap 0.5)
			(thermal_bridge_width 0.5)
			(island_removal_mode 0)
		)
		(polygon
			(pts
				(arc
					(start 277.961598 -202.621388)
					(mid 277.976477 -202.657309)
					(end 278.012398 -202.672188)
				)
				(arc
					(start 279.411938 -202.672188)
					(mid 279.447859 -202.657309)
					(end 279.462738 -202.621388)
				)
				(arc
					(start 279.462738 -202.212448)
					(mid 279.447859 -202.176527)
					(end 279.411938 -202.161648)
				)
				(arc
					(start 278.012398 -202.161648)
					(mid 277.976477 -202.176527)
					(end 277.961598 -202.212448)
				)
			)
		)
	)
	(zone
		(layers "In1.Cu" "In2.Cu")
		(hatch none 0.5)
		(connect_pads
			(clearance 0)
		)
		(min_thickness 0.25)
		(keepout
			(tracks not_allowed)
			(vias allowed)
			(pads allowed)
			(copperpour not_allowed)
			(footprints allowed)
		)
		(placement
			(enabled no)
			(sheetname "")
		)
		(fill yes
			(thermal_gap 0.5)
			(thermal_bridge_width 0.5)
			(island_removal_mode 0)
		)
		(polygon
			(pts
				(arc
					(start 455.365866 -295.271444)
					(mid 455.380745 -295.307365)
					(end 455.416666 -295.322244)
				)
				(arc
					(start 456.816206 -295.322244)
					(mid 456.852127 -295.307365)
					(end 456.867006 -295.271444)
				)
				(arc
					(start 456.867006 -294.862504)
					(mid 456.852127 -294.826583)
					(end 456.816206 -294.811704)
				)
				(arc
					(start 455.416666 -294.811704)
					(mid 455.380745 -294.826583)
					(end 455.365866 -294.862504)
				)
			)
		)
	)
	(zone
		(layers "In1.Cu" "In2.Cu")
		(hatch none 0.5)
		(connect_pads
			(clearance 0)
		)
		(min_thickness 0.25)
		(keepout
			(tracks not_allowed)
			(vias allowed)
			(pads allowed)
			(copperpour not_allowed)
			(footprints allowed)
		)
		(placement
			(enabled no)
			(sheetname "")
		)
		(fill yes
			(thermal_gap 0.5)
			(thermal_bridge_width 0.5)
			(island_removal_mode 0)
		)
		(polygon
			(pts
				(arc
					(start 440.278266 -291.021516)
					(mid 440.293145 -291.057437)
					(end 440.329066 -291.072316)
				)
				(arc
					(start 441.728606 -291.072316)
					(mid 441.764527 -291.057437)
					(end 441.779406 -291.021516)
				)
				(arc
					(start 441.779406 -290.612576)
					(mid 441.764527 -290.576655)
					(end 441.728606 -290.561776)
				)
				(arc
					(start 440.329066 -290.561776)
					(mid 440.293145 -290.576655)
					(end 440.278266 -290.612576)
				)
			)
		)
	)
	(zone
		(layers "In1.Cu" "In2.Cu")
		(hatch none 0.5)
		(connect_pads
			(clearance 0)
		)
		(min_thickness 0.25)
		(keepout
			(tracks not_allowed)
			(vias allowed)
			(pads allowed)
			(copperpour not_allowed)
			(footprints allowed)
		)
		(placement
			(enabled no)
			(sheetname "")
		)
		(fill yes
			(thermal_gap 0.5)
			(thermal_bridge_width 0.5)
			(island_removal_mode 0)
		)
		(polygon
			(pts
				(arc
					(start 282.061666 -240.871502)
					(mid 282.076545 -240.907423)
					(end 282.112466 -240.922302)
				)
				(arc
					(start 283.512006 -240.922302)
					(mid 283.547927 -240.907423)
					(end 283.562806 -240.871502)
				)
				(arc
					(start 283.562806 -240.462562)
					(mid 283.547927 -240.426641)
					(end 283.512006 -240.411762)
				)
				(arc
					(start 282.112466 -240.411762)
					(mid 282.076545 -240.426641)
					(end 282.061666 -240.462562)
				)
			)
		)
	)
	(zone
		(layers "In1.Cu" "In2.Cu")
		(hatch none 0.5)
		(connect_pads
			(clearance 0)
		)
		(min_thickness 0.25)
		(keepout
			(tracks not_allowed)
			(vias allowed)
			(pads allowed)
			(copperpour not_allowed)
			(footprints allowed)
		)
		(placement
			(enabled no)
			(sheetname "")
		)
		(fill yes
			(thermal_gap 0.5)
			(thermal_bridge_width 0.5)
			(island_removal_mode 0)
		)
		(polygon
			(pts
				(arc
					(start 11.490198 -267.221462)
					(mid 11.505077 -267.257383)
					(end 11.540998 -267.272262)
				)
				(arc
					(start 12.940538 -267.272262)
					(mid 12.976459 -267.257383)
					(end 12.991338 -267.221462)
				)
				(arc
					(start 12.991338 -266.812522)
					(mid 12.976459 -266.776601)
					(end 12.940538 -266.761722)
				)
				(arc
					(start 11.540998 -266.761722)
					(mid 11.505077 -266.776601)
					(end 11.490198 -266.812522)
				)
			)
		)
	)
	(zone
		(layers "In1.Cu" "In2.Cu")
		(hatch none 0.5)
		(connect_pads
			(clearance 0)
		)
		(min_thickness 0.25)
		(keepout
			(tracks not_allowed)
			(vias allowed)
			(pads allowed)
			(copperpour not_allowed)
			(footprints allowed)
		)
		(placement
			(enabled no)
			(sheetname "")
		)
		(fill yes
			(thermal_gap 0.5)
			(thermal_bridge_width 0.5)
			(island_removal_mode 0)
		)
		(polygon
			(pts
				(arc
					(start 34.121598 -216.22131)
					(mid 34.136477 -216.257231)
					(end 34.172398 -216.27211)
				)
				(arc
					(start 35.571938 -216.27211)
					(mid 35.607859 -216.257231)
					(end 35.622738 -216.22131)
				)
				(arc
					(start 35.622738 -215.81237)
					(mid 35.607859 -215.776449)
					(end 35.571938 -215.76157)
				)
				(arc
					(start 34.172398 -215.76157)
					(mid 34.136477 -215.776449)
					(end 34.121598 -215.81237)
				)
			)
		)
	)
	(zone
		(layers "In1.Cu" "In2.Cu")
		(hatch none 0.5)
		(connect_pads
			(clearance 0)
		)
		(min_thickness 0.25)
		(keepout
			(tracks not_allowed)
			(vias allowed)
			(pads allowed)
			(copperpour not_allowed)
			(footprints allowed)
		)
		(placement
			(enabled no)
			(sheetname "")
		)
		(fill yes
			(thermal_gap 0.5)
			(thermal_bridge_width 0.5)
			(island_removal_mode 0)
		)
		(polygon
			(pts
				(arc
					(start 188.23813 -217.071448)
					(mid 188.253009 -217.107369)
					(end 188.28893 -217.122248)
				)
				(arc
					(start 189.68847 -217.122248)
					(mid 189.724391 -217.107369)
					(end 189.73927 -217.071448)
				)
				(arc
					(start 189.73927 -216.662508)
					(mid 189.724391 -216.626587)
					(end 189.68847 -216.611708)
				)
				(arc
					(start 188.28893 -216.611708)
					(mid 188.253009 -216.626587)
					(end 188.23813 -216.662508)
				)
			)
		)
	)
	(zone
		(layers "In1.Cu" "In2.Cu")
		(hatch none 0.5)
		(connect_pads
			(clearance 0)
		)
		(min_thickness 0.25)
		(keepout
			(tracks not_allowed)
			(vias allowed)
			(pads allowed)
			(copperpour not_allowed)
			(footprints allowed)
		)
		(placement
			(enabled no)
			(sheetname "")
		)
		(fill yes
			(thermal_gap 0.5)
			(thermal_bridge_width 0.5)
			(island_removal_mode 0)
		)
		(polygon
			(pts
				(arc
					(start 165.60673 -219.621354)
					(mid 165.621609 -219.657275)
					(end 165.65753 -219.672154)
				)
				(arc
					(start 167.05707 -219.672154)
					(mid 167.092991 -219.657275)
					(end 167.10787 -219.621354)
				)
				(arc
					(start 167.10787 -219.212414)
					(mid 167.092991 -219.176493)
					(end 167.05707 -219.161614)
				)
				(arc
					(start 165.65753 -219.161614)
					(mid 165.621609 -219.176493)
					(end 165.60673 -219.212414)
				)
			)
		)
	)
	(zone
		(layers "In1.Cu" "In2.Cu")
		(hatch none 0.5)
		(connect_pads
			(clearance 0)
		)
		(min_thickness 0.25)
		(keepout
			(tracks not_allowed)
			(vias allowed)
			(pads allowed)
			(copperpour not_allowed)
			(footprints allowed)
		)
		(placement
			(enabled no)
			(sheetname "")
		)
		(fill yes
			(thermal_gap 0.5)
			(thermal_bridge_width 0.5)
			(island_removal_mode 0)
		)
		(polygon
			(pts
				(arc
					(start 49.209198 -289.321494)
					(mid 49.224077 -289.357415)
					(end 49.259998 -289.372294)
				)
				(arc
					(start 50.659538 -289.372294)
					(mid 50.695459 -289.357415)
					(end 50.710338 -289.321494)
				)
				(arc
					(start 50.710338 -288.912554)
					(mid 50.695459 -288.876633)
					(end 50.659538 -288.861754)
				)
				(arc
					(start 49.259998 -288.861754)
					(mid 49.224077 -288.876633)
					(end 49.209198 -288.912554)
				)
			)
		)
	)
	(zone
		(layers "In1.Cu" "In2.Cu")
		(hatch none 0.5)
		(connect_pads
			(clearance 0)
		)
		(min_thickness 0.25)
		(keepout
			(tracks not_allowed)
			(vias allowed)
			(pads allowed)
			(copperpour not_allowed)
			(footprints allowed)
		)
		(placement
			(enabled no)
			(sheetname "")
		)
		(fill yes
			(thermal_gap 0.5)
			(thermal_bridge_width 0.5)
			(island_removal_mode 0)
		)
		(polygon
			(pts
				(arc
					(start 49.209198 -220.471492)
					(mid 49.224077 -220.507413)
					(end 49.259998 -220.522292)
				)
				(arc
					(start 50.659538 -220.522292)
					(mid 50.695459 -220.507413)
					(end 50.710338 -220.471492)
				)
				(arc
					(start 50.710338 -220.062552)
					(mid 50.695459 -220.026631)
					(end 50.659538 -220.011752)
				)
				(arc
					(start 49.259998 -220.011752)
					(mid 49.224077 -220.026631)
					(end 49.209198 -220.062552)
				)
			)
		)
	)
	(zone
		(layers "In1.Cu" "In2.Cu")
		(hatch none 0.5)
		(connect_pads
			(clearance 0)
		)
		(min_thickness 0.25)
		(keepout
			(tracks not_allowed)
			(vias allowed)
			(pads allowed)
			(copperpour not_allowed)
			(footprints allowed)
		)
		(placement
			(enabled no)
			(sheetname "")
		)
		(fill yes
			(thermal_gap 0.5)
			(thermal_bridge_width 0.5)
			(island_removal_mode 0)
		)
		(polygon
			(pts
				(arc
					(start 443.721998 -274.871434)
					(mid 443.736877 -274.907355)
					(end 443.772798 -274.922234)
				)
				(arc
					(start 445.172338 -274.922234)
					(mid 445.208259 -274.907355)
					(end 445.223138 -274.871434)
				)
				(arc
					(start 445.223138 -274.462494)
					(mid 445.208259 -274.426573)
					(end 445.172338 -274.411694)
				)
				(arc
					(start 443.772798 -274.411694)
					(mid 443.736877 -274.426573)
					(end 443.721998 -274.462494)
				)
			)
		)
	)
	(zone
		(layers "In1.Cu" "In2.Cu")
		(hatch none 0.5)
		(connect_pads
			(clearance 0)
		)
		(min_thickness 0.25)
		(keepout
			(tracks not_allowed)
			(vias allowed)
			(pads allowed)
			(copperpour not_allowed)
			(footprints allowed)
		)
		(placement
			(enabled no)
			(sheetname "")
		)
		(fill yes
			(thermal_gap 0.5)
			(thermal_bridge_width 0.5)
			(island_removal_mode 0)
		)
		(polygon
			(pts
				(arc
					(start 440.278266 -246.821452)
					(mid 440.293145 -246.857373)
					(end 440.329066 -246.872252)
				)
				(arc
					(start 441.728606 -246.872252)
					(mid 441.764527 -246.857373)
					(end 441.779406 -246.821452)
				)
				(arc
					(start 441.779406 -246.412512)
					(mid 441.764527 -246.376591)
					(end 441.728606 -246.361712)
				)
				(arc
					(start 440.329066 -246.361712)
					(mid 440.293145 -246.376591)
					(end 440.278266 -246.412512)
				)
			)
		)
	)
	(zone
		(layers "In1.Cu" "In2.Cu")
		(hatch none 0.5)
		(connect_pads
			(clearance 0)
		)
		(min_thickness 0.25)
		(keepout
			(tracks not_allowed)
			(vias allowed)
			(pads allowed)
			(copperpour not_allowed)
			(footprints allowed)
		)
		(placement
			(enabled no)
			(sheetname "")
		)
		(fill yes
			(thermal_gap 0.5)
			(thermal_bridge_width 0.5)
			(island_removal_mode 0)
		)
		(polygon
			(pts
				(arc
					(start 428.634398 -230.67137)
					(mid 428.649277 -230.707291)
					(end 428.685198 -230.72217)
				)
				(arc
					(start 430.084738 -230.72217)
					(mid 430.120659 -230.707291)
					(end 430.135538 -230.67137)
				)
				(arc
					(start 430.135538 -230.26243)
					(mid 430.120659 -230.226509)
					(end 430.084738 -230.21163)
				)
				(arc
					(start 428.685198 -230.21163)
					(mid 428.649277 -230.226509)
					(end 428.634398 -230.26243)
				)
			)
		)
	)
	(zone
		(layers "In1.Cu" "In2.Cu")
		(hatch none 0.5)
		(connect_pads
			(clearance 0)
		)
		(min_thickness 0.25)
		(keepout
			(tracks not_allowed)
			(vias allowed)
			(pads allowed)
			(copperpour not_allowed)
			(footprints allowed)
		)
		(placement
			(enabled no)
			(sheetname "")
		)
		(fill yes
			(thermal_gap 0.5)
			(thermal_bridge_width 0.5)
			(island_removal_mode 0)
		)
		(polygon
			(pts
				(arc
					(start 188.23813 -301.221394)
					(mid 188.253009 -301.257315)
					(end 188.28893 -301.272194)
				)
				(arc
					(start 189.68847 -301.272194)
					(mid 189.724391 -301.257315)
					(end 189.73927 -301.221394)
				)
				(arc
					(start 189.73927 -300.812454)
					(mid 189.724391 -300.776533)
					(end 189.68847 -300.761654)
				)
				(arc
					(start 188.28893 -300.761654)
					(mid 188.253009 -300.776533)
					(end 188.23813 -300.812454)
				)
			)
		)
	)
	(zone
		(layers "In1.Cu" "In2.Cu")
		(hatch none 0.5)
		(connect_pads
			(clearance 0)
		)
		(min_thickness 0.25)
		(keepout
			(tracks not_allowed)
			(vias allowed)
			(pads allowed)
			(copperpour not_allowed)
			(footprints allowed)
		)
		(placement
			(enabled no)
			(sheetname "")
		)
		(fill yes
			(thermal_gap 0.5)
			(thermal_bridge_width 0.5)
			(island_removal_mode 0)
		)
		(polygon
			(pts
				(arc
					(start 30.02153 -285.071312)
					(mid 30.036409 -285.107233)
					(end 30.07233 -285.122112)
				)
				(arc
					(start 31.47187 -285.122112)
					(mid 31.507791 -285.107233)
					(end 31.52267 -285.071312)
				)
				(arc
					(start 31.52267 -284.662372)
					(mid 31.507791 -284.626451)
					(end 31.47187 -284.611572)
				)
				(arc
					(start 30.07233 -284.611572)
					(mid 30.036409 -284.626451)
					(end 30.02153 -284.662372)
				)
			)
		)
	)
	(zone
		(layers "In1.Cu" "In2.Cu")
		(hatch none 0.5)
		(connect_pads
			(clearance 0)
		)
		(min_thickness 0.25)
		(keepout
			(tracks not_allowed)
			(vias allowed)
			(pads allowed)
			(copperpour not_allowed)
			(footprints allowed)
		)
		(placement
			(enabled no)
			(sheetname "")
		)
		(fill yes
			(thermal_gap 0.5)
			(thermal_bridge_width 0.5)
			(island_removal_mode 0)
		)
		(polygon
			(pts
				(arc
					(start 417.646866 -315.671454)
					(mid 417.661745 -315.707375)
					(end 417.697666 -315.722254)
				)
				(arc
					(start 419.097206 -315.722254)
					(mid 419.133127 -315.707375)
					(end 419.148006 -315.671454)
				)
				(arc
					(start 419.148006 -315.262514)
					(mid 419.133127 -315.226593)
					(end 419.097206 -315.211714)
				)
				(arc
					(start 417.697666 -315.211714)
					(mid 417.661745 -315.226593)
					(end 417.646866 -315.262514)
				)
			)
		)
	)
	(zone
		(layers "In1.Cu" "In2.Cu")
		(hatch none 0.5)
		(connect_pads
			(clearance 0)
		)
		(min_thickness 0.25)
		(keepout
			(tracks not_allowed)
			(vias allowed)
			(pads allowed)
			(copperpour not_allowed)
			(footprints allowed)
		)
		(placement
			(enabled no)
			(sheetname "")
		)
		(fill yes
			(thermal_gap 0.5)
			(thermal_bridge_width 0.5)
			(island_removal_mode 0)
		)
		(polygon
			(pts
				(arc
					(start 169.706798 -251.921518)
					(mid 169.721677 -251.957439)
					(end 169.757598 -251.972318)
				)
				(arc
					(start 171.157138 -251.972318)
					(mid 171.193059 -251.957439)
					(end 171.207938 -251.921518)
				)
				(arc
					(start 171.207938 -251.512578)
					(mid 171.193059 -251.476657)
					(end 171.157138 -251.461778)
				)
				(arc
					(start 169.757598 -251.461778)
					(mid 169.721677 -251.476657)
					(end 169.706798 -251.512578)
				)
			)
		)
	)
	(zone
		(layers "In1.Cu" "In2.Cu")
		(hatch none 0.5)
		(connect_pads
			(clearance 0)
		)
		(min_thickness 0.25)
		(keepout
			(tracks not_allowed)
			(vias allowed)
			(pads allowed)
			(copperpour not_allowed)
			(footprints allowed)
		)
		(placement
			(enabled no)
			(sheetname "")
		)
		(fill yes
			(thermal_gap 0.5)
			(thermal_bridge_width 0.5)
			(island_removal_mode 0)
		)
		(polygon
			(pts
				(arc
					(start 45.10913 -299.521372)
					(mid 45.124009 -299.557293)
					(end 45.15993 -299.572172)
				)
				(arc
					(start 46.55947 -299.572172)
					(mid 46.595391 -299.557293)
					(end 46.61027 -299.521372)
				)
				(arc
					(start 46.61027 -299.112432)
					(mid 46.595391 -299.076511)
					(end 46.55947 -299.061632)
				)
				(arc
					(start 45.15993 -299.061632)
					(mid 45.124009 -299.076511)
					(end 45.10913 -299.112432)
				)
			)
		)
	)
	(zone
		(layers "In1.Cu" "In2.Cu")
		(hatch none 0.5)
		(connect_pads
			(clearance 0)
		)
		(min_thickness 0.25)
		(keepout
			(tracks not_allowed)
			(vias allowed)
			(pads allowed)
			(copperpour not_allowed)
			(footprints allowed)
		)
		(placement
			(enabled no)
			(sheetname "")
		)
		(fill yes
			(thermal_gap 0.5)
			(thermal_bridge_width 0.5)
			(island_removal_mode 0)
		)
		(polygon
			(pts
				(arc
					(start 277.961598 -274.871434)
					(mid 277.976477 -274.907355)
					(end 278.012398 -274.922234)
				)
				(arc
					(start 279.411938 -274.922234)
					(mid 279.447859 -274.907355)
					(end 279.462738 -274.871434)
				)
				(arc
					(start 279.462738 -274.462494)
					(mid 279.447859 -274.426573)
					(end 279.411938 -274.411694)
				)
				(arc
					(start 278.012398 -274.411694)
					(mid 277.976477 -274.426573)
					(end 277.961598 -274.462494)
				)
			)
		)
	)
	(zone
		(layers "In1.Cu" "In2.Cu")
		(hatch none 0.5)
		(connect_pads
			(clearance 0)
		)
		(min_thickness 0.25)
		(keepout
			(tracks not_allowed)
			(vias allowed)
			(pads allowed)
			(copperpour not_allowed)
			(footprints allowed)
		)
		(placement
			(enabled no)
			(sheetname "")
		)
		(fill yes
			(thermal_gap 0.5)
			(thermal_bridge_width 0.5)
			(island_removal_mode 0)
		)
		(polygon
			(pts
				(arc
					(start 410.103066 -237.471458)
					(mid 410.117945 -237.507379)
					(end 410.153866 -237.522258)
				)
				(arc
					(start 411.553406 -237.522258)
					(mid 411.589327 -237.507379)
					(end 411.604206 -237.471458)
				)
				(arc
					(start 411.604206 -237.062518)
					(mid 411.589327 -237.026597)
					(end 411.553406 -237.011718)
				)
				(arc
					(start 410.153866 -237.011718)
					(mid 410.117945 -237.026597)
					(end 410.103066 -237.062518)
				)
			)
		)
	)
	(zone
		(layers "In1.Cu" "In2.Cu")
		(hatch none 0.5)
		(connect_pads
			(clearance 0)
		)
		(min_thickness 0.25)
		(keepout
			(tracks not_allowed)
			(vias allowed)
			(pads allowed)
			(copperpour not_allowed)
			(footprints allowed)
		)
		(placement
			(enabled no)
			(sheetname "")
		)
		(fill yes
			(thermal_gap 0.5)
			(thermal_bridge_width 0.5)
			(island_removal_mode 0)
		)
		(polygon
			(pts
				(arc
					(start 56.752998 -229.821486)
					(mid 56.767877 -229.857407)
					(end 56.803798 -229.872286)
				)
				(arc
					(start 58.203338 -229.872286)
					(mid 58.239259 -229.857407)
					(end 58.254138 -229.821486)
				)
				(arc
					(start 58.254138 -229.412546)
					(mid 58.239259 -229.376625)
					(end 58.203338 -229.361746)
				)
				(arc
					(start 56.803798 -229.361746)
					(mid 56.767877 -229.376625)
					(end 56.752998 -229.412546)
				)
			)
		)
	)
	(zone
		(layers "In1.Cu" "In2.Cu")
		(hatch none 0.5)
		(connect_pads
			(clearance 0)
		)
		(min_thickness 0.25)
		(keepout
			(tracks not_allowed)
			(vias allowed)
			(pads allowed)
			(copperpour not_allowed)
			(footprints allowed)
		)
		(placement
			(enabled no)
			(sheetname "")
		)
		(fill yes
			(thermal_gap 0.5)
			(thermal_bridge_width 0.5)
			(island_removal_mode 0)
		)
		(polygon
			(pts
				(arc
					(start 41.665398 -223.871536)
					(mid 41.680277 -223.907457)
					(end 41.716198 -223.922336)
				)
				(arc
					(start 43.115738 -223.922336)
					(mid 43.151659 -223.907457)
					(end 43.166538 -223.871536)
				)
				(arc
					(start 43.166538 -223.462596)
					(mid 43.151659 -223.426675)
					(end 43.115738 -223.411796)
				)
				(arc
					(start 41.716198 -223.411796)
					(mid 41.680277 -223.426675)
					(end 41.665398 -223.462596)
				)
			)
		)
	)
	(zone
		(layers "In1.Cu" "In2.Cu")
		(hatch none 0.5)
		(connect_pads
			(clearance 0)
		)
		(min_thickness 0.25)
		(keepout
			(tracks not_allowed)
			(vias allowed)
			(pads allowed)
			(copperpour not_allowed)
			(footprints allowed)
		)
		(placement
			(enabled no)
			(sheetname "")
		)
		(fill yes
			(thermal_gap 0.5)
			(thermal_bridge_width 0.5)
			(island_removal_mode 0)
		)
		(polygon
			(pts
				(arc
					(start 308.136798 -269.771368)
					(mid 308.151677 -269.807289)
					(end 308.187598 -269.822168)
				)
				(arc
					(start 309.587138 -269.822168)
					(mid 309.623059 -269.807289)
					(end 309.637938 -269.771368)
				)
				(arc
					(start 309.637938 -269.362428)
					(mid 309.623059 -269.326507)
					(end 309.587138 -269.311628)
				)
				(arc
					(start 308.187598 -269.311628)
					(mid 308.151677 -269.326507)
					(end 308.136798 -269.362428)
				)
			)
		)
	)
	(zone
		(layers "In1.Cu" "In2.Cu")
		(hatch none 0.5)
		(connect_pads
			(clearance 0)
		)
		(min_thickness 0.25)
		(keepout
			(tracks not_allowed)
			(vias allowed)
			(pads allowed)
			(copperpour not_allowed)
			(footprints allowed)
		)
		(placement
			(enabled no)
			(sheetname "")
		)
		(fill yes
			(thermal_gap 0.5)
			(thermal_bridge_width 0.5)
			(island_removal_mode 0)
		)
		(polygon
			(pts
				(arc
					(start 162.162998 -223.871536)
					(mid 162.177877 -223.907457)
					(end 162.213798 -223.922336)
				)
				(arc
					(start 163.613338 -223.922336)
					(mid 163.649259 -223.907457)
					(end 163.664138 -223.871536)
				)
				(arc
					(start 163.664138 -223.462596)
					(mid 163.649259 -223.426675)
					(end 163.613338 -223.411796)
				)
				(arc
					(start 162.213798 -223.411796)
					(mid 162.177877 -223.426675)
					(end 162.162998 -223.462596)
				)
			)
		)
	)
	(zone
		(layers "In1.Cu" "In2.Cu")
		(hatch none 0.5)
		(connect_pads
			(clearance 0)
		)
		(min_thickness 0.25)
		(keepout
			(tracks not_allowed)
			(vias allowed)
			(pads allowed)
			(copperpour not_allowed)
			(footprints allowed)
		)
		(placement
			(enabled no)
			(sheetname "")
		)
		(fill yes
			(thermal_gap 0.5)
			(thermal_bridge_width 0.5)
			(island_removal_mode 0)
		)
		(polygon
			(pts
				(arc
					(start 458.809598 -209.421476)
					(mid 458.824477 -209.457397)
					(end 458.860398 -209.472276)
				)
				(arc
					(start 460.259938 -209.472276)
					(mid 460.295859 -209.457397)
					(end 460.310738 -209.421476)
				)
				(arc
					(start 460.310738 -209.012536)
					(mid 460.295859 -208.976615)
					(end 460.259938 -208.961736)
				)
				(arc
					(start 458.860398 -208.961736)
					(mid 458.824477 -208.976615)
					(end 458.809598 -209.012536)
				)
			)
		)
	)
	(zone
		(layers "In1.Cu" "In2.Cu")
		(hatch none 0.5)
		(connect_pads
			(clearance 0)
		)
		(min_thickness 0.25)
		(keepout
			(tracks not_allowed)
			(vias allowed)
			(pads allowed)
			(copperpour not_allowed)
			(footprints allowed)
		)
		(placement
			(enabled no)
			(sheetname "")
		)
		(fill yes
			(thermal_gap 0.5)
			(thermal_bridge_width 0.5)
			(island_removal_mode 0)
		)
		(polygon
			(pts
				(arc
					(start 297.149266 -206.871316)
					(mid 297.164145 -206.907237)
					(end 297.200066 -206.922116)
				)
				(arc
					(start 298.599606 -206.922116)
					(mid 298.635527 -206.907237)
					(end 298.650406 -206.871316)
				)
				(arc
					(start 298.650406 -206.462376)
					(mid 298.635527 -206.426455)
					(end 298.599606 -206.411576)
				)
				(arc
					(start 297.200066 -206.411576)
					(mid 297.164145 -206.426455)
					(end 297.149266 -206.462376)
				)
			)
		)
	)
	(zone
		(layers "In1.Cu" "In2.Cu")
		(hatch none 0.5)
		(connect_pads
			(clearance 0)
		)
		(min_thickness 0.25)
		(keepout
			(tracks not_allowed)
			(vias allowed)
			(pads allowed)
			(copperpour not_allowed)
			(footprints allowed)
		)
		(placement
			(enabled no)
			(sheetname "")
		)
		(fill yes
			(thermal_gap 0.5)
			(thermal_bridge_width 0.5)
			(island_removal_mode 0)
		)
		(polygon
			(pts
				(arc
					(start 207.425798 -267.221462)
					(mid 207.440677 -267.257383)
					(end 207.476598 -267.272262)
				)
				(arc
					(start 208.876138 -267.272262)
					(mid 208.912059 -267.257383)
					(end 208.926938 -267.221462)
				)
				(arc
					(start 208.926938 -266.812522)
					(mid 208.912059 -266.776601)
					(end 208.876138 -266.761722)
				)
				(arc
					(start 207.476598 -266.761722)
					(mid 207.440677 -266.776601)
					(end 207.425798 -266.812522)
				)
			)
		)
	)
	(zone
		(layers "In1.Cu" "In2.Cu")
		(hatch none 0.5)
		(connect_pads
			(clearance 0)
		)
		(min_thickness 0.25)
		(keepout
			(tracks not_allowed)
			(vias allowed)
			(pads allowed)
			(copperpour not_allowed)
			(footprints allowed)
		)
		(placement
			(enabled no)
			(sheetname "")
		)
		(fill yes
			(thermal_gap 0.5)
			(thermal_bridge_width 0.5)
			(island_removal_mode 0)
		)
		(polygon
			(pts
				(arc
					(start 173.15053 -273.171412)
					(mid 173.165409 -273.207333)
					(end 173.20133 -273.222212)
				)
				(arc
					(start 174.60087 -273.222212)
					(mid 174.636791 -273.207333)
					(end 174.65167 -273.171412)
				)
				(arc
					(start 174.65167 -272.762472)
					(mid 174.636791 -272.726551)
					(end 174.60087 -272.711672)
				)
				(arc
					(start 173.20133 -272.711672)
					(mid 173.165409 -272.726551)
					(end 173.15053 -272.762472)
				)
			)
		)
	)
	(zone
		(layers "In1.Cu" "In2.Cu")
		(hatch none 0.5)
		(connect_pads
			(clearance 0)
		)
		(min_thickness 0.25)
		(keepout
			(tracks not_allowed)
			(vias allowed)
			(pads allowed)
			(copperpour not_allowed)
			(footprints allowed)
		)
		(placement
			(enabled no)
			(sheetname "")
		)
		(fill yes
			(thermal_gap 0.5)
			(thermal_bridge_width 0.5)
			(island_removal_mode 0)
		)
		(polygon
			(pts
				(arc
					(start 300.592998 -268.071346)
					(mid 300.607877 -268.107267)
					(end 300.643798 -268.122146)
				)
				(arc
					(start 302.043338 -268.122146)
					(mid 302.079259 -268.107267)
					(end 302.094138 -268.071346)
				)
				(arc
					(start 302.094138 -267.662406)
					(mid 302.079259 -267.626485)
					(end 302.043338 -267.611606)
				)
				(arc
					(start 300.643798 -267.611606)
					(mid 300.607877 -267.626485)
					(end 300.592998 -267.662406)
				)
			)
		)
	)
	(zone
		(layers "In1.Cu" "In2.Cu")
		(hatch none 0.5)
		(connect_pads
			(clearance 0)
		)
		(min_thickness 0.25)
		(keepout
			(tracks not_allowed)
			(vias allowed)
			(pads allowed)
			(copperpour not_allowed)
			(footprints allowed)
		)
		(placement
			(enabled no)
			(sheetname "")
		)
		(fill yes
			(thermal_gap 0.5)
			(thermal_bridge_width 0.5)
			(island_removal_mode 0)
		)
		(polygon
			(pts
				(arc
					(start 443.721998 -314.821316)
					(mid 443.736877 -314.857237)
					(end 443.772798 -314.872116)
				)
				(arc
					(start 445.172338 -314.872116)
					(mid 445.208259 -314.857237)
					(end 445.223138 -314.821316)
				)
				(arc
					(start 445.223138 -314.412376)
					(mid 445.208259 -314.376455)
					(end 445.172338 -314.361576)
				)
				(arc
					(start 443.772798 -314.361576)
					(mid 443.736877 -314.376455)
					(end 443.721998 -314.412376)
				)
			)
		)
	)
	(zone
		(layers "In1.Cu" "In2.Cu")
		(hatch none 0.5)
		(connect_pads
			(clearance 0)
		)
		(min_thickness 0.25)
		(keepout
			(tracks not_allowed)
			(vias allowed)
			(pads allowed)
			(copperpour not_allowed)
			(footprints allowed)
		)
		(placement
			(enabled no)
			(sheetname "")
		)
		(fill yes
			(thermal_gap 0.5)
			(thermal_bridge_width 0.5)
			(island_removal_mode 0)
		)
		(polygon
			(pts
				(arc
					(start 458.809598 -210.27136)
					(mid 458.824477 -210.307281)
					(end 458.860398 -210.32216)
				)
				(arc
					(start 460.259938 -210.32216)
					(mid 460.295859 -210.307281)
					(end 460.310738 -210.27136)
				)
				(arc
					(start 460.310738 -209.86242)
					(mid 460.295859 -209.826499)
					(end 460.259938 -209.81162)
				)
				(arc
					(start 458.860398 -209.81162)
					(mid 458.824477 -209.826499)
					(end 458.809598 -209.86242)
				)
			)
		)
	)
	(zone
		(layers "In1.Cu" "In2.Cu")
		(hatch none 0.5)
		(connect_pads
			(clearance 0)
		)
		(min_thickness 0.25)
		(keepout
			(tracks not_allowed)
			(vias allowed)
			(pads allowed)
			(copperpour not_allowed)
			(footprints allowed)
		)
		(placement
			(enabled no)
			(sheetname "")
		)
		(fill yes
			(thermal_gap 0.5)
			(thermal_bridge_width 0.5)
			(island_removal_mode 0)
		)
		(polygon
			(pts
				(arc
					(start 210.86953 -312.27141)
					(mid 210.884409 -312.307331)
					(end 210.92033 -312.32221)
				)
				(arc
					(start 212.31987 -312.32221)
					(mid 212.355791 -312.307331)
					(end 212.37067 -312.27141)
				)
				(arc
					(start 212.37067 -311.86247)
					(mid 212.355791 -311.826549)
					(end 212.31987 -311.81167)
				)
				(arc
					(start 210.92033 -311.81167)
					(mid 210.884409 -311.826549)
					(end 210.86953 -311.86247)
				)
			)
		)
	)
	(zone
		(layers "In1.Cu" "In2.Cu")
		(hatch none 0.5)
		(connect_pads
			(clearance 0)
		)
		(min_thickness 0.25)
		(keepout
			(tracks not_allowed)
			(vias allowed)
			(pads allowed)
			(copperpour not_allowed)
			(footprints allowed)
		)
		(placement
			(enabled no)
			(sheetname "")
		)
		(fill yes
			(thermal_gap 0.5)
			(thermal_bridge_width 0.5)
			(island_removal_mode 0)
		)
		(polygon
			(pts
				(arc
					(start 162.162998 -296.971466)
					(mid 162.177877 -297.007387)
					(end 162.213798 -297.022266)
				)
				(arc
					(start 163.613338 -297.022266)
					(mid 163.649259 -297.007387)
					(end 163.664138 -296.971466)
				)
				(arc
					(start 163.664138 -296.562526)
					(mid 163.649259 -296.526605)
					(end 163.613338 -296.511726)
				)
				(arc
					(start 162.213798 -296.511726)
					(mid 162.177877 -296.526605)
					(end 162.162998 -296.562526)
				)
			)
		)
	)
	(zone
		(layers "In1.Cu" "In2.Cu")
		(hatch none 0.5)
		(connect_pads
			(clearance 0)
		)
		(min_thickness 0.25)
		(keepout
			(tracks not_allowed)
			(vias allowed)
			(pads allowed)
			(copperpour not_allowed)
			(footprints allowed)
		)
		(placement
			(enabled no)
			(sheetname "")
		)
		(fill yes
			(thermal_gap 0.5)
			(thermal_bridge_width 0.5)
			(island_removal_mode 0)
		)
		(polygon
			(pts
				(arc
					(start 462.909666 -312.27141)
					(mid 462.924545 -312.307331)
					(end 462.960466 -312.32221)
				)
				(arc
					(start 464.360006 -312.32221)
					(mid 464.395927 -312.307331)
					(end 464.410806 -312.27141)
				)
				(arc
					(start 464.410806 -311.86247)
					(mid 464.395927 -311.826549)
					(end 464.360006 -311.81167)
				)
				(arc
					(start 462.960466 -311.81167)
					(mid 462.924545 -311.826549)
					(end 462.909666 -311.86247)
				)
			)
		)
	)
	(zone
		(layers "In1.Cu" "In2.Cu")
		(hatch none 0.5)
		(connect_pads
			(clearance 0)
		)
		(min_thickness 0.25)
		(keepout
			(tracks not_allowed)
			(vias allowed)
			(pads allowed)
			(copperpour not_allowed)
			(footprints allowed)
		)
		(placement
			(enabled no)
			(sheetname "")
		)
		(fill yes
			(thermal_gap 0.5)
			(thermal_bridge_width 0.5)
			(island_removal_mode 0)
		)
		(polygon
			(pts
				(arc
					(start 413.546798 -202.621388)
					(mid 413.561677 -202.657309)
					(end 413.597598 -202.672188)
				)
				(arc
					(start 414.997138 -202.672188)
					(mid 415.033059 -202.657309)
					(end 415.047938 -202.621388)
				)
				(arc
					(start 415.047938 -202.212448)
					(mid 415.033059 -202.176527)
					(end 414.997138 -202.161648)
				)
				(arc
					(start 413.597598 -202.161648)
					(mid 413.561677 -202.176527)
					(end 413.546798 -202.212448)
				)
			)
		)
	)
	(zone
		(layers "In1.Cu" "In2.Cu")
		(hatch none 0.5)
		(connect_pads
			(clearance 0)
		)
		(min_thickness 0.25)
		(keepout
			(tracks not_allowed)
			(vias allowed)
			(pads allowed)
			(copperpour not_allowed)
			(footprints allowed)
		)
		(placement
			(enabled no)
			(sheetname "")
		)
		(fill yes
			(thermal_gap 0.5)
			(thermal_bridge_width 0.5)
			(island_removal_mode 0)
		)
		(polygon
			(pts
				(arc
					(start 308.136798 -302.921416)
					(mid 308.151677 -302.957337)
					(end 308.187598 -302.972216)
				)
				(arc
					(start 309.587138 -302.972216)
					(mid 309.623059 -302.957337)
					(end 309.637938 -302.921416)
				)
				(arc
					(start 309.637938 -302.512476)
					(mid 309.623059 -302.476555)
					(end 309.587138 -302.461676)
				)
				(arc
					(start 308.187598 -302.461676)
					(mid 308.151677 -302.476555)
					(end 308.136798 -302.512476)
				)
			)
		)
	)
	(zone
		(layers "In1.Cu" "In2.Cu")
		(hatch none 0.5)
		(connect_pads
			(clearance 0)
		)
		(min_thickness 0.25)
		(keepout
			(tracks not_allowed)
			(vias allowed)
			(pads allowed)
			(copperpour not_allowed)
			(footprints allowed)
		)
		(placement
			(enabled no)
			(sheetname "")
		)
		(fill yes
			(thermal_gap 0.5)
			(thermal_bridge_width 0.5)
			(island_removal_mode 0)
		)
		(polygon
			(pts
				(arc
					(start 282.061666 -245.12143)
					(mid 282.076545 -245.157351)
					(end 282.112466 -245.17223)
				)
				(arc
					(start 283.512006 -245.17223)
					(mid 283.547927 -245.157351)
					(end 283.562806 -245.12143)
				)
				(arc
					(start 283.562806 -244.71249)
					(mid 283.547927 -244.676569)
					(end 283.512006 -244.66169)
				)
				(arc
					(start 282.112466 -244.66169)
					(mid 282.076545 -244.676569)
					(end 282.061666 -244.71249)
				)
			)
		)
	)
	(zone
		(layers "In1.Cu" "In2.Cu")
		(hatch none 0.5)
		(connect_pads
			(clearance 0)
		)
		(min_thickness 0.25)
		(keepout
			(tracks not_allowed)
			(vias allowed)
			(pads allowed)
			(copperpour not_allowed)
			(footprints allowed)
		)
		(placement
			(enabled no)
			(sheetname "")
		)
		(fill yes
			(thermal_gap 0.5)
			(thermal_bridge_width 0.5)
			(island_removal_mode 0)
		)
		(polygon
			(pts
				(arc
					(start 11.490198 -309.721504)
					(mid 11.505077 -309.757425)
					(end 11.540998 -309.772304)
				)
				(arc
					(start 12.940538 -309.772304)
					(mid 12.976459 -309.757425)
					(end 12.991338 -309.721504)
				)
				(arc
					(start 12.991338 -309.312564)
					(mid 12.976459 -309.276643)
					(end 12.940538 -309.261764)
				)
				(arc
					(start 11.540998 -309.261764)
					(mid 11.505077 -309.276643)
					(end 11.490198 -309.312564)
				)
			)
		)
	)
	(zone
		(layers "In1.Cu" "In2.Cu")
		(hatch none 0.5)
		(connect_pads
			(clearance 0)
		)
		(min_thickness 0.25)
		(keepout
			(tracks not_allowed)
			(vias allowed)
			(pads allowed)
			(copperpour not_allowed)
			(footprints allowed)
		)
		(placement
			(enabled no)
			(sheetname "")
		)
		(fill yes
			(thermal_gap 0.5)
			(thermal_bridge_width 0.5)
			(island_removal_mode 0)
		)
		(polygon
			(pts
				(arc
					(start 417.646866 -239.17148)
					(mid 417.661745 -239.207401)
					(end 417.697666 -239.22228)
				)
				(arc
					(start 419.097206 -239.22228)
					(mid 419.133127 -239.207401)
					(end 419.148006 -239.17148)
				)
				(arc
					(start 419.148006 -238.76254)
					(mid 419.133127 -238.726619)
					(end 419.097206 -238.71174)
				)
				(arc
					(start 417.697666 -238.71174)
					(mid 417.661745 -238.726619)
					(end 417.646866 -238.76254)
				)
			)
		)
	)
	(zone
		(layers "In1.Cu" "In2.Cu")
		(hatch none 0.5)
		(connect_pads
			(clearance 0)
		)
		(min_thickness 0.25)
		(keepout
			(tracks not_allowed)
			(vias allowed)
			(pads allowed)
			(copperpour not_allowed)
			(footprints allowed)
		)
		(placement
			(enabled no)
			(sheetname "")
		)
		(fill yes
			(thermal_gap 0.5)
			(thermal_bridge_width 0.5)
			(island_removal_mode 0)
		)
		(polygon
			(pts
				(arc
					(start 432.734466 -308.021482)
					(mid 432.749345 -308.057403)
					(end 432.785266 -308.072282)
				)
				(arc
					(start 434.184806 -308.072282)
					(mid 434.220727 -308.057403)
					(end 434.235606 -308.021482)
				)
				(arc
					(start 434.235606 -307.612542)
					(mid 434.220727 -307.576621)
					(end 434.184806 -307.561742)
				)
				(arc
					(start 432.785266 -307.561742)
					(mid 432.749345 -307.576621)
					(end 432.734466 -307.612542)
				)
			)
		)
	)
	(zone
		(layers "In1.Cu" "In2.Cu")
		(hatch none 0.5)
		(connect_pads
			(clearance 0)
		)
		(min_thickness 0.25)
		(keepout
			(tracks not_allowed)
			(vias allowed)
			(pads allowed)
			(copperpour not_allowed)
			(footprints allowed)
		)
		(placement
			(enabled no)
			(sheetname "")
		)
		(fill yes
			(thermal_gap 0.5)
			(thermal_bridge_width 0.5)
			(island_removal_mode 0)
		)
		(polygon
			(pts
				(arc
					(start 304.693066 -312.27141)
					(mid 304.707945 -312.307331)
					(end 304.743866 -312.32221)
				)
				(arc
					(start 306.143406 -312.32221)
					(mid 306.179327 -312.307331)
					(end 306.194206 -312.27141)
				)
				(arc
					(start 306.194206 -311.86247)
					(mid 306.179327 -311.826549)
					(end 306.143406 -311.81167)
				)
				(arc
					(start 304.743866 -311.81167)
					(mid 304.707945 -311.826549)
					(end 304.693066 -311.86247)
				)
			)
		)
	)
	(zone
		(layers "In1.Cu" "In2.Cu")
		(hatch none 0.5)
		(connect_pads
			(clearance 0)
		)
		(min_thickness 0.25)
		(keepout
			(tracks not_allowed)
			(vias allowed)
			(pads allowed)
			(copperpour not_allowed)
			(footprints allowed)
		)
		(placement
			(enabled no)
			(sheetname "")
		)
		(fill yes
			(thermal_gap 0.5)
			(thermal_bridge_width 0.5)
			(island_removal_mode 0)
		)
		(polygon
			(pts
				(arc
					(start 7.39013 -219.621354)
					(mid 7.405009 -219.657275)
					(end 7.44093 -219.672154)
				)
				(arc
					(start 8.84047 -219.672154)
					(mid 8.876391 -219.657275)
					(end 8.89127 -219.621354)
				)
				(arc
					(start 8.89127 -219.212414)
					(mid 8.876391 -219.176493)
					(end 8.84047 -219.161614)
				)
				(arc
					(start 7.44093 -219.161614)
					(mid 7.405009 -219.176493)
					(end 7.39013 -219.212414)
				)
			)
		)
	)
	(zone
		(layers "In1.Cu" "In2.Cu")
		(hatch none 0.5)
		(connect_pads
			(clearance 0)
		)
		(min_thickness 0.25)
		(keepout
			(tracks not_allowed)
			(vias allowed)
			(pads allowed)
			(copperpour not_allowed)
			(footprints allowed)
		)
		(placement
			(enabled no)
			(sheetname "")
		)
		(fill yes
			(thermal_gap 0.5)
			(thermal_bridge_width 0.5)
			(island_removal_mode 0)
		)
		(polygon
			(pts
				(arc
					(start 304.693066 -227.271326)
					(mid 304.707945 -227.307247)
					(end 304.743866 -227.322126)
				)
				(arc
					(start 306.143406 -227.322126)
					(mid 306.179327 -227.307247)
					(end 306.194206 -227.271326)
				)
				(arc
					(start 306.194206 -226.862386)
					(mid 306.179327 -226.826465)
					(end 306.143406 -226.811586)
				)
				(arc
					(start 304.743866 -226.811586)
					(mid 304.707945 -226.826465)
					(end 304.693066 -226.862386)
				)
			)
		)
	)
	(zone
		(layers "In1.Cu" "In2.Cu")
		(hatch none 0.5)
		(connect_pads
			(clearance 0)
		)
		(min_thickness 0.25)
		(keepout
			(tracks not_allowed)
			(vias allowed)
			(pads allowed)
			(copperpour not_allowed)
			(footprints allowed)
		)
		(placement
			(enabled no)
			(sheetname "")
		)
		(fill yes
			(thermal_gap 0.5)
			(thermal_bridge_width 0.5)
			(island_removal_mode 0)
		)
		(polygon
			(pts
				(arc
					(start 52.65293 -213.671404)
					(mid 52.667809 -213.707325)
					(end 52.70373 -213.722204)
				)
				(arc
					(start 54.10327 -213.722204)
					(mid 54.139191 -213.707325)
					(end 54.15407 -213.671404)
				)
				(arc
					(start 54.15407 -213.262464)
					(mid 54.139191 -213.226543)
					(end 54.10327 -213.211664)
				)
				(arc
					(start 52.70373 -213.211664)
					(mid 52.667809 -213.226543)
					(end 52.65293 -213.262464)
				)
			)
		)
	)
	(zone
		(layers "In1.Cu" "In2.Cu")
		(hatch none 0.5)
		(connect_pads
			(clearance 0)
		)
		(min_thickness 0.25)
		(keepout
			(tracks not_allowed)
			(vias allowed)
			(pads allowed)
			(copperpour not_allowed)
			(footprints allowed)
		)
		(placement
			(enabled no)
			(sheetname "")
		)
		(fill yes
			(thermal_gap 0.5)
			(thermal_bridge_width 0.5)
			(island_removal_mode 0)
		)
		(polygon
			(pts
				(arc
					(start 192.338198 -220.471492)
					(mid 192.353077 -220.507413)
					(end 192.388998 -220.522292)
				)
				(arc
					(start 193.788538 -220.522292)
					(mid 193.824459 -220.507413)
					(end 193.839338 -220.471492)
				)
				(arc
					(start 193.839338 -220.062552)
					(mid 193.824459 -220.026631)
					(end 193.788538 -220.011752)
				)
				(arc
					(start 192.388998 -220.011752)
					(mid 192.353077 -220.026631)
					(end 192.338198 -220.062552)
				)
			)
		)
	)
	(zone
		(layers "In1.Cu" "In2.Cu")
		(hatch none 0.5)
		(connect_pads
			(clearance 0)
		)
		(min_thickness 0.25)
		(keepout
			(tracks not_allowed)
			(vias allowed)
			(pads allowed)
			(copperpour not_allowed)
			(footprints allowed)
		)
		(placement
			(enabled no)
			(sheetname "")
		)
		(fill yes
			(thermal_gap 0.5)
			(thermal_bridge_width 0.5)
			(island_removal_mode 0)
		)
		(polygon
			(pts
				(arc
					(start 432.734466 -214.521542)
					(mid 432.749345 -214.557463)
					(end 432.785266 -214.572342)
				)
				(arc
					(start 434.184806 -214.572342)
					(mid 434.220727 -214.557463)
					(end 434.235606 -214.521542)
				)
				(arc
					(start 434.235606 -214.112602)
					(mid 434.220727 -214.076681)
					(end 434.184806 -214.061802)
				)
				(arc
					(start 432.785266 -214.061802)
					(mid 432.749345 -214.076681)
					(end 432.734466 -214.112602)
				)
			)
		)
	)
	(zone
		(layers "In1.Cu" "In2.Cu")
		(hatch none 0.5)
		(connect_pads
			(clearance 0)
		)
		(min_thickness 0.25)
		(keepout
			(tracks not_allowed)
			(vias allowed)
			(pads allowed)
			(copperpour not_allowed)
			(footprints allowed)
		)
		(placement
			(enabled no)
			(sheetname "")
		)
		(fill yes
			(thermal_gap 0.5)
			(thermal_bridge_width 0.5)
			(island_removal_mode 0)
		)
		(polygon
			(pts
				(arc
					(start 180.69433 -294.421306)
					(mid 180.709209 -294.457227)
					(end 180.74513 -294.472106)
				)
				(arc
					(start 182.14467 -294.472106)
					(mid 182.180591 -294.457227)
					(end 182.19547 -294.421306)
				)
				(arc
					(start 182.19547 -294.012366)
					(mid 182.180591 -293.976445)
					(end 182.14467 -293.961566)
				)
				(arc
					(start 180.74513 -293.961566)
					(mid 180.709209 -293.976445)
					(end 180.69433 -294.012366)
				)
			)
		)
	)
	(zone
		(layers "In1.Cu" "In2.Cu")
		(hatch none 0.5)
		(connect_pads
			(clearance 0)
		)
		(min_thickness 0.25)
		(keepout
			(tracks not_allowed)
			(vias allowed)
			(pads allowed)
			(copperpour not_allowed)
			(footprints allowed)
		)
		(placement
			(enabled no)
			(sheetname "")
		)
		(fill yes
			(thermal_gap 0.5)
			(thermal_bridge_width 0.5)
			(island_removal_mode 0)
		)
		(polygon
			(pts
				(arc
					(start 158.06293 -261.271512)
					(mid 158.077809 -261.307433)
					(end 158.11373 -261.322312)
				)
				(arc
					(start 159.51327 -261.322312)
					(mid 159.549191 -261.307433)
					(end 159.56407 -261.271512)
				)
				(arc
					(start 159.56407 -260.862572)
					(mid 159.549191 -260.826651)
					(end 159.51327 -260.811772)
				)
				(arc
					(start 158.11373 -260.811772)
					(mid 158.077809 -260.826651)
					(end 158.06293 -260.862572)
				)
			)
		)
	)
	(zone
		(layers "In1.Cu" "In2.Cu")
		(hatch none 0.5)
		(connect_pads
			(clearance 0)
		)
		(min_thickness 0.25)
		(keepout
			(tracks not_allowed)
			(vias allowed)
			(pads allowed)
			(copperpour not_allowed)
			(footprints allowed)
		)
		(placement
			(enabled no)
			(sheetname "")
		)
		(fill yes
			(thermal_gap 0.5)
			(thermal_bridge_width 0.5)
			(island_removal_mode 0)
		)
		(polygon
			(pts
				(arc
					(start 7.39013 -207.721454)
					(mid 7.405009 -207.757375)
					(end 7.44093 -207.772254)
				)
				(arc
					(start 8.84047 -207.772254)
					(mid 8.876391 -207.757375)
					(end 8.89127 -207.721454)
				)
				(arc
					(start 8.89127 -207.312514)
					(mid 8.876391 -207.276593)
					(end 8.84047 -207.261714)
				)
				(arc
					(start 7.44093 -207.261714)
					(mid 7.405009 -207.276593)
					(end 7.39013 -207.312514)
				)
			)
		)
	)
	(zone
		(layers "In1.Cu" "In2.Cu")
		(hatch none 0.5)
		(connect_pads
			(clearance 0)
		)
		(min_thickness 0.25)
		(keepout
			(tracks not_allowed)
			(vias allowed)
			(pads allowed)
			(copperpour not_allowed)
			(footprints allowed)
		)
		(placement
			(enabled no)
			(sheetname "")
		)
		(fill yes
			(thermal_gap 0.5)
			(thermal_bridge_width 0.5)
			(island_removal_mode 0)
		)
		(polygon
			(pts
				(arc
					(start 52.65293 -264.671302)
					(mid 52.667809 -264.707223)
					(end 52.70373 -264.722102)
				)
				(arc
					(start 54.10327 -264.722102)
					(mid 54.139191 -264.707223)
					(end 54.15407 -264.671302)
				)
				(arc
					(start 54.15407 -264.262362)
					(mid 54.139191 -264.226441)
					(end 54.10327 -264.211562)
				)
				(arc
					(start 52.70373 -264.211562)
					(mid 52.667809 -264.226441)
					(end 52.65293 -264.262362)
				)
			)
		)
	)
	(zone
		(layers "In1.Cu" "In2.Cu")
		(hatch none 0.5)
		(connect_pads
			(clearance 0)
		)
		(min_thickness 0.25)
		(keepout
			(tracks not_allowed)
			(vias allowed)
			(pads allowed)
			(copperpour not_allowed)
			(footprints allowed)
		)
		(placement
			(enabled no)
			(sheetname "")
		)
		(fill yes
			(thermal_gap 0.5)
			(thermal_bridge_width 0.5)
			(island_removal_mode 0)
		)
		(polygon
			(pts
				(arc
					(start 11.490198 -284.221428)
					(mid 11.505077 -284.257349)
					(end 11.540998 -284.272228)
				)
				(arc
					(start 12.940538 -284.272228)
					(mid 12.976459 -284.257349)
					(end 12.991338 -284.221428)
				)
				(arc
					(start 12.991338 -283.812488)
					(mid 12.976459 -283.776567)
					(end 12.940538 -283.761688)
				)
				(arc
					(start 11.540998 -283.761688)
					(mid 11.505077 -283.776567)
					(end 11.490198 -283.812488)
				)
			)
		)
	)
	(zone
		(layers "In1.Cu" "In2.Cu")
		(hatch none 0.5)
		(connect_pads
			(clearance 0)
		)
		(min_thickness 0.25)
		(keepout
			(tracks not_allowed)
			(vias allowed)
			(pads allowed)
			(copperpour not_allowed)
			(footprints allowed)
		)
		(placement
			(enabled no)
			(sheetname "")
		)
		(fill yes
			(thermal_gap 0.5)
			(thermal_bridge_width 0.5)
			(island_removal_mode 0)
		)
		(polygon
			(pts
				(arc
					(start 293.049198 -210.27136)
					(mid 293.064077 -210.307281)
					(end 293.099998 -210.32216)
				)
				(arc
					(start 294.499538 -210.32216)
					(mid 294.535459 -210.307281)
					(end 294.550338 -210.27136)
				)
				(arc
					(start 294.550338 -209.86242)
					(mid 294.535459 -209.826499)
					(end 294.499538 -209.81162)
				)
				(arc
					(start 293.099998 -209.81162)
					(mid 293.064077 -209.826499)
					(end 293.049198 -209.86242)
				)
			)
		)
	)
	(zone
		(layers "In1.Cu" "In2.Cu")
		(hatch none 0.5)
		(connect_pads
			(clearance 0)
		)
		(min_thickness 0.25)
		(keepout
			(tracks not_allowed)
			(vias allowed)
			(pads allowed)
			(copperpour not_allowed)
			(footprints allowed)
		)
		(placement
			(enabled no)
			(sheetname "")
		)
		(fill yes
			(thermal_gap 0.5)
			(thermal_bridge_width 0.5)
			(island_removal_mode 0)
		)
		(polygon
			(pts
				(arc
					(start 455.365866 -262.121396)
					(mid 455.380745 -262.157317)
					(end 455.416666 -262.172196)
				)
				(arc
					(start 456.816206 -262.172196)
					(mid 456.852127 -262.157317)
					(end 456.867006 -262.121396)
				)
				(arc
					(start 456.867006 -261.712456)
					(mid 456.852127 -261.676535)
					(end 456.816206 -261.661656)
				)
				(arc
					(start 455.416666 -261.661656)
					(mid 455.380745 -261.676535)
					(end 455.365866 -261.712456)
				)
			)
		)
	)
	(zone
		(layers "In1.Cu" "In2.Cu")
		(hatch none 0.5)
		(connect_pads
			(clearance 0)
		)
		(min_thickness 0.25)
		(keepout
			(tracks not_allowed)
			(vias allowed)
			(pads allowed)
			(copperpour not_allowed)
			(footprints allowed)
		)
		(placement
			(enabled no)
			(sheetname "")
		)
		(fill yes
			(thermal_gap 0.5)
			(thermal_bridge_width 0.5)
			(island_removal_mode 0)
		)
		(polygon
			(pts
				(arc
					(start 34.121598 -211.121498)
					(mid 34.136477 -211.157419)
					(end 34.172398 -211.172298)
				)
				(arc
					(start 35.571938 -211.172298)
					(mid 35.607859 -211.157419)
					(end 35.622738 -211.121498)
				)
				(arc
					(start 35.622738 -210.712558)
					(mid 35.607859 -210.676637)
					(end 35.571938 -210.661758)
				)
				(arc
					(start 34.172398 -210.661758)
					(mid 34.136477 -210.676637)
					(end 34.121598 -210.712558)
				)
			)
		)
	)
	(zone
		(layers "In1.Cu" "In2.Cu")
		(hatch none 0.5)
		(connect_pads
			(clearance 0)
		)
		(min_thickness 0.25)
		(keepout
			(tracks not_allowed)
			(vias allowed)
			(pads allowed)
			(copperpour not_allowed)
			(footprints allowed)
		)
		(placement
			(enabled no)
			(sheetname "")
		)
		(fill yes
			(thermal_gap 0.5)
			(thermal_bridge_width 0.5)
			(island_removal_mode 0)
		)
		(polygon
			(pts
				(arc
					(start 162.162998 -208.571338)
					(mid 162.177877 -208.607259)
					(end 162.213798 -208.622138)
				)
				(arc
					(start 163.613338 -208.622138)
					(mid 163.649259 -208.607259)
					(end 163.664138 -208.571338)
				)
				(arc
					(start 163.664138 -208.162398)
					(mid 163.649259 -208.126477)
					(end 163.613338 -208.111598)
				)
				(arc
					(start 162.213798 -208.111598)
					(mid 162.177877 -208.126477)
					(end 162.162998 -208.162398)
				)
			)
		)
	)
	(zone
		(layers "In1.Cu" "In2.Cu")
		(hatch none 0.5)
		(connect_pads
			(clearance 0)
		)
		(min_thickness 0.25)
		(keepout
			(tracks not_allowed)
			(vias allowed)
			(pads allowed)
			(copperpour not_allowed)
			(footprints allowed)
		)
		(placement
			(enabled no)
			(sheetname "")
		)
		(fill yes
			(thermal_gap 0.5)
			(thermal_bridge_width 0.5)
			(island_removal_mode 0)
		)
		(polygon
			(pts
				(arc
					(start 26.577798 -201.771504)
					(mid 26.592677 -201.807425)
					(end 26.628598 -201.822304)
				)
				(arc
					(start 28.028138 -201.822304)
					(mid 28.064059 -201.807425)
					(end 28.078938 -201.771504)
				)
				(arc
					(start 28.078938 -201.362564)
					(mid 28.064059 -201.326643)
					(end 28.028138 -201.311764)
				)
				(arc
					(start 26.628598 -201.311764)
					(mid 26.592677 -201.326643)
					(end 26.577798 -201.362564)
				)
			)
		)
	)
	(zone
		(layers "In1.Cu" "In2.Cu")
		(hatch none 0.5)
		(connect_pads
			(clearance 0)
		)
		(min_thickness 0.25)
		(keepout
			(tracks not_allowed)
			(vias allowed)
			(pads allowed)
			(copperpour not_allowed)
			(footprints allowed)
		)
		(placement
			(enabled no)
			(sheetname "")
		)
		(fill yes
			(thermal_gap 0.5)
			(thermal_bridge_width 0.5)
			(island_removal_mode 0)
		)
		(polygon
			(pts
				(arc
					(start 165.60673 -288.471356)
					(mid 165.621609 -288.507277)
					(end 165.65753 -288.522156)
				)
				(arc
					(start 167.05707 -288.522156)
					(mid 167.092991 -288.507277)
					(end 167.10787 -288.471356)
				)
				(arc
					(start 167.10787 -288.062416)
					(mid 167.092991 -288.026495)
					(end 167.05707 -288.011616)
				)
				(arc
					(start 165.65753 -288.011616)
					(mid 165.621609 -288.026495)
					(end 165.60673 -288.062416)
				)
			)
		)
	)
	(zone
		(layers "In1.Cu" "In2.Cu")
		(hatch none 0.5)
		(connect_pads
			(clearance 0)
		)
		(min_thickness 0.25)
		(keepout
			(tracks not_allowed)
			(vias allowed)
			(pads allowed)
			(copperpour not_allowed)
			(footprints allowed)
		)
		(placement
			(enabled no)
			(sheetname "")
		)
		(fill yes
			(thermal_gap 0.5)
			(thermal_bridge_width 0.5)
			(island_removal_mode 0)
		)
		(polygon
			(pts
				(arc
					(start 266.974066 -214.521542)
					(mid 266.988945 -214.557463)
					(end 267.024866 -214.572342)
				)
				(arc
					(start 268.424406 -214.572342)
					(mid 268.460327 -214.557463)
					(end 268.475206 -214.521542)
				)
				(arc
					(start 268.475206 -214.112602)
					(mid 268.460327 -214.076681)
					(end 268.424406 -214.061802)
				)
				(arc
					(start 267.024866 -214.061802)
					(mid 266.988945 -214.076681)
					(end 266.974066 -214.112602)
				)
			)
		)
	)
	(zone
		(layers "In1.Cu" "In2.Cu")
		(hatch none 0.5)
		(connect_pads
			(clearance 0)
		)
		(min_thickness 0.25)
		(keepout
			(tracks not_allowed)
			(vias allowed)
			(pads allowed)
			(copperpour not_allowed)
			(footprints allowed)
		)
		(placement
			(enabled no)
			(sheetname "")
		)
		(fill yes
			(thermal_gap 0.5)
			(thermal_bridge_width 0.5)
			(island_removal_mode 0)
		)
		(polygon
			(pts
				(arc
					(start 297.149266 -200.071482)
					(mid 297.164145 -200.107403)
					(end 297.200066 -200.122282)
				)
				(arc
					(start 298.599606 -200.122282)
					(mid 298.635527 -200.107403)
					(end 298.650406 -200.071482)
				)
				(arc
					(start 298.650406 -199.662542)
					(mid 298.635527 -199.626621)
					(end 298.599606 -199.611742)
				)
				(arc
					(start 297.200066 -199.611742)
					(mid 297.164145 -199.626621)
					(end 297.149266 -199.662542)
				)
			)
		)
	)
	(zone
		(layers "In1.Cu" "In2.Cu")
		(hatch none 0.5)
		(connect_pads
			(clearance 0)
		)
		(min_thickness 0.25)
		(keepout
			(tracks not_allowed)
			(vias allowed)
			(pads allowed)
			(copperpour not_allowed)
			(footprints allowed)
		)
		(placement
			(enabled no)
			(sheetname "")
		)
		(fill yes
			(thermal_gap 0.5)
			(thermal_bridge_width 0.5)
			(island_removal_mode 0)
		)
		(polygon
			(pts
				(arc
					(start 34.121598 -229.821486)
					(mid 34.136477 -229.857407)
					(end 34.172398 -229.872286)
				)
				(arc
					(start 35.571938 -229.872286)
					(mid 35.607859 -229.857407)
					(end 35.622738 -229.821486)
				)
				(arc
					(start 35.622738 -229.412546)
					(mid 35.607859 -229.376625)
					(end 35.571938 -229.361746)
				)
				(arc
					(start 34.172398 -229.361746)
					(mid 34.136477 -229.376625)
					(end 34.121598 -229.412546)
				)
			)
		)
	)
	(zone
		(layers "In1.Cu" "In2.Cu")
		(hatch none 0.5)
		(connect_pads
			(clearance 0)
		)
		(min_thickness 0.25)
		(keepout
			(tracks not_allowed)
			(vias allowed)
			(pads allowed)
			(copperpour not_allowed)
			(footprints allowed)
		)
		(placement
			(enabled no)
			(sheetname "")
		)
		(fill yes
			(thermal_gap 0.5)
			(thermal_bridge_width 0.5)
			(island_removal_mode 0)
		)
		(polygon
			(pts
				(arc
					(start 274.517866 -225.571304)
					(mid 274.532745 -225.607225)
					(end 274.568666 -225.622104)
				)
				(arc
					(start 275.968206 -225.622104)
					(mid 276.004127 -225.607225)
					(end 276.019006 -225.571304)
				)
				(arc
					(start 276.019006 -225.162364)
					(mid 276.004127 -225.126443)
					(end 275.968206 -225.111564)
				)
				(arc
					(start 274.568666 -225.111564)
					(mid 274.532745 -225.126443)
					(end 274.517866 -225.162364)
				)
			)
		)
	)
	(zone
		(layers "In1.Cu" "In2.Cu")
		(hatch none 0.5)
		(connect_pads
			(clearance 0)
		)
		(min_thickness 0.25)
		(keepout
			(tracks not_allowed)
			(vias allowed)
			(pads allowed)
			(copperpour not_allowed)
			(footprints allowed)
		)
		(placement
			(enabled no)
			(sheetname "")
		)
		(fill yes
			(thermal_gap 0.5)
			(thermal_bridge_width 0.5)
			(island_removal_mode 0)
		)
		(polygon
			(pts
				(arc
					(start 262.873998 -226.421442)
					(mid 262.888877 -226.457363)
					(end 262.924798 -226.472242)
				)
				(arc
					(start 264.324338 -226.472242)
					(mid 264.360259 -226.457363)
					(end 264.375138 -226.421442)
				)
				(arc
					(start 264.375138 -226.012502)
					(mid 264.360259 -225.976581)
					(end 264.324338 -225.961702)
				)
				(arc
					(start 262.924798 -225.961702)
					(mid 262.888877 -225.976581)
					(end 262.873998 -226.012502)
				)
			)
		)
	)
	(zone
		(layers "In1.Cu" "In2.Cu")
		(hatch none 0.5)
		(connect_pads
			(clearance 0)
		)
		(min_thickness 0.25)
		(keepout
			(tracks not_allowed)
			(vias allowed)
			(pads allowed)
			(copperpour not_allowed)
			(footprints allowed)
		)
		(placement
			(enabled no)
			(sheetname "")
		)
		(fill yes
			(thermal_gap 0.5)
			(thermal_bridge_width 0.5)
			(island_removal_mode 0)
		)
		(polygon
			(pts
				(arc
					(start 52.65293 -286.771334)
					(mid 52.667809 -286.807255)
					(end 52.70373 -286.822134)
				)
				(arc
					(start 54.10327 -286.822134)
					(mid 54.139191 -286.807255)
					(end 54.15407 -286.771334)
				)
				(arc
					(start 54.15407 -286.362394)
					(mid 54.139191 -286.326473)
					(end 54.10327 -286.311594)
				)
				(arc
					(start 52.70373 -286.311594)
					(mid 52.667809 -286.326473)
					(end 52.65293 -286.362394)
				)
			)
		)
	)
	(zone
		(layers "In1.Cu" "In2.Cu")
		(hatch none 0.5)
		(connect_pads
			(clearance 0)
		)
		(min_thickness 0.25)
		(keepout
			(tracks not_allowed)
			(vias allowed)
			(pads allowed)
			(copperpour not_allowed)
			(footprints allowed)
		)
		(placement
			(enabled no)
			(sheetname "")
		)
		(fill yes
			(thermal_gap 0.5)
			(thermal_bridge_width 0.5)
			(island_removal_mode 0)
		)
		(polygon
			(pts
				(arc
					(start 259.430266 -201.771504)
					(mid 259.445145 -201.807425)
					(end 259.481066 -201.822304)
				)
				(arc
					(start 260.880606 -201.822304)
					(mid 260.916527 -201.807425)
					(end 260.931406 -201.771504)
				)
				(arc
					(start 260.931406 -201.362564)
					(mid 260.916527 -201.326643)
					(end 260.880606 -201.311764)
				)
				(arc
					(start 259.481066 -201.311764)
					(mid 259.445145 -201.326643)
					(end 259.430266 -201.362564)
				)
			)
		)
	)
	(zone
		(layers "In1.Cu" "In2.Cu")
		(hatch none 0.5)
		(connect_pads
			(clearance 0)
		)
		(min_thickness 0.25)
		(keepout
			(tracks not_allowed)
			(vias allowed)
			(pads allowed)
			(copperpour not_allowed)
			(footprints allowed)
		)
		(placement
			(enabled no)
			(sheetname "")
		)
		(fill yes
			(thermal_gap 0.5)
			(thermal_bridge_width 0.5)
			(island_removal_mode 0)
		)
		(polygon
			(pts
				(arc
					(start 177.250598 -296.971466)
					(mid 177.265477 -297.007387)
					(end 177.301398 -297.022266)
				)
				(arc
					(start 178.700938 -297.022266)
					(mid 178.736859 -297.007387)
					(end 178.751738 -296.971466)
				)
				(arc
					(start 178.751738 -296.562526)
					(mid 178.736859 -296.526605)
					(end 178.700938 -296.511726)
				)
				(arc
					(start 177.301398 -296.511726)
					(mid 177.265477 -296.526605)
					(end 177.250598 -296.562526)
				)
			)
		)
	)
	(zone
		(layers "In1.Cu" "In2.Cu")
		(hatch none 0.5)
		(connect_pads
			(clearance 0)
		)
		(min_thickness 0.25)
		(keepout
			(tracks not_allowed)
			(vias allowed)
			(pads allowed)
			(copperpour not_allowed)
			(footprints allowed)
		)
		(placement
			(enabled no)
			(sheetname "")
		)
		(fill yes
			(thermal_gap 0.5)
			(thermal_bridge_width 0.5)
			(island_removal_mode 0)
		)
		(polygon
			(pts
				(arc
					(start 413.546798 -297.82135)
					(mid 413.561677 -297.857271)
					(end 413.597598 -297.87215)
				)
				(arc
					(start 414.997138 -297.87215)
					(mid 415.033059 -297.857271)
					(end 415.047938 -297.82135)
				)
				(arc
					(start 415.047938 -297.41241)
					(mid 415.033059 -297.376489)
					(end 414.997138 -297.36161)
				)
				(arc
					(start 413.597598 -297.36161)
					(mid 413.561677 -297.376489)
					(end 413.546798 -297.41241)
				)
			)
		)
	)
	(zone
		(layers "In1.Cu" "In2.Cu")
		(hatch none 0.5)
		(connect_pads
			(clearance 0)
		)
		(min_thickness 0.25)
		(keepout
			(tracks not_allowed)
			(vias allowed)
			(pads allowed)
			(copperpour not_allowed)
			(footprints allowed)
		)
		(placement
			(enabled no)
			(sheetname "")
		)
		(fill yes
			(thermal_gap 0.5)
			(thermal_bridge_width 0.5)
			(island_removal_mode 0)
		)
		(polygon
			(pts
				(arc
					(start 158.06293 -262.971534)
					(mid 158.077809 -263.007455)
					(end 158.11373 -263.022334)
				)
				(arc
					(start 159.51327 -263.022334)
					(mid 159.549191 -263.007455)
					(end 159.56407 -262.971534)
				)
				(arc
					(start 159.56407 -262.562594)
					(mid 159.549191 -262.526673)
					(end 159.51327 -262.511794)
				)
				(arc
					(start 158.11373 -262.511794)
					(mid 158.077809 -262.526673)
					(end 158.06293 -262.562594)
				)
			)
		)
	)
	(zone
		(layers "In1.Cu" "In2.Cu")
		(hatch none 0.5)
		(connect_pads
			(clearance 0)
		)
		(min_thickness 0.25)
		(keepout
			(tracks not_allowed)
			(vias allowed)
			(pads allowed)
			(copperpour not_allowed)
			(footprints allowed)
		)
		(placement
			(enabled no)
			(sheetname "")
		)
		(fill yes
			(thermal_gap 0.5)
			(thermal_bridge_width 0.5)
			(island_removal_mode 0)
		)
		(polygon
			(pts
				(arc
					(start 14.93393 -291.8714)
					(mid 14.948809 -291.907321)
					(end 14.98473 -291.9222)
				)
				(arc
					(start 16.38427 -291.9222)
					(mid 16.420191 -291.907321)
					(end 16.43507 -291.8714)
				)
				(arc
					(start 16.43507 -291.46246)
					(mid 16.420191 -291.426539)
					(end 16.38427 -291.41166)
				)
				(arc
					(start 14.98473 -291.41166)
					(mid 14.948809 -291.426539)
					(end 14.93393 -291.46246)
				)
			)
		)
	)
	(zone
		(layers "In1.Cu" "In2.Cu")
		(hatch none 0.5)
		(connect_pads
			(clearance 0)
		)
		(min_thickness 0.25)
		(keepout
			(tracks not_allowed)
			(vias allowed)
			(pads allowed)
			(copperpour not_allowed)
			(footprints allowed)
		)
		(placement
			(enabled no)
			(sheetname "")
		)
		(fill yes
			(thermal_gap 0.5)
			(thermal_bridge_width 0.5)
			(island_removal_mode 0)
		)
		(polygon
			(pts
				(arc
					(start 312.236866 -281.671522)
					(mid 312.251745 -281.707443)
					(end 312.287666 -281.722322)
				)
				(arc
					(start 313.687206 -281.722322)
					(mid 313.723127 -281.707443)
					(end 313.738006 -281.671522)
				)
				(arc
					(start 313.738006 -281.262582)
					(mid 313.723127 -281.226661)
					(end 313.687206 -281.211782)
				)
				(arc
					(start 312.287666 -281.211782)
					(mid 312.251745 -281.226661)
					(end 312.236866 -281.262582)
				)
			)
		)
	)
	(zone
		(layers "In1.Cu" "In2.Cu")
		(hatch none 0.5)
		(connect_pads
			(clearance 0)
		)
		(min_thickness 0.25)
		(keepout
			(tracks not_allowed)
			(vias allowed)
			(pads allowed)
			(copperpour not_allowed)
			(footprints allowed)
		)
		(placement
			(enabled no)
			(sheetname "")
		)
		(fill yes
			(thermal_gap 0.5)
			(thermal_bridge_width 0.5)
			(island_removal_mode 0)
		)
		(polygon
			(pts
				(arc
					(start 277.961598 -294.421306)
					(mid 277.976477 -294.457227)
					(end 278.012398 -294.472106)
				)
				(arc
					(start 279.411938 -294.472106)
					(mid 279.447859 -294.457227)
					(end 279.462738 -294.421306)
				)
				(arc
					(start 279.462738 -294.012366)
					(mid 279.447859 -293.976445)
					(end 279.411938 -293.961566)
				)
				(arc
					(start 278.012398 -293.961566)
					(mid 277.976477 -293.976445)
					(end 277.961598 -294.012366)
				)
			)
		)
	)
	(zone
		(layers "In1.Cu" "In2.Cu")
		(hatch none 0.5)
		(connect_pads
			(clearance 0)
		)
		(min_thickness 0.25)
		(keepout
			(tracks not_allowed)
			(vias allowed)
			(pads allowed)
			(copperpour not_allowed)
			(footprints allowed)
		)
		(placement
			(enabled no)
			(sheetname "")
		)
		(fill yes
			(thermal_gap 0.5)
			(thermal_bridge_width 0.5)
			(island_removal_mode 0)
		)
		(polygon
			(pts
				(arc
					(start 184.794398 -236.62132)
					(mid 184.809277 -236.657241)
					(end 184.845198 -236.67212)
				)
				(arc
					(start 186.244738 -236.67212)
					(mid 186.280659 -236.657241)
					(end 186.295538 -236.62132)
				)
				(arc
					(start 186.295538 -236.21238)
					(mid 186.280659 -236.176459)
					(end 186.244738 -236.16158)
				)
				(arc
					(start 184.845198 -236.16158)
					(mid 184.809277 -236.176459)
					(end 184.794398 -236.21238)
				)
			)
		)
	)
	(zone
		(layers "In1.Cu" "In2.Cu")
		(hatch none 0.5)
		(connect_pads
			(clearance 0)
		)
		(min_thickness 0.25)
		(keepout
			(tracks not_allowed)
			(vias allowed)
			(pads allowed)
			(copperpour not_allowed)
			(footprints allowed)
		)
		(placement
			(enabled no)
			(sheetname "")
		)
		(fill yes
			(thermal_gap 0.5)
			(thermal_bridge_width 0.5)
			(island_removal_mode 0)
		)
		(polygon
			(pts
				(arc
					(start 49.209198 -274.871434)
					(mid 49.224077 -274.907355)
					(end 49.259998 -274.922234)
				)
				(arc
					(start 50.659538 -274.922234)
					(mid 50.695459 -274.907355)
					(end 50.710338 -274.871434)
				)
				(arc
					(start 50.710338 -274.462494)
					(mid 50.695459 -274.426573)
					(end 50.659538 -274.411694)
				)
				(arc
					(start 49.259998 -274.411694)
					(mid 49.224077 -274.426573)
					(end 49.209198 -274.462494)
				)
			)
		)
	)
	(zone
		(layers "In1.Cu" "In2.Cu")
		(hatch none 0.5)
		(connect_pads
			(clearance 0)
		)
		(min_thickness 0.25)
		(keepout
			(tracks not_allowed)
			(vias allowed)
			(pads allowed)
			(copperpour not_allowed)
			(footprints allowed)
		)
		(placement
			(enabled no)
			(sheetname "")
		)
		(fill yes
			(thermal_gap 0.5)
			(thermal_bridge_width 0.5)
			(island_removal_mode 0)
		)
		(polygon
			(pts
				(arc
					(start 49.209198 -229.821486)
					(mid 49.224077 -229.857407)
					(end 49.259998 -229.872286)
				)
				(arc
					(start 50.659538 -229.872286)
					(mid 50.695459 -229.857407)
					(end 50.710338 -229.821486)
				)
				(arc
					(start 50.710338 -229.412546)
					(mid 50.695459 -229.376625)
					(end 50.659538 -229.361746)
				)
				(arc
					(start 49.259998 -229.361746)
					(mid 49.224077 -229.376625)
					(end 49.209198 -229.412546)
				)
			)
		)
	)
	(zone
		(layers "In1.Cu" "In2.Cu")
		(hatch none 0.5)
		(connect_pads
			(clearance 0)
		)
		(min_thickness 0.25)
		(keepout
			(tracks not_allowed)
			(vias allowed)
			(pads allowed)
			(copperpour not_allowed)
			(footprints allowed)
		)
		(placement
			(enabled no)
			(sheetname "")
		)
		(fill yes
			(thermal_gap 0.5)
			(thermal_bridge_width 0.5)
			(island_removal_mode 0)
		)
		(polygon
			(pts
				(arc
					(start 52.65293 -234.071414)
					(mid 52.667809 -234.107335)
					(end 52.70373 -234.122214)
				)
				(arc
					(start 54.10327 -234.122214)
					(mid 54.139191 -234.107335)
					(end 54.15407 -234.071414)
				)
				(arc
					(start 54.15407 -233.662474)
					(mid 54.139191 -233.626553)
					(end 54.10327 -233.611674)
				)
				(arc
					(start 52.70373 -233.611674)
					(mid 52.667809 -233.626553)
					(end 52.65293 -233.662474)
				)
			)
		)
	)
	(zone
		(layers "In1.Cu" "In2.Cu")
		(hatch none 0.5)
		(connect_pads
			(clearance 0)
		)
		(min_thickness 0.25)
		(keepout
			(tracks not_allowed)
			(vias allowed)
			(pads allowed)
			(copperpour not_allowed)
			(footprints allowed)
		)
		(placement
			(enabled no)
			(sheetname "")
		)
		(fill yes
			(thermal_gap 0.5)
			(thermal_bridge_width 0.5)
			(island_removal_mode 0)
		)
		(polygon
			(pts
				(arc
					(start 266.974066 -309.721504)
					(mid 266.988945 -309.757425)
					(end 267.024866 -309.772304)
				)
				(arc
					(start 268.424406 -309.772304)
					(mid 268.460327 -309.757425)
					(end 268.475206 -309.721504)
				)
				(arc
					(start 268.475206 -309.312564)
					(mid 268.460327 -309.276643)
					(end 268.424406 -309.261764)
				)
				(arc
					(start 267.024866 -309.261764)
					(mid 266.988945 -309.276643)
					(end 266.974066 -309.312564)
				)
			)
		)
	)
	(zone
		(layers "In1.Cu" "In2.Cu")
		(hatch none 0.5)
		(connect_pads
			(clearance 0)
		)
		(min_thickness 0.25)
		(keepout
			(tracks not_allowed)
			(vias allowed)
			(pads allowed)
			(copperpour not_allowed)
			(footprints allowed)
		)
		(placement
			(enabled no)
			(sheetname "")
		)
		(fill yes
			(thermal_gap 0.5)
			(thermal_bridge_width 0.5)
			(island_removal_mode 0)
		)
		(polygon
			(pts
				(arc
					(start 192.338198 -251.921518)
					(mid 192.353077 -251.957439)
					(end 192.388998 -251.972318)
				)
				(arc
					(start 193.788538 -251.972318)
					(mid 193.824459 -251.957439)
					(end 193.839338 -251.921518)
				)
				(arc
					(start 193.839338 -251.512578)
					(mid 193.824459 -251.476657)
					(end 193.788538 -251.461778)
				)
				(arc
					(start 192.388998 -251.461778)
					(mid 192.353077 -251.476657)
					(end 192.338198 -251.512578)
				)
			)
		)
	)
	(zone
		(layers "In1.Cu" "In2.Cu")
		(hatch none 0.5)
		(connect_pads
			(clearance 0)
		)
		(min_thickness 0.25)
		(keepout
			(tracks not_allowed)
			(vias allowed)
			(pads allowed)
			(copperpour not_allowed)
			(footprints allowed)
		)
		(placement
			(enabled no)
			(sheetname "")
		)
		(fill yes
			(thermal_gap 0.5)
			(thermal_bridge_width 0.5)
			(island_removal_mode 0)
		)
		(polygon
			(pts
				(arc
					(start 413.546798 -209.421476)
					(mid 413.561677 -209.457397)
					(end 413.597598 -209.472276)
				)
				(arc
					(start 414.997138 -209.472276)
					(mid 415.033059 -209.457397)
					(end 415.047938 -209.421476)
				)
				(arc
					(start 415.047938 -209.012536)
					(mid 415.033059 -208.976615)
					(end 414.997138 -208.961736)
				)
				(arc
					(start 413.597598 -208.961736)
					(mid 413.561677 -208.976615)
					(end 413.546798 -209.012536)
				)
			)
		)
	)
	(zone
		(layers "In1.Cu" "In2.Cu")
		(hatch none 0.5)
		(connect_pads
			(clearance 0)
		)
		(min_thickness 0.25)
		(keepout
			(tracks not_allowed)
			(vias allowed)
			(pads allowed)
			(copperpour not_allowed)
			(footprints allowed)
		)
		(placement
			(enabled no)
			(sheetname "")
		)
		(fill yes
			(thermal_gap 0.5)
			(thermal_bridge_width 0.5)
			(island_removal_mode 0)
		)
		(polygon
			(pts
				(arc
					(start 162.162998 -227.271326)
					(mid 162.177877 -227.307247)
					(end 162.213798 -227.322126)
				)
				(arc
					(start 163.613338 -227.322126)
					(mid 163.649259 -227.307247)
					(end 163.664138 -227.271326)
				)
				(arc
					(start 163.664138 -226.862386)
					(mid 163.649259 -226.826465)
					(end 163.613338 -226.811586)
				)
				(arc
					(start 162.213798 -226.811586)
					(mid 162.177877 -226.826465)
					(end 162.162998 -226.862386)
				)
			)
		)
	)
	(zone
		(layers "In1.Cu" "In2.Cu")
		(hatch none 0.5)
		(connect_pads
			(clearance 0)
		)
		(min_thickness 0.25)
		(keepout
			(tracks not_allowed)
			(vias allowed)
			(pads allowed)
			(copperpour not_allowed)
			(footprints allowed)
		)
		(placement
			(enabled no)
			(sheetname "")
		)
		(fill yes
			(thermal_gap 0.5)
			(thermal_bridge_width 0.5)
			(island_removal_mode 0)
		)
		(polygon
			(pts
				(arc
					(start 425.190666 -267.221462)
					(mid 425.205545 -267.257383)
					(end 425.241466 -267.272262)
				)
				(arc
					(start 426.641006 -267.272262)
					(mid 426.676927 -267.257383)
					(end 426.691806 -267.221462)
				)
				(arc
					(start 426.691806 -266.812522)
					(mid 426.676927 -266.776601)
					(end 426.641006 -266.761722)
				)
				(arc
					(start 425.241466 -266.761722)
					(mid 425.205545 -266.776601)
					(end 425.190666 -266.812522)
				)
			)
		)
	)
	(zone
		(layers "In1.Cu" "In2.Cu")
		(hatch none 0.5)
		(connect_pads
			(clearance 0)
		)
		(min_thickness 0.25)
		(keepout
			(tracks not_allowed)
			(vias allowed)
			(pads allowed)
			(copperpour not_allowed)
			(footprints allowed)
		)
		(placement
			(enabled no)
			(sheetname "")
		)
		(fill yes
			(thermal_gap 0.5)
			(thermal_bridge_width 0.5)
			(island_removal_mode 0)
		)
		(polygon
			(pts
				(arc
					(start 195.78193 -307.171344)
					(mid 195.796809 -307.207265)
					(end 195.83273 -307.222144)
				)
				(arc
					(start 197.23227 -307.222144)
					(mid 197.268191 -307.207265)
					(end 197.28307 -307.171344)
				)
				(arc
					(start 197.28307 -306.762404)
					(mid 197.268191 -306.726483)
					(end 197.23227 -306.711604)
				)
				(arc
					(start 195.83273 -306.711604)
					(mid 195.796809 -306.726483)
					(end 195.78193 -306.762404)
				)
			)
		)
	)
	(zone
		(layers "In1.Cu" "In2.Cu")
		(hatch none 0.5)
		(connect_pads
			(clearance 0)
		)
		(min_thickness 0.25)
		(keepout
			(tracks not_allowed)
			(vias allowed)
			(pads allowed)
			(copperpour not_allowed)
			(footprints allowed)
		)
		(placement
			(enabled no)
			(sheetname "")
		)
		(fill yes
			(thermal_gap 0.5)
			(thermal_bridge_width 0.5)
			(island_removal_mode 0)
		)
		(polygon
			(pts
				(arc
					(start 22.47773 -305.471322)
					(mid 22.492609 -305.507243)
					(end 22.52853 -305.522122)
				)
				(arc
					(start 23.92807 -305.522122)
					(mid 23.963991 -305.507243)
					(end 23.97887 -305.471322)
				)
				(arc
					(start 23.97887 -305.062382)
					(mid 23.963991 -305.026461)
					(end 23.92807 -305.011582)
				)
				(arc
					(start 22.52853 -305.011582)
					(mid 22.492609 -305.026461)
					(end 22.47773 -305.062382)
				)
			)
		)
	)
	(zone
		(layers "In1.Cu" "In2.Cu")
		(hatch none 0.5)
		(connect_pads
			(clearance 0)
		)
		(min_thickness 0.25)
		(keepout
			(tracks not_allowed)
			(vias allowed)
			(pads allowed)
			(copperpour not_allowed)
			(footprints allowed)
		)
		(placement
			(enabled no)
			(sheetname "")
		)
		(fill yes
			(thermal_gap 0.5)
			(thermal_bridge_width 0.5)
			(island_removal_mode 0)
		)
		(polygon
			(pts
				(arc
					(start 425.190666 -265.52144)
					(mid 425.205545 -265.557361)
					(end 425.241466 -265.57224)
				)
				(arc
					(start 426.641006 -265.57224)
					(mid 426.676927 -265.557361)
					(end 426.691806 -265.52144)
				)
				(arc
					(start 426.691806 -265.1125)
					(mid 426.676927 -265.076579)
					(end 426.641006 -265.0617)
				)
				(arc
					(start 425.241466 -265.0617)
					(mid 425.205545 -265.076579)
					(end 425.190666 -265.1125)
				)
			)
		)
	)
	(zone
		(layers "In1.Cu" "In2.Cu")
		(hatch none 0.5)
		(connect_pads
			(clearance 0)
		)
		(min_thickness 0.25)
		(keepout
			(tracks not_allowed)
			(vias allowed)
			(pads allowed)
			(copperpour not_allowed)
			(footprints allowed)
		)
		(placement
			(enabled no)
			(sheetname "")
		)
		(fill yes
			(thermal_gap 0.5)
			(thermal_bridge_width 0.5)
			(island_removal_mode 0)
		)
		(polygon
			(pts
				(arc
					(start 52.65293 -244.271292)
					(mid 52.667809 -244.307213)
					(end 52.70373 -244.322092)
				)
				(arc
					(start 54.10327 -244.322092)
					(mid 54.139191 -244.307213)
					(end 54.15407 -244.271292)
				)
				(arc
					(start 54.15407 -243.862352)
					(mid 54.139191 -243.826431)
					(end 54.10327 -243.811552)
				)
				(arc
					(start 52.70373 -243.811552)
					(mid 52.667809 -243.826431)
					(end 52.65293 -243.862352)
				)
			)
		)
	)
	(zone
		(layers "In1.Cu" "In2.Cu")
		(hatch none 0.5)
		(connect_pads
			(clearance 0)
		)
		(min_thickness 0.25)
		(keepout
			(tracks not_allowed)
			(vias allowed)
			(pads allowed)
			(copperpour not_allowed)
			(footprints allowed)
		)
		(placement
			(enabled no)
			(sheetname "")
		)
		(fill yes
			(thermal_gap 0.5)
			(thermal_bridge_width 0.5)
			(island_removal_mode 0)
		)
		(polygon
			(pts
				(arc
					(start 60.19673 -310.571388)
					(mid 60.211609 -310.607309)
					(end 60.24753 -310.622188)
				)
				(arc
					(start 61.64707 -310.622188)
					(mid 61.682991 -310.607309)
					(end 61.69787 -310.571388)
				)
				(arc
					(start 61.69787 -310.162448)
					(mid 61.682991 -310.126527)
					(end 61.64707 -310.111648)
				)
				(arc
					(start 60.24753 -310.111648)
					(mid 60.211609 -310.126527)
					(end 60.19673 -310.162448)
				)
			)
		)
	)
	(zone
		(layers "In1.Cu" "In2.Cu")
		(hatch none 0.5)
		(connect_pads
			(clearance 0)
		)
		(min_thickness 0.25)
		(keepout
			(tracks not_allowed)
			(vias allowed)
			(pads allowed)
			(copperpour not_allowed)
			(footprints allowed)
		)
		(placement
			(enabled no)
			(sheetname "")
		)
		(fill yes
			(thermal_gap 0.5)
			(thermal_bridge_width 0.5)
			(island_removal_mode 0)
		)
		(polygon
			(pts
				(arc
					(start 14.93393 -237.471458)
					(mid 14.948809 -237.507379)
					(end 14.98473 -237.522258)
				)
				(arc
					(start 16.38427 -237.522258)
					(mid 16.420191 -237.507379)
					(end 16.43507 -237.471458)
				)
				(arc
					(start 16.43507 -237.062518)
					(mid 16.420191 -237.026597)
					(end 16.38427 -237.011718)
				)
				(arc
					(start 14.98473 -237.011718)
					(mid 14.948809 -237.026597)
					(end 14.93393 -237.062518)
				)
			)
		)
	)
	(zone
		(layers "In1.Cu" "In2.Cu")
		(hatch none 0.5)
		(connect_pads
			(clearance 0)
		)
		(min_thickness 0.25)
		(keepout
			(tracks not_allowed)
			(vias allowed)
			(pads allowed)
			(copperpour not_allowed)
			(footprints allowed)
		)
		(placement
			(enabled no)
			(sheetname "")
		)
		(fill yes
			(thermal_gap 0.5)
			(thermal_bridge_width 0.5)
			(island_removal_mode 0)
		)
		(polygon
			(pts
				(arc
					(start 64.296798 -268.921484)
					(mid 64.311677 -268.957405)
					(end 64.347598 -268.972284)
				)
				(arc
					(start 65.747138 -268.972284)
					(mid 65.783059 -268.957405)
					(end 65.797938 -268.921484)
				)
				(arc
					(start 65.797938 -268.512544)
					(mid 65.783059 -268.476623)
					(end 65.747138 -268.461744)
				)
				(arc
					(start 64.347598 -268.461744)
					(mid 64.311677 -268.476623)
					(end 64.296798 -268.512544)
				)
			)
		)
	)
	(zone
		(layers "In1.Cu" "In2.Cu")
		(hatch none 0.5)
		(connect_pads
			(clearance 0)
		)
		(min_thickness 0.25)
		(keepout
			(tracks not_allowed)
			(vias allowed)
			(pads allowed)
			(copperpour not_allowed)
			(footprints allowed)
		)
		(placement
			(enabled no)
			(sheetname "")
		)
		(fill yes
			(thermal_gap 0.5)
			(thermal_bridge_width 0.5)
			(island_removal_mode 0)
		)
		(polygon
			(pts
				(arc
					(start 428.634398 -223.021398)
					(mid 428.649277 -223.057319)
					(end 428.685198 -223.072198)
				)
				(arc
					(start 430.084738 -223.072198)
					(mid 430.120659 -223.057319)
					(end 430.135538 -223.021398)
				)
				(arc
					(start 430.135538 -222.612458)
					(mid 430.120659 -222.576537)
					(end 430.084738 -222.561658)
				)
				(arc
					(start 428.685198 -222.561658)
					(mid 428.649277 -222.576537)
					(end 428.634398 -222.612458)
				)
			)
		)
	)
	(zone
		(layers "In1.Cu" "In2.Cu")
		(hatch none 0.5)
		(connect_pads
			(clearance 0)
		)
		(min_thickness 0.25)
		(keepout
			(tracks not_allowed)
			(vias allowed)
			(pads allowed)
			(copperpour not_allowed)
			(footprints allowed)
		)
		(placement
			(enabled no)
			(sheetname "")
		)
		(fill yes
			(thermal_gap 0.5)
			(thermal_bridge_width 0.5)
			(island_removal_mode 0)
		)
		(polygon
			(pts
				(arc
					(start 297.149266 -274.871434)
					(mid 297.164145 -274.907355)
					(end 297.200066 -274.922234)
				)
				(arc
					(start 298.599606 -274.922234)
					(mid 298.635527 -274.907355)
					(end 298.650406 -274.871434)
				)
				(arc
					(start 298.650406 -274.462494)
					(mid 298.635527 -274.426573)
					(end 298.599606 -274.411694)
				)
				(arc
					(start 297.200066 -274.411694)
					(mid 297.164145 -274.426573)
					(end 297.149266 -274.462494)
				)
			)
		)
	)
	(zone
		(layers "In1.Cu" "In2.Cu")
		(hatch none 0.5)
		(connect_pads
			(clearance 0)
		)
		(min_thickness 0.25)
		(keepout
			(tracks not_allowed)
			(vias allowed)
			(pads allowed)
			(copperpour not_allowed)
			(footprints allowed)
		)
		(placement
			(enabled no)
			(sheetname "")
		)
		(fill yes
			(thermal_gap 0.5)
			(thermal_bridge_width 0.5)
			(island_removal_mode 0)
		)
		(polygon
			(pts
				(arc
					(start 37.56533 -264.671302)
					(mid 37.580209 -264.707223)
					(end 37.61613 -264.722102)
				)
				(arc
					(start 39.01567 -264.722102)
					(mid 39.051591 -264.707223)
					(end 39.06647 -264.671302)
				)
				(arc
					(start 39.06647 -264.262362)
					(mid 39.051591 -264.226441)
					(end 39.01567 -264.211562)
				)
				(arc
					(start 37.61613 -264.211562)
					(mid 37.580209 -264.226441)
					(end 37.56533 -264.262362)
				)
			)
		)
	)
	(zone
		(layers "In1.Cu" "In2.Cu")
		(hatch none 0.5)
		(connect_pads
			(clearance 0)
		)
		(min_thickness 0.25)
		(keepout
			(tracks not_allowed)
			(vias allowed)
			(pads allowed)
			(copperpour not_allowed)
			(footprints allowed)
		)
		(placement
			(enabled no)
			(sheetname "")
		)
		(fill yes
			(thermal_gap 0.5)
			(thermal_bridge_width 0.5)
			(island_removal_mode 0)
		)
		(polygon
			(pts
				(arc
					(start 293.049198 -206.021432)
					(mid 293.064077 -206.057353)
					(end 293.099998 -206.072232)
				)
				(arc
					(start 294.499538 -206.072232)
					(mid 294.535459 -206.057353)
					(end 294.550338 -206.021432)
				)
				(arc
					(start 294.550338 -205.612492)
					(mid 294.535459 -205.576571)
					(end 294.499538 -205.561692)
				)
				(arc
					(start 293.099998 -205.561692)
					(mid 293.064077 -205.576571)
					(end 293.049198 -205.612492)
				)
			)
		)
	)
	(zone
		(layers "In1.Cu" "In2.Cu")
		(hatch none 0.5)
		(connect_pads
			(clearance 0)
		)
		(min_thickness 0.25)
		(keepout
			(tracks not_allowed)
			(vias allowed)
			(pads allowed)
			(copperpour not_allowed)
			(footprints allowed)
		)
		(placement
			(enabled no)
			(sheetname "")
		)
		(fill yes
			(thermal_gap 0.5)
			(thermal_bridge_width 0.5)
			(island_removal_mode 0)
		)
		(polygon
			(pts
				(arc
					(start 451.265798 -234.071414)
					(mid 451.280677 -234.107335)
					(end 451.316598 -234.122214)
				)
				(arc
					(start 452.716138 -234.122214)
					(mid 452.752059 -234.107335)
					(end 452.766938 -234.071414)
				)
				(arc
					(start 452.766938 -233.662474)
					(mid 452.752059 -233.626553)
					(end 452.716138 -233.611674)
				)
				(arc
					(start 451.316598 -233.611674)
					(mid 451.280677 -233.626553)
					(end 451.265798 -233.662474)
				)
			)
		)
	)
	(zone
		(layers "In1.Cu" "In2.Cu")
		(hatch none 0.5)
		(connect_pads
			(clearance 0)
		)
		(min_thickness 0.25)
		(keepout
			(tracks not_allowed)
			(vias allowed)
			(pads allowed)
			(copperpour not_allowed)
			(footprints allowed)
		)
		(placement
			(enabled no)
			(sheetname "")
		)
		(fill yes
			(thermal_gap 0.5)
			(thermal_bridge_width 0.5)
			(island_removal_mode 0)
		)
		(polygon
			(pts
				(arc
					(start 297.149266 -300.37151)
					(mid 297.164145 -300.407431)
					(end 297.200066 -300.42231)
				)
				(arc
					(start 298.599606 -300.42231)
					(mid 298.635527 -300.407431)
					(end 298.650406 -300.37151)
				)
				(arc
					(start 298.650406 -299.96257)
					(mid 298.635527 -299.926649)
					(end 298.599606 -299.91177)
				)
				(arc
					(start 297.200066 -299.91177)
					(mid 297.164145 -299.926649)
					(end 297.149266 -299.96257)
				)
			)
		)
	)
	(zone
		(layers "In1.Cu" "In2.Cu")
		(hatch none 0.5)
		(connect_pads
			(clearance 0)
		)
		(min_thickness 0.25)
		(keepout
			(tracks not_allowed)
			(vias allowed)
			(pads allowed)
			(copperpour not_allowed)
			(footprints allowed)
		)
		(placement
			(enabled no)
			(sheetname "")
		)
		(fill yes
			(thermal_gap 0.5)
			(thermal_bridge_width 0.5)
			(island_removal_mode 0)
		)
		(polygon
			(pts
				(arc
					(start 413.546798 -228.971348)
					(mid 413.561677 -229.007269)
					(end 413.597598 -229.022148)
				)
				(arc
					(start 414.997138 -229.022148)
					(mid 415.033059 -229.007269)
					(end 415.047938 -228.971348)
				)
				(arc
					(start 415.047938 -228.562408)
					(mid 415.033059 -228.526487)
					(end 414.997138 -228.511608)
				)
				(arc
					(start 413.597598 -228.511608)
					(mid 413.561677 -228.526487)
					(end 413.546798 -228.562408)
				)
			)
		)
	)
	(zone
		(layers "In1.Cu" "In2.Cu")
		(hatch none 0.5)
		(connect_pads
			(clearance 0)
		)
		(min_thickness 0.25)
		(keepout
			(tracks not_allowed)
			(vias allowed)
			(pads allowed)
			(copperpour not_allowed)
			(footprints allowed)
		)
		(placement
			(enabled no)
			(sheetname "")
		)
		(fill yes
			(thermal_gap 0.5)
			(thermal_bridge_width 0.5)
			(island_removal_mode 0)
		)
		(polygon
			(pts
				(arc
					(start 451.265798 -249.371358)
					(mid 451.280677 -249.407279)
					(end 451.316598 -249.422158)
				)
				(arc
					(start 452.716138 -249.422158)
					(mid 452.752059 -249.407279)
					(end 452.766938 -249.371358)
				)
				(arc
					(start 452.766938 -248.962418)
					(mid 452.752059 -248.926497)
					(end 452.716138 -248.911618)
				)
				(arc
					(start 451.316598 -248.911618)
					(mid 451.280677 -248.926497)
					(end 451.265798 -248.962418)
				)
			)
		)
	)
	(zone
		(layers "In1.Cu" "In2.Cu")
		(hatch none 0.5)
		(connect_pads
			(clearance 0)
		)
		(min_thickness 0.25)
		(keepout
			(tracks not_allowed)
			(vias allowed)
			(pads allowed)
			(copperpour not_allowed)
			(footprints allowed)
		)
		(placement
			(enabled no)
			(sheetname "")
		)
		(fill yes
			(thermal_gap 0.5)
			(thermal_bridge_width 0.5)
			(island_removal_mode 0)
		)
		(polygon
			(pts
				(arc
					(start 195.78193 -284.221428)
					(mid 195.796809 -284.257349)
					(end 195.83273 -284.272228)
				)
				(arc
					(start 197.23227 -284.272228)
					(mid 197.268191 -284.257349)
					(end 197.28307 -284.221428)
				)
				(arc
					(start 197.28307 -283.812488)
					(mid 197.268191 -283.776567)
					(end 197.23227 -283.761688)
				)
				(arc
					(start 195.83273 -283.761688)
					(mid 195.796809 -283.776567)
					(end 195.78193 -283.812488)
				)
			)
		)
	)
	(zone
		(layers "In1.Cu" "In2.Cu")
		(hatch none 0.5)
		(connect_pads
			(clearance 0)
		)
		(min_thickness 0.25)
		(keepout
			(tracks not_allowed)
			(vias allowed)
			(pads allowed)
			(copperpour not_allowed)
			(footprints allowed)
		)
		(placement
			(enabled no)
			(sheetname "")
		)
		(fill yes
			(thermal_gap 0.5)
			(thermal_bridge_width 0.5)
			(island_removal_mode 0)
		)
		(polygon
			(pts
				(arc
					(start 210.86953 -204.32141)
					(mid 210.884409 -204.357331)
					(end 210.92033 -204.37221)
				)
				(arc
					(start 212.31987 -204.37221)
					(mid 212.355791 -204.357331)
					(end 212.37067 -204.32141)
				)
				(arc
					(start 212.37067 -203.91247)
					(mid 212.355791 -203.876549)
					(end 212.31987 -203.86167)
				)
				(arc
					(start 210.92033 -203.86167)
					(mid 210.884409 -203.876549)
					(end 210.86953 -203.91247)
				)
			)
		)
	)
	(zone
		(layers "In1.Cu" "In2.Cu")
		(hatch none 0.5)
		(connect_pads
			(clearance 0)
		)
		(min_thickness 0.25)
		(keepout
			(tracks not_allowed)
			(vias allowed)
			(pads allowed)
			(copperpour not_allowed)
			(footprints allowed)
		)
		(placement
			(enabled no)
			(sheetname "")
		)
		(fill yes
			(thermal_gap 0.5)
			(thermal_bridge_width 0.5)
			(island_removal_mode 0)
		)
		(polygon
			(pts
				(arc
					(start 432.734466 -279.9715)
					(mid 432.749345 -280.007421)
					(end 432.785266 -280.0223)
				)
				(arc
					(start 434.184806 -280.0223)
					(mid 434.220727 -280.007421)
					(end 434.235606 -279.9715)
				)
				(arc
					(start 434.235606 -279.56256)
					(mid 434.220727 -279.526639)
					(end 434.184806 -279.51176)
				)
				(arc
					(start 432.785266 -279.51176)
					(mid 432.749345 -279.526639)
					(end 432.734466 -279.56256)
				)
			)
		)
	)
	(zone
		(layers "In1.Cu" "In2.Cu")
		(hatch none 0.5)
		(connect_pads
			(clearance 0)
		)
		(min_thickness 0.25)
		(keepout
			(tracks not_allowed)
			(vias allowed)
			(pads allowed)
			(copperpour not_allowed)
			(footprints allowed)
		)
		(placement
			(enabled no)
			(sheetname "")
		)
		(fill yes
			(thermal_gap 0.5)
			(thermal_bridge_width 0.5)
			(island_removal_mode 0)
		)
		(polygon
			(pts
				(arc
					(start 262.873998 -299.521372)
					(mid 262.888877 -299.557293)
					(end 262.924798 -299.572172)
				)
				(arc
					(start 264.324338 -299.572172)
					(mid 264.360259 -299.557293)
					(end 264.375138 -299.521372)
				)
				(arc
					(start 264.375138 -299.112432)
					(mid 264.360259 -299.076511)
					(end 264.324338 -299.061632)
				)
				(arc
					(start 262.924798 -299.061632)
					(mid 262.888877 -299.076511)
					(end 262.873998 -299.112432)
				)
			)
		)
	)
	(zone
		(layers "In1.Cu" "In2.Cu")
		(hatch none 0.5)
		(connect_pads
			(clearance 0)
		)
		(min_thickness 0.25)
		(keepout
			(tracks not_allowed)
			(vias allowed)
			(pads allowed)
			(copperpour not_allowed)
			(footprints allowed)
		)
		(placement
			(enabled no)
			(sheetname "")
		)
		(fill yes
			(thermal_gap 0.5)
			(thermal_bridge_width 0.5)
			(island_removal_mode 0)
		)
		(polygon
			(pts
				(arc
					(start 199.881998 -236.62132)
					(mid 199.896877 -236.657241)
					(end 199.932798 -236.67212)
				)
				(arc
					(start 201.332338 -236.67212)
					(mid 201.368259 -236.657241)
					(end 201.383138 -236.62132)
				)
				(arc
					(start 201.383138 -236.21238)
					(mid 201.368259 -236.176459)
					(end 201.332338 -236.16158)
				)
				(arc
					(start 199.932798 -236.16158)
					(mid 199.896877 -236.176459)
					(end 199.881998 -236.21238)
				)
			)
		)
	)
	(zone
		(layers "In1.Cu" "In2.Cu")
		(hatch none 0.5)
		(connect_pads
			(clearance 0)
		)
		(min_thickness 0.25)
		(keepout
			(tracks not_allowed)
			(vias allowed)
			(pads allowed)
			(copperpour not_allowed)
			(footprints allowed)
		)
		(placement
			(enabled no)
			(sheetname "")
		)
		(fill yes
			(thermal_gap 0.5)
			(thermal_bridge_width 0.5)
			(island_removal_mode 0)
		)
		(polygon
			(pts
				(arc
					(start 285.505398 -303.7713)
					(mid 285.520277 -303.807221)
					(end 285.556198 -303.8221)
				)
				(arc
					(start 286.955738 -303.8221)
					(mid 286.991659 -303.807221)
					(end 287.006538 -303.7713)
				)
				(arc
					(start 287.006538 -303.36236)
					(mid 286.991659 -303.326439)
					(end 286.955738 -303.31156)
				)
				(arc
					(start 285.556198 -303.31156)
					(mid 285.520277 -303.326439)
					(end 285.505398 -303.36236)
				)
			)
		)
	)
	(zone
		(layers "In1.Cu" "In2.Cu")
		(hatch none 0.5)
		(connect_pads
			(clearance 0)
		)
		(min_thickness 0.25)
		(keepout
			(tracks not_allowed)
			(vias allowed)
			(pads allowed)
			(copperpour not_allowed)
			(footprints allowed)
		)
		(placement
			(enabled no)
			(sheetname "")
		)
		(fill yes
			(thermal_gap 0.5)
			(thermal_bridge_width 0.5)
			(island_removal_mode 0)
		)
		(polygon
			(pts
				(arc
					(start 289.605466 -281.671522)
					(mid 289.620345 -281.707443)
					(end 289.656266 -281.722322)
				)
				(arc
					(start 291.055806 -281.722322)
					(mid 291.091727 -281.707443)
					(end 291.106606 -281.671522)
				)
				(arc
					(start 291.106606 -281.262582)
					(mid 291.091727 -281.226661)
					(end 291.055806 -281.211782)
				)
				(arc
					(start 289.656266 -281.211782)
					(mid 289.620345 -281.226661)
					(end 289.605466 -281.262582)
				)
			)
		)
	)
	(zone
		(layers "In1.Cu" "In2.Cu")
		(hatch none 0.5)
		(connect_pads
			(clearance 0)
		)
		(min_thickness 0.25)
		(keepout
			(tracks not_allowed)
			(vias allowed)
			(pads allowed)
			(copperpour not_allowed)
			(footprints allowed)
		)
		(placement
			(enabled no)
			(sheetname "")
		)
		(fill yes
			(thermal_gap 0.5)
			(thermal_bridge_width 0.5)
			(island_removal_mode 0)
		)
		(polygon
			(pts
				(arc
					(start 30.02153 -196.671438)
					(mid 30.036409 -196.707359)
					(end 30.07233 -196.722238)
				)
				(arc
					(start 31.47187 -196.722238)
					(mid 31.507791 -196.707359)
					(end 31.52267 -196.671438)
				)
				(arc
					(start 31.52267 -196.262498)
					(mid 31.507791 -196.226577)
					(end 31.47187 -196.211698)
				)
				(arc
					(start 30.07233 -196.211698)
					(mid 30.036409 -196.226577)
					(end 30.02153 -196.262498)
				)
			)
		)
	)
	(zone
		(layers "In1.Cu" "In2.Cu")
		(hatch none 0.5)
		(connect_pads
			(clearance 0)
		)
		(min_thickness 0.25)
		(keepout
			(tracks not_allowed)
			(vias allowed)
			(pads allowed)
			(copperpour not_allowed)
			(footprints allowed)
		)
		(placement
			(enabled no)
			(sheetname "")
		)
		(fill yes
			(thermal_gap 0.5)
			(thermal_bridge_width 0.5)
			(island_removal_mode 0)
		)
		(polygon
			(pts
				(arc
					(start 60.19673 -305.471322)
					(mid 60.211609 -305.507243)
					(end 60.24753 -305.522122)
				)
				(arc
					(start 61.64707 -305.522122)
					(mid 61.682991 -305.507243)
					(end 61.69787 -305.471322)
				)
				(arc
					(start 61.69787 -305.062382)
					(mid 61.682991 -305.026461)
					(end 61.64707 -305.011582)
				)
				(arc
					(start 60.24753 -305.011582)
					(mid 60.211609 -305.026461)
					(end 60.19673 -305.062382)
				)
			)
		)
	)
	(zone
		(layers "In1.Cu" "In2.Cu")
		(hatch none 0.5)
		(connect_pads
			(clearance 0)
		)
		(min_thickness 0.25)
		(keepout
			(tracks not_allowed)
			(vias allowed)
			(pads allowed)
			(copperpour not_allowed)
			(footprints allowed)
		)
		(placement
			(enabled no)
			(sheetname "")
		)
		(fill yes
			(thermal_gap 0.5)
			(thermal_bridge_width 0.5)
			(island_removal_mode 0)
		)
		(polygon
			(pts
				(arc
					(start 207.425798 -199.221344)
					(mid 207.440677 -199.257265)
					(end 207.476598 -199.272144)
				)
				(arc
					(start 208.876138 -199.272144)
					(mid 208.912059 -199.257265)
					(end 208.926938 -199.221344)
				)
				(arc
					(start 208.926938 -198.812404)
					(mid 208.912059 -198.776483)
					(end 208.876138 -198.761604)
				)
				(arc
					(start 207.476598 -198.761604)
					(mid 207.440677 -198.776483)
					(end 207.425798 -198.812404)
				)
			)
		)
	)
	(zone
		(layers "In1.Cu" "In2.Cu")
		(hatch none 0.5)
		(connect_pads
			(clearance 0)
		)
		(min_thickness 0.25)
		(keepout
			(tracks not_allowed)
			(vias allowed)
			(pads allowed)
			(copperpour not_allowed)
			(footprints allowed)
		)
		(placement
			(enabled no)
			(sheetname "")
		)
		(fill yes
			(thermal_gap 0.5)
			(thermal_bridge_width 0.5)
			(island_removal_mode 0)
		)
		(polygon
			(pts
				(arc
					(start 285.505398 -301.221394)
					(mid 285.520277 -301.257315)
					(end 285.556198 -301.272194)
				)
				(arc
					(start 286.955738 -301.272194)
					(mid 286.991659 -301.257315)
					(end 287.006538 -301.221394)
				)
				(arc
					(start 287.006538 -300.812454)
					(mid 286.991659 -300.776533)
					(end 286.955738 -300.761654)
				)
				(arc
					(start 285.556198 -300.761654)
					(mid 285.520277 -300.776533)
					(end 285.505398 -300.812454)
				)
			)
		)
	)
	(zone
		(layers "In1.Cu" "In2.Cu")
		(hatch none 0.5)
		(connect_pads
			(clearance 0)
		)
		(min_thickness 0.25)
		(keepout
			(tracks not_allowed)
			(vias allowed)
			(pads allowed)
			(copperpour not_allowed)
			(footprints allowed)
		)
		(placement
			(enabled no)
			(sheetname "")
		)
		(fill yes
			(thermal_gap 0.5)
			(thermal_bridge_width 0.5)
			(island_removal_mode 0)
		)
		(polygon
			(pts
				(arc
					(start 60.19673 -228.971348)
					(mid 60.211609 -229.007269)
					(end 60.24753 -229.022148)
				)
				(arc
					(start 61.64707 -229.022148)
					(mid 61.682991 -229.007269)
					(end 61.69787 -228.971348)
				)
				(arc
					(start 61.69787 -228.562408)
					(mid 61.682991 -228.526487)
					(end 61.64707 -228.511608)
				)
				(arc
					(start 60.24753 -228.511608)
					(mid 60.211609 -228.526487)
					(end 60.19673 -228.562408)
				)
			)
		)
	)
	(zone
		(layers "In1.Cu" "In2.Cu")
		(hatch none 0.5)
		(connect_pads
			(clearance 0)
		)
		(min_thickness 0.25)
		(keepout
			(tracks not_allowed)
			(vias allowed)
			(pads allowed)
			(copperpour not_allowed)
			(footprints allowed)
		)
		(placement
			(enabled no)
			(sheetname "")
		)
		(fill yes
			(thermal_gap 0.5)
			(thermal_bridge_width 0.5)
			(island_removal_mode 0)
		)
		(polygon
			(pts
				(arc
					(start 432.734466 -268.921484)
					(mid 432.749345 -268.957405)
					(end 432.785266 -268.972284)
				)
				(arc
					(start 434.184806 -268.972284)
					(mid 434.220727 -268.957405)
					(end 434.235606 -268.921484)
				)
				(arc
					(start 434.235606 -268.512544)
					(mid 434.220727 -268.476623)
					(end 434.184806 -268.461744)
				)
				(arc
					(start 432.785266 -268.461744)
					(mid 432.749345 -268.476623)
					(end 432.734466 -268.512544)
				)
			)
		)
	)
	(zone
		(layers "In1.Cu" "In2.Cu")
		(hatch none 0.5)
		(connect_pads
			(clearance 0)
		)
		(min_thickness 0.25)
		(keepout
			(tracks not_allowed)
			(vias allowed)
			(pads allowed)
			(copperpour not_allowed)
			(footprints allowed)
		)
		(placement
			(enabled no)
			(sheetname "")
		)
		(fill yes
			(thermal_gap 0.5)
			(thermal_bridge_width 0.5)
			(island_removal_mode 0)
		)
		(polygon
			(pts
				(arc
					(start 436.178198 -207.721454)
					(mid 436.193077 -207.757375)
					(end 436.228998 -207.772254)
				)
				(arc
					(start 437.628538 -207.772254)
					(mid 437.664459 -207.757375)
					(end 437.679338 -207.721454)
				)
				(arc
					(start 437.679338 -207.312514)
					(mid 437.664459 -207.276593)
					(end 437.628538 -207.261714)
				)
				(arc
					(start 436.228998 -207.261714)
					(mid 436.193077 -207.276593)
					(end 436.178198 -207.312514)
				)
			)
		)
	)
	(zone
		(layers "In1.Cu" "In2.Cu")
		(hatch none 0.5)
		(connect_pads
			(clearance 0)
		)
		(min_thickness 0.25)
		(keepout
			(tracks not_allowed)
			(vias allowed)
			(pads allowed)
			(copperpour not_allowed)
			(footprints allowed)
		)
		(placement
			(enabled no)
			(sheetname "")
		)
		(fill yes
			(thermal_gap 0.5)
			(thermal_bridge_width 0.5)
			(island_removal_mode 0)
		)
		(polygon
			(pts
				(arc
					(start 60.19673 -259.57149)
					(mid 60.211609 -259.607411)
					(end 60.24753 -259.62229)
				)
				(arc
					(start 61.64707 -259.62229)
					(mid 61.682991 -259.607411)
					(end 61.69787 -259.57149)
				)
				(arc
					(start 61.69787 -259.16255)
					(mid 61.682991 -259.126629)
					(end 61.64707 -259.11175)
				)
				(arc
					(start 60.24753 -259.11175)
					(mid 60.211609 -259.126629)
					(end 60.19673 -259.16255)
				)
			)
		)
	)
	(zone
		(layers "In1.Cu" "In2.Cu")
		(hatch none 0.5)
		(connect_pads
			(clearance 0)
		)
		(min_thickness 0.25)
		(keepout
			(tracks not_allowed)
			(vias allowed)
			(pads allowed)
			(copperpour not_allowed)
			(footprints allowed)
		)
		(placement
			(enabled no)
			(sheetname "")
		)
		(fill yes
			(thermal_gap 0.5)
			(thermal_bridge_width 0.5)
			(island_removal_mode 0)
		)
		(polygon
			(pts
				(arc
					(start 177.250598 -203.471526)
					(mid 177.265477 -203.507447)
					(end 177.301398 -203.522326)
				)
				(arc
					(start 178.700938 -203.522326)
					(mid 178.736859 -203.507447)
					(end 178.751738 -203.471526)
				)
				(arc
					(start 178.751738 -203.062586)
					(mid 178.736859 -203.026665)
					(end 178.700938 -203.011786)
				)
				(arc
					(start 177.301398 -203.011786)
					(mid 177.265477 -203.026665)
					(end 177.250598 -203.062586)
				)
			)
		)
	)
	(zone
		(layers "In1.Cu" "In2.Cu")
		(hatch none 0.5)
		(connect_pads
			(clearance 0)
		)
		(min_thickness 0.25)
		(keepout
			(tracks not_allowed)
			(vias allowed)
			(pads allowed)
			(copperpour not_allowed)
			(footprints allowed)
		)
		(placement
			(enabled no)
			(sheetname "")
		)
		(fill yes
			(thermal_gap 0.5)
			(thermal_bridge_width 0.5)
			(island_removal_mode 0)
		)
		(polygon
			(pts
				(arc
					(start 192.338198 -211.121498)
					(mid 192.353077 -211.157419)
					(end 192.388998 -211.172298)
				)
				(arc
					(start 193.788538 -211.172298)
					(mid 193.824459 -211.157419)
					(end 193.839338 -211.121498)
				)
				(arc
					(start 193.839338 -210.712558)
					(mid 193.824459 -210.676637)
					(end 193.788538 -210.661758)
				)
				(arc
					(start 192.388998 -210.661758)
					(mid 192.353077 -210.676637)
					(end 192.338198 -210.712558)
				)
			)
		)
	)
	(zone
		(layers "In1.Cu" "In2.Cu")
		(hatch none 0.5)
		(connect_pads
			(clearance 0)
		)
		(min_thickness 0.25)
		(keepout
			(tracks not_allowed)
			(vias allowed)
			(pads allowed)
			(copperpour not_allowed)
			(footprints allowed)
		)
		(placement
			(enabled no)
			(sheetname "")
		)
		(fill yes
			(thermal_gap 0.5)
			(thermal_bridge_width 0.5)
			(island_removal_mode 0)
		)
		(polygon
			(pts
				(arc
					(start 165.60673 -237.471458)
					(mid 165.621609 -237.507379)
					(end 165.65753 -237.522258)
				)
				(arc
					(start 167.05707 -237.522258)
					(mid 167.092991 -237.507379)
					(end 167.10787 -237.471458)
				)
				(arc
					(start 167.10787 -237.062518)
					(mid 167.092991 -237.026597)
					(end 167.05707 -237.011718)
				)
				(arc
					(start 165.65753 -237.011718)
					(mid 165.621609 -237.026597)
					(end 165.60673 -237.062518)
				)
			)
		)
	)
	(zone
		(layers "In1.Cu" "In2.Cu")
		(hatch none 0.5)
		(connect_pads
			(clearance 0)
		)
		(min_thickness 0.25)
		(keepout
			(tracks not_allowed)
			(vias allowed)
			(pads allowed)
			(copperpour not_allowed)
			(footprints allowed)
		)
		(placement
			(enabled no)
			(sheetname "")
		)
		(fill yes
			(thermal_gap 0.5)
			(thermal_bridge_width 0.5)
			(island_removal_mode 0)
		)
		(polygon
			(pts
				(arc
					(start 22.47773 -213.671404)
					(mid 22.492609 -213.707325)
					(end 22.52853 -213.722204)
				)
				(arc
					(start 23.92807 -213.722204)
					(mid 23.963991 -213.707325)
					(end 23.97887 -213.671404)
				)
				(arc
					(start 23.97887 -213.262464)
					(mid 23.963991 -213.226543)
					(end 23.92807 -213.211664)
				)
				(arc
					(start 22.52853 -213.211664)
					(mid 22.492609 -213.226543)
					(end 22.47773 -213.262464)
				)
			)
		)
	)
	(zone
		(layers "In1.Cu" "In2.Cu")
		(hatch none 0.5)
		(connect_pads
			(clearance 0)
		)
		(min_thickness 0.25)
		(keepout
			(tracks not_allowed)
			(vias allowed)
			(pads allowed)
			(copperpour not_allowed)
			(footprints allowed)
		)
		(placement
			(enabled no)
			(sheetname "")
		)
		(fill yes
			(thermal_gap 0.5)
			(thermal_bridge_width 0.5)
			(island_removal_mode 0)
		)
		(polygon
			(pts
				(arc
					(start 158.06293 -277.42134)
					(mid 158.077809 -277.457261)
					(end 158.11373 -277.47214)
				)
				(arc
					(start 159.51327 -277.47214)
					(mid 159.549191 -277.457261)
					(end 159.56407 -277.42134)
				)
				(arc
					(start 159.56407 -277.0124)
					(mid 159.549191 -276.976479)
					(end 159.51327 -276.9616)
				)
				(arc
					(start 158.11373 -276.9616)
					(mid 158.077809 -276.976479)
					(end 158.06293 -277.0124)
				)
			)
		)
	)
	(zone
		(layers "In1.Cu" "In2.Cu")
		(hatch none 0.5)
		(connect_pads
			(clearance 0)
		)
		(min_thickness 0.25)
		(keepout
			(tracks not_allowed)
			(vias allowed)
			(pads allowed)
			(copperpour not_allowed)
			(footprints allowed)
		)
		(placement
			(enabled no)
			(sheetname "")
		)
		(fill yes
			(thermal_gap 0.5)
			(thermal_bridge_width 0.5)
			(island_removal_mode 0)
		)
		(polygon
			(pts
				(arc
					(start 270.417798 -275.721318)
					(mid 270.432677 -275.757239)
					(end 270.468598 -275.772118)
				)
				(arc
					(start 271.868138 -275.772118)
					(mid 271.904059 -275.757239)
					(end 271.918938 -275.721318)
				)
				(arc
					(start 271.918938 -275.312378)
					(mid 271.904059 -275.276457)
					(end 271.868138 -275.261578)
				)
				(arc
					(start 270.468598 -275.261578)
					(mid 270.432677 -275.276457)
					(end 270.417798 -275.312378)
				)
			)
		)
	)
	(zone
		(layers "In1.Cu" "In2.Cu")
		(hatch none 0.5)
		(connect_pads
			(clearance 0)
		)
		(min_thickness 0.25)
		(keepout
			(tracks not_allowed)
			(vias allowed)
			(pads allowed)
			(copperpour not_allowed)
			(footprints allowed)
		)
		(placement
			(enabled no)
			(sheetname "")
		)
		(fill yes
			(thermal_gap 0.5)
			(thermal_bridge_width 0.5)
			(island_removal_mode 0)
		)
		(polygon
			(pts
				(arc
					(start 214.969598 -206.871316)
					(mid 214.984477 -206.907237)
					(end 215.020398 -206.922116)
				)
				(arc
					(start 216.419938 -206.922116)
					(mid 216.455859 -206.907237)
					(end 216.470738 -206.871316)
				)
				(arc
					(start 216.470738 -206.462376)
					(mid 216.455859 -206.426455)
					(end 216.419938 -206.411576)
				)
				(arc
					(start 215.020398 -206.411576)
					(mid 214.984477 -206.426455)
					(end 214.969598 -206.462376)
				)
			)
		)
	)
	(zone
		(layers "In1.Cu" "In2.Cu")
		(hatch none 0.5)
		(connect_pads
			(clearance 0)
		)
		(min_thickness 0.25)
		(keepout
			(tracks not_allowed)
			(vias allowed)
			(pads allowed)
			(copperpour not_allowed)
			(footprints allowed)
		)
		(placement
			(enabled no)
			(sheetname "")
		)
		(fill yes
			(thermal_gap 0.5)
			(thermal_bridge_width 0.5)
			(island_removal_mode 0)
		)
		(polygon
			(pts
				(arc
					(start 199.881998 -208.571338)
					(mid 199.896877 -208.607259)
					(end 199.932798 -208.622138)
				)
				(arc
					(start 201.332338 -208.622138)
					(mid 201.368259 -208.607259)
					(end 201.383138 -208.571338)
				)
				(arc
					(start 201.383138 -208.162398)
					(mid 201.368259 -208.126477)
					(end 201.332338 -208.111598)
				)
				(arc
					(start 199.932798 -208.111598)
					(mid 199.896877 -208.126477)
					(end 199.881998 -208.162398)
				)
			)
		)
	)
	(zone
		(layers "In1.Cu" "In2.Cu")
		(hatch none 0.5)
		(connect_pads
			(clearance 0)
		)
		(min_thickness 0.25)
		(keepout
			(tracks not_allowed)
			(vias allowed)
			(pads allowed)
			(copperpour not_allowed)
			(footprints allowed)
		)
		(placement
			(enabled no)
			(sheetname "")
		)
		(fill yes
			(thermal_gap 0.5)
			(thermal_bridge_width 0.5)
			(island_removal_mode 0)
		)
		(polygon
			(pts
				(arc
					(start 425.190666 -279.9715)
					(mid 425.205545 -280.007421)
					(end 425.241466 -280.0223)
				)
				(arc
					(start 426.641006 -280.0223)
					(mid 426.676927 -280.007421)
					(end 426.691806 -279.9715)
				)
				(arc
					(start 426.691806 -279.56256)
					(mid 426.676927 -279.526639)
					(end 426.641006 -279.51176)
				)
				(arc
					(start 425.241466 -279.51176)
					(mid 425.205545 -279.526639)
					(end 425.190666 -279.56256)
				)
			)
		)
	)
	(zone
		(layers "In1.Cu" "In2.Cu")
		(hatch none 0.5)
		(connect_pads
			(clearance 0)
		)
		(min_thickness 0.25)
		(keepout
			(tracks not_allowed)
			(vias allowed)
			(pads allowed)
			(copperpour not_allowed)
			(footprints allowed)
		)
		(placement
			(enabled no)
			(sheetname "")
		)
		(fill yes
			(thermal_gap 0.5)
			(thermal_bridge_width 0.5)
			(island_removal_mode 0)
		)
		(polygon
			(pts
				(arc
					(start 158.06293 -200.071482)
					(mid 158.077809 -200.107403)
					(end 158.11373 -200.122282)
				)
				(arc
					(start 159.51327 -200.122282)
					(mid 159.549191 -200.107403)
					(end 159.56407 -200.071482)
				)
				(arc
					(start 159.56407 -199.662542)
					(mid 159.549191 -199.626621)
					(end 159.51327 -199.611742)
				)
				(arc
					(start 158.11373 -199.611742)
					(mid 158.077809 -199.626621)
					(end 158.06293 -199.662542)
				)
			)
		)
	)
	(zone
		(layers "In1.Cu" "In2.Cu")
		(hatch none 0.5)
		(connect_pads
			(clearance 0)
		)
		(min_thickness 0.25)
		(keepout
			(tracks not_allowed)
			(vias allowed)
			(pads allowed)
			(copperpour not_allowed)
			(footprints allowed)
		)
		(placement
			(enabled no)
			(sheetname "")
		)
		(fill yes
			(thermal_gap 0.5)
			(thermal_bridge_width 0.5)
			(island_removal_mode 0)
		)
		(polygon
			(pts
				(arc
					(start 410.103066 -231.521508)
					(mid 410.117945 -231.557429)
					(end 410.153866 -231.572308)
				)
				(arc
					(start 411.553406 -231.572308)
					(mid 411.589327 -231.557429)
					(end 411.604206 -231.521508)
				)
				(arc
					(start 411.604206 -231.112568)
					(mid 411.589327 -231.076647)
					(end 411.553406 -231.061768)
				)
				(arc
					(start 410.153866 -231.061768)
					(mid 410.117945 -231.076647)
					(end 410.103066 -231.112568)
				)
			)
		)
	)
	(zone
		(layers "In1.Cu" "In2.Cu")
		(hatch none 0.5)
		(connect_pads
			(clearance 0)
		)
		(min_thickness 0.25)
		(keepout
			(tracks not_allowed)
			(vias allowed)
			(pads allowed)
			(copperpour not_allowed)
			(footprints allowed)
		)
		(placement
			(enabled no)
			(sheetname "")
		)
		(fill yes
			(thermal_gap 0.5)
			(thermal_bridge_width 0.5)
			(island_removal_mode 0)
		)
		(polygon
			(pts
				(arc
					(start 443.721998 -243.421408)
					(mid 443.736877 -243.457329)
					(end 443.772798 -243.472208)
				)
				(arc
					(start 445.172338 -243.472208)
					(mid 445.208259 -243.457329)
					(end 445.223138 -243.421408)
				)
				(arc
					(start 445.223138 -243.012468)
					(mid 445.208259 -242.976547)
					(end 445.172338 -242.961668)
				)
				(arc
					(start 443.772798 -242.961668)
					(mid 443.736877 -242.976547)
					(end 443.721998 -243.012468)
				)
			)
		)
	)
	(zone
		(layers "In1.Cu" "In2.Cu")
		(hatch none 0.5)
		(connect_pads
			(clearance 0)
		)
		(min_thickness 0.25)
		(keepout
			(tracks not_allowed)
			(vias allowed)
			(pads allowed)
			(copperpour not_allowed)
			(footprints allowed)
		)
		(placement
			(enabled no)
			(sheetname "")
		)
		(fill yes
			(thermal_gap 0.5)
			(thermal_bridge_width 0.5)
			(island_removal_mode 0)
		)
		(polygon
			(pts
				(arc
					(start 262.873998 -206.021432)
					(mid 262.888877 -206.057353)
					(end 262.924798 -206.072232)
				)
				(arc
					(start 264.324338 -206.072232)
					(mid 264.360259 -206.057353)
					(end 264.375138 -206.021432)
				)
				(arc
					(start 264.375138 -205.612492)
					(mid 264.360259 -205.576571)
					(end 264.324338 -205.561692)
				)
				(arc
					(start 262.924798 -205.561692)
					(mid 262.888877 -205.576571)
					(end 262.873998 -205.612492)
				)
			)
		)
	)
	(zone
		(layers "In1.Cu" "In2.Cu")
		(hatch none 0.5)
		(connect_pads
			(clearance 0)
		)
		(min_thickness 0.25)
		(keepout
			(tracks not_allowed)
			(vias allowed)
			(pads allowed)
			(copperpour not_allowed)
			(footprints allowed)
		)
		(placement
			(enabled no)
			(sheetname "")
		)
		(fill yes
			(thermal_gap 0.5)
			(thermal_bridge_width 0.5)
			(island_removal_mode 0)
		)
		(polygon
			(pts
				(arc
					(start 180.69433 -228.121464)
					(mid 180.709209 -228.157385)
					(end 180.74513 -228.172264)
				)
				(arc
					(start 182.14467 -228.172264)
					(mid 182.180591 -228.157385)
					(end 182.19547 -228.121464)
				)
				(arc
					(start 182.19547 -227.712524)
					(mid 182.180591 -227.676603)
					(end 182.14467 -227.661724)
				)
				(arc
					(start 180.74513 -227.661724)
					(mid 180.709209 -227.676603)
					(end 180.69433 -227.712524)
				)
			)
		)
	)
	(zone
		(layers "In1.Cu" "In2.Cu")
		(hatch none 0.5)
		(connect_pads
			(clearance 0)
		)
		(min_thickness 0.25)
		(keepout
			(tracks not_allowed)
			(vias allowed)
			(pads allowed)
			(copperpour not_allowed)
			(footprints allowed)
		)
		(placement
			(enabled no)
			(sheetname "")
		)
		(fill yes
			(thermal_gap 0.5)
			(thermal_bridge_width 0.5)
			(island_removal_mode 0)
		)
		(polygon
			(pts
				(arc
					(start 277.961598 -247.671336)
					(mid 277.976477 -247.707257)
					(end 278.012398 -247.722136)
				)
				(arc
					(start 279.411938 -247.722136)
					(mid 279.447859 -247.707257)
					(end 279.462738 -247.671336)
				)
				(arc
					(start 279.462738 -247.262396)
					(mid 279.447859 -247.226475)
					(end 279.411938 -247.211596)
				)
				(arc
					(start 278.012398 -247.211596)
					(mid 277.976477 -247.226475)
					(end 277.961598 -247.262396)
				)
			)
		)
	)
	(zone
		(layers "In1.Cu" "In2.Cu")
		(hatch none 0.5)
		(connect_pads
			(clearance 0)
		)
		(min_thickness 0.25)
		(keepout
			(tracks not_allowed)
			(vias allowed)
			(pads allowed)
			(copperpour not_allowed)
			(footprints allowed)
		)
		(placement
			(enabled no)
			(sheetname "")
		)
		(fill yes
			(thermal_gap 0.5)
			(thermal_bridge_width 0.5)
			(island_removal_mode 0)
		)
		(polygon
			(pts
				(arc
					(start 289.605466 -203.471526)
					(mid 289.620345 -203.507447)
					(end 289.656266 -203.522326)
				)
				(arc
					(start 291.055806 -203.522326)
					(mid 291.091727 -203.507447)
					(end 291.106606 -203.471526)
				)
				(arc
					(start 291.106606 -203.062586)
					(mid 291.091727 -203.026665)
					(end 291.055806 -203.011786)
				)
				(arc
					(start 289.656266 -203.011786)
					(mid 289.620345 -203.026665)
					(end 289.605466 -203.062586)
				)
			)
		)
	)
	(zone
		(layers "In1.Cu" "In2.Cu")
		(hatch none 0.5)
		(connect_pads
			(clearance 0)
		)
		(min_thickness 0.25)
		(keepout
			(tracks not_allowed)
			(vias allowed)
			(pads allowed)
			(copperpour not_allowed)
			(footprints allowed)
		)
		(placement
			(enabled no)
			(sheetname "")
		)
		(fill yes
			(thermal_gap 0.5)
			(thermal_bridge_width 0.5)
			(island_removal_mode 0)
		)
		(polygon
			(pts
				(arc
					(start 410.103066 -262.121396)
					(mid 410.117945 -262.157317)
					(end 410.153866 -262.172196)
				)
				(arc
					(start 411.553406 -262.172196)
					(mid 411.589327 -262.157317)
					(end 411.604206 -262.121396)
				)
				(arc
					(start 411.604206 -261.712456)
					(mid 411.589327 -261.676535)
					(end 411.553406 -261.661656)
				)
				(arc
					(start 410.153866 -261.661656)
					(mid 410.117945 -261.676535)
					(end 410.103066 -261.712456)
				)
			)
		)
	)
	(zone
		(layers "In1.Cu" "In2.Cu")
		(hatch none 0.5)
		(connect_pads
			(clearance 0)
		)
		(min_thickness 0.25)
		(keepout
			(tracks not_allowed)
			(vias allowed)
			(pads allowed)
			(copperpour not_allowed)
			(footprints allowed)
		)
		(placement
			(enabled no)
			(sheetname "")
		)
		(fill yes
			(thermal_gap 0.5)
			(thermal_bridge_width 0.5)
			(island_removal_mode 0)
		)
		(polygon
			(pts
				(arc
					(start 195.78193 -313.121294)
					(mid 195.796809 -313.157215)
					(end 195.83273 -313.172094)
				)
				(arc
					(start 197.23227 -313.172094)
					(mid 197.268191 -313.157215)
					(end 197.28307 -313.121294)
				)
				(arc
					(start 197.28307 -312.712354)
					(mid 197.268191 -312.676433)
					(end 197.23227 -312.661554)
				)
				(arc
					(start 195.83273 -312.661554)
					(mid 195.796809 -312.676433)
					(end 195.78193 -312.712354)
				)
			)
		)
	)
	(zone
		(layers "In1.Cu" "In2.Cu")
		(hatch none 0.5)
		(connect_pads
			(clearance 0)
		)
		(min_thickness 0.25)
		(keepout
			(tracks not_allowed)
			(vias allowed)
			(pads allowed)
			(copperpour not_allowed)
			(footprints allowed)
		)
		(placement
			(enabled no)
			(sheetname "")
		)
		(fill yes
			(thermal_gap 0.5)
			(thermal_bridge_width 0.5)
			(island_removal_mode 0)
		)
		(polygon
			(pts
				(arc
					(start 180.69433 -252.771402)
					(mid 180.709209 -252.807323)
					(end 180.74513 -252.822202)
				)
				(arc
					(start 182.14467 -252.822202)
					(mid 182.180591 -252.807323)
					(end 182.19547 -252.771402)
				)
				(arc
					(start 182.19547 -252.362462)
					(mid 182.180591 -252.326541)
					(end 182.14467 -252.311662)
				)
				(arc
					(start 180.74513 -252.311662)
					(mid 180.709209 -252.326541)
					(end 180.69433 -252.362462)
				)
			)
		)
	)
	(zone
		(layers "In1.Cu" "In2.Cu")
		(hatch none 0.5)
		(connect_pads
			(clearance 0)
		)
		(min_thickness 0.25)
		(keepout
			(tracks not_allowed)
			(vias allowed)
			(pads allowed)
			(copperpour not_allowed)
			(footprints allowed)
		)
		(placement
			(enabled no)
			(sheetname "")
		)
		(fill yes
			(thermal_gap 0.5)
			(thermal_bridge_width 0.5)
			(island_removal_mode 0)
		)
		(polygon
			(pts
				(arc
					(start 259.430266 -276.571456)
					(mid 259.445145 -276.607377)
					(end 259.481066 -276.622256)
				)
				(arc
					(start 260.880606 -276.622256)
					(mid 260.916527 -276.607377)
					(end 260.931406 -276.571456)
				)
				(arc
					(start 260.931406 -276.162516)
					(mid 260.916527 -276.126595)
					(end 260.880606 -276.111716)
				)
				(arc
					(start 259.481066 -276.111716)
					(mid 259.445145 -276.126595)
					(end 259.430266 -276.162516)
				)
			)
		)
	)
	(zone
		(layers "In1.Cu" "In2.Cu")
		(hatch none 0.5)
		(connect_pads
			(clearance 0)
		)
		(min_thickness 0.25)
		(keepout
			(tracks not_allowed)
			(vias allowed)
			(pads allowed)
			(copperpour not_allowed)
			(footprints allowed)
		)
		(placement
			(enabled no)
			(sheetname "")
		)
		(fill yes
			(thermal_gap 0.5)
			(thermal_bridge_width 0.5)
			(island_removal_mode 0)
		)
		(polygon
			(pts
				(arc
					(start 308.136798 -290.171378)
					(mid 308.151677 -290.207299)
					(end 308.187598 -290.222178)
				)
				(arc
					(start 309.587138 -290.222178)
					(mid 309.623059 -290.207299)
					(end 309.637938 -290.171378)
				)
				(arc
					(start 309.637938 -289.762438)
					(mid 309.623059 -289.726517)
					(end 309.587138 -289.711638)
				)
				(arc
					(start 308.187598 -289.711638)
					(mid 308.151677 -289.726517)
					(end 308.136798 -289.762438)
				)
			)
		)
	)
	(zone
		(layers "In1.Cu" "In2.Cu")
		(hatch none 0.5)
		(connect_pads
			(clearance 0)
		)
		(min_thickness 0.25)
		(keepout
			(tracks not_allowed)
			(vias allowed)
			(pads allowed)
			(copperpour not_allowed)
			(footprints allowed)
		)
		(placement
			(enabled no)
			(sheetname "")
		)
		(fill yes
			(thermal_gap 0.5)
			(thermal_bridge_width 0.5)
			(island_removal_mode 0)
		)
		(polygon
			(pts
				(arc
					(start 7.39013 -198.37146)
					(mid 7.405009 -198.407381)
					(end 7.44093 -198.42226)
				)
				(arc
					(start 8.84047 -198.42226)
					(mid 8.876391 -198.407381)
					(end 8.89127 -198.37146)
				)
				(arc
					(start 8.89127 -197.96252)
					(mid 8.876391 -197.926599)
					(end 8.84047 -197.91172)
				)
				(arc
					(start 7.44093 -197.91172)
					(mid 7.405009 -197.926599)
					(end 7.39013 -197.96252)
				)
			)
		)
	)
	(zone
		(layers "In1.Cu" "In2.Cu")
		(hatch none 0.5)
		(connect_pads
			(clearance 0)
		)
		(min_thickness 0.25)
		(keepout
			(tracks not_allowed)
			(vias allowed)
			(pads allowed)
			(copperpour not_allowed)
			(footprints allowed)
		)
		(placement
			(enabled no)
			(sheetname "")
		)
		(fill yes
			(thermal_gap 0.5)
			(thermal_bridge_width 0.5)
			(island_removal_mode 0)
		)
		(polygon
			(pts
				(arc
					(start 277.961598 -280.821384)
					(mid 277.976477 -280.857305)
					(end 278.012398 -280.872184)
				)
				(arc
					(start 279.411938 -280.872184)
					(mid 279.447859 -280.857305)
					(end 279.462738 -280.821384)
				)
				(arc
					(start 279.462738 -280.412444)
					(mid 279.447859 -280.376523)
					(end 279.411938 -280.361644)
				)
				(arc
					(start 278.012398 -280.361644)
					(mid 277.976477 -280.376523)
					(end 277.961598 -280.412444)
				)
			)
		)
	)
	(zone
		(layers "In1.Cu" "In2.Cu")
		(hatch none 0.5)
		(connect_pads
			(clearance 0)
		)
		(min_thickness 0.25)
		(keepout
			(tracks not_allowed)
			(vias allowed)
			(pads allowed)
			(copperpour not_allowed)
			(footprints allowed)
		)
		(placement
			(enabled no)
			(sheetname "")
		)
		(fill yes
			(thermal_gap 0.5)
			(thermal_bridge_width 0.5)
			(island_removal_mode 0)
		)
		(polygon
			(pts
				(arc
					(start 199.881998 -205.171548)
					(mid 199.896877 -205.207469)
					(end 199.932798 -205.222348)
				)
				(arc
					(start 201.332338 -205.222348)
					(mid 201.368259 -205.207469)
					(end 201.383138 -205.171548)
				)
				(arc
					(start 201.383138 -204.762608)
					(mid 201.368259 -204.726687)
					(end 201.332338 -204.711808)
				)
				(arc
					(start 199.932798 -204.711808)
					(mid 199.896877 -204.726687)
					(end 199.881998 -204.762608)
				)
			)
		)
	)
	(zone
		(layers "In1.Cu" "In2.Cu")
		(hatch none 0.5)
		(connect_pads
			(clearance 0)
		)
		(min_thickness 0.25)
		(keepout
			(tracks not_allowed)
			(vias allowed)
			(pads allowed)
			(copperpour not_allowed)
			(footprints allowed)
		)
		(placement
			(enabled no)
			(sheetname "")
		)
		(fill yes
			(thermal_gap 0.5)
			(thermal_bridge_width 0.5)
			(island_removal_mode 0)
		)
		(polygon
			(pts
				(arc
					(start 255.330198 -215.371426)
					(mid 255.345077 -215.407347)
					(end 255.380998 -215.422226)
				)
				(arc
					(start 256.780538 -215.422226)
					(mid 256.816459 -215.407347)
					(end 256.831338 -215.371426)
				)
				(arc
					(start 256.831338 -214.962486)
					(mid 256.816459 -214.926565)
					(end 256.780538 -214.911686)
				)
				(arc
					(start 255.380998 -214.911686)
					(mid 255.345077 -214.926565)
					(end 255.330198 -214.962486)
				)
			)
		)
	)
	(zone
		(layers "In1.Cu" "In2.Cu")
		(hatch none 0.5)
		(connect_pads
			(clearance 0)
		)
		(min_thickness 0.25)
		(keepout
			(tracks not_allowed)
			(vias allowed)
			(pads allowed)
			(copperpour not_allowed)
			(footprints allowed)
		)
		(placement
			(enabled no)
			(sheetname "")
		)
		(fill yes
			(thermal_gap 0.5)
			(thermal_bridge_width 0.5)
			(island_removal_mode 0)
		)
		(polygon
			(pts
				(arc
					(start 26.577798 -225.571304)
					(mid 26.592677 -225.607225)
					(end 26.628598 -225.622104)
				)
				(arc
					(start 28.028138 -225.622104)
					(mid 28.064059 -225.607225)
					(end 28.078938 -225.571304)
				)
				(arc
					(start 28.078938 -225.162364)
					(mid 28.064059 -225.126443)
					(end 28.028138 -225.111564)
				)
				(arc
					(start 26.628598 -225.111564)
					(mid 26.592677 -225.126443)
					(end 26.577798 -225.162364)
				)
			)
		)
	)
	(zone
		(layers "In1.Cu" "In2.Cu")
		(hatch none 0.5)
		(connect_pads
			(clearance 0)
		)
		(min_thickness 0.25)
		(keepout
			(tracks not_allowed)
			(vias allowed)
			(pads allowed)
			(copperpour not_allowed)
			(footprints allowed)
		)
		(placement
			(enabled no)
			(sheetname "")
		)
		(fill yes
			(thermal_gap 0.5)
			(thermal_bridge_width 0.5)
			(island_removal_mode 0)
		)
		(polygon
			(pts
				(arc
					(start 56.752998 -262.121396)
					(mid 56.767877 -262.157317)
					(end 56.803798 -262.172196)
				)
				(arc
					(start 58.203338 -262.172196)
					(mid 58.239259 -262.157317)
					(end 58.254138 -262.121396)
				)
				(arc
					(start 58.254138 -261.712456)
					(mid 58.239259 -261.676535)
					(end 58.203338 -261.661656)
				)
				(arc
					(start 56.803798 -261.661656)
					(mid 56.767877 -261.676535)
					(end 56.752998 -261.712456)
				)
			)
		)
	)
	(zone
		(layers "In1.Cu" "In2.Cu")
		(hatch none 0.5)
		(connect_pads
			(clearance 0)
		)
		(min_thickness 0.25)
		(keepout
			(tracks not_allowed)
			(vias allowed)
			(pads allowed)
			(copperpour not_allowed)
			(footprints allowed)
		)
		(placement
			(enabled no)
			(sheetname "")
		)
		(fill yes
			(thermal_gap 0.5)
			(thermal_bridge_width 0.5)
			(island_removal_mode 0)
		)
		(polygon
			(pts
				(arc
					(start 282.061666 -289.321494)
					(mid 282.076545 -289.357415)
					(end 282.112466 -289.372294)
				)
				(arc
					(start 283.512006 -289.372294)
					(mid 283.547927 -289.357415)
					(end 283.562806 -289.321494)
				)
				(arc
					(start 283.562806 -288.912554)
					(mid 283.547927 -288.876633)
					(end 283.512006 -288.861754)
				)
				(arc
					(start 282.112466 -288.861754)
					(mid 282.076545 -288.876633)
					(end 282.061666 -288.912554)
				)
			)
		)
	)
	(zone
		(layers "In1.Cu" "In2.Cu")
		(hatch none 0.5)
		(connect_pads
			(clearance 0)
		)
		(min_thickness 0.25)
		(keepout
			(tracks not_allowed)
			(vias allowed)
			(pads allowed)
			(copperpour not_allowed)
			(footprints allowed)
		)
		(placement
			(enabled no)
			(sheetname "")
		)
		(fill yes
			(thermal_gap 0.5)
			(thermal_bridge_width 0.5)
			(island_removal_mode 0)
		)
		(polygon
			(pts
				(arc
					(start 11.490198 -216.22131)
					(mid 11.505077 -216.257231)
					(end 11.540998 -216.27211)
				)
				(arc
					(start 12.940538 -216.27211)
					(mid 12.976459 -216.257231)
					(end 12.991338 -216.22131)
				)
				(arc
					(start 12.991338 -215.81237)
					(mid 12.976459 -215.776449)
					(end 12.940538 -215.76157)
				)
				(arc
					(start 11.540998 -215.76157)
					(mid 11.505077 -215.776449)
					(end 11.490198 -215.81237)
				)
			)
		)
	)
	(zone
		(layers "In1.Cu" "In2.Cu")
		(hatch none 0.5)
		(connect_pads
			(clearance 0)
		)
		(min_thickness 0.25)
		(keepout
			(tracks not_allowed)
			(vias allowed)
			(pads allowed)
			(copperpour not_allowed)
			(footprints allowed)
		)
		(placement
			(enabled no)
			(sheetname "")
		)
		(fill yes
			(thermal_gap 0.5)
			(thermal_bridge_width 0.5)
			(island_removal_mode 0)
		)
		(polygon
			(pts
				(arc
					(start 421.090598 -207.721454)
					(mid 421.105477 -207.757375)
					(end 421.141398 -207.772254)
				)
				(arc
					(start 422.540938 -207.772254)
					(mid 422.576859 -207.757375)
					(end 422.591738 -207.721454)
				)
				(arc
					(start 422.591738 -207.312514)
					(mid 422.576859 -207.276593)
					(end 422.540938 -207.261714)
				)
				(arc
					(start 421.141398 -207.261714)
					(mid 421.105477 -207.276593)
					(end 421.090598 -207.312514)
				)
			)
		)
	)
	(zone
		(layers "In1.Cu" "In2.Cu")
		(hatch none 0.5)
		(connect_pads
			(clearance 0)
		)
		(min_thickness 0.25)
		(keepout
			(tracks not_allowed)
			(vias allowed)
			(pads allowed)
			(copperpour not_allowed)
			(footprints allowed)
		)
		(placement
			(enabled no)
			(sheetname "")
		)
		(fill yes
			(thermal_gap 0.5)
			(thermal_bridge_width 0.5)
			(island_removal_mode 0)
		)
		(polygon
			(pts
				(arc
					(start 199.881998 -203.471526)
					(mid 199.896877 -203.507447)
					(end 199.932798 -203.522326)
				)
				(arc
					(start 201.332338 -203.522326)
					(mid 201.368259 -203.507447)
					(end 201.383138 -203.471526)
				)
				(arc
					(start 201.383138 -203.062586)
					(mid 201.368259 -203.026665)
					(end 201.332338 -203.011786)
				)
				(arc
					(start 199.932798 -203.011786)
					(mid 199.896877 -203.026665)
					(end 199.881998 -203.062586)
				)
			)
		)
	)
	(zone
		(layers "In1.Cu" "In2.Cu")
		(hatch none 0.5)
		(connect_pads
			(clearance 0)
		)
		(min_thickness 0.25)
		(keepout
			(tracks not_allowed)
			(vias allowed)
			(pads allowed)
			(copperpour not_allowed)
			(footprints allowed)
		)
		(placement
			(enabled no)
			(sheetname "")
		)
		(fill yes
			(thermal_gap 0.5)
			(thermal_bridge_width 0.5)
			(island_removal_mode 0)
		)
		(polygon
			(pts
				(arc
					(start 210.86953 -288.471356)
					(mid 210.884409 -288.507277)
					(end 210.92033 -288.522156)
				)
				(arc
					(start 212.31987 -288.522156)
					(mid 212.355791 -288.507277)
					(end 212.37067 -288.471356)
				)
				(arc
					(start 212.37067 -288.062416)
					(mid 212.355791 -288.026495)
					(end 212.31987 -288.011616)
				)
				(arc
					(start 210.92033 -288.011616)
					(mid 210.884409 -288.026495)
					(end 210.86953 -288.062416)
				)
			)
		)
	)
	(zone
		(layers "In1.Cu" "In2.Cu")
		(hatch none 0.5)
		(connect_pads
			(clearance 0)
		)
		(min_thickness 0.25)
		(keepout
			(tracks not_allowed)
			(vias allowed)
			(pads allowed)
			(copperpour not_allowed)
			(footprints allowed)
		)
		(placement
			(enabled no)
			(sheetname "")
		)
		(fill yes
			(thermal_gap 0.5)
			(thermal_bridge_width 0.5)
			(island_removal_mode 0)
		)
		(polygon
			(pts
				(arc
					(start 22.47773 -308.871366)
					(mid 22.492609 -308.907287)
					(end 22.52853 -308.922166)
				)
				(arc
					(start 23.92807 -308.922166)
					(mid 23.963991 -308.907287)
					(end 23.97887 -308.871366)
				)
				(arc
					(start 23.97887 -308.462426)
					(mid 23.963991 -308.426505)
					(end 23.92807 -308.411626)
				)
				(arc
					(start 22.52853 -308.411626)
					(mid 22.492609 -308.426505)
					(end 22.47773 -308.462426)
				)
			)
		)
	)
	(zone
		(layers "In1.Cu" "In2.Cu")
		(hatch none 0.5)
		(connect_pads
			(clearance 0)
		)
		(min_thickness 0.25)
		(keepout
			(tracks not_allowed)
			(vias allowed)
			(pads allowed)
			(copperpour not_allowed)
			(footprints allowed)
		)
		(placement
			(enabled no)
			(sheetname "")
		)
		(fill yes
			(thermal_gap 0.5)
			(thermal_bridge_width 0.5)
			(island_removal_mode 0)
		)
		(polygon
			(pts
				(arc
					(start 308.136798 -296.121328)
					(mid 308.151677 -296.157249)
					(end 308.187598 -296.172128)
				)
				(arc
					(start 309.587138 -296.172128)
					(mid 309.623059 -296.157249)
					(end 309.637938 -296.121328)
				)
				(arc
					(start 309.637938 -295.712388)
					(mid 309.623059 -295.676467)
					(end 309.587138 -295.661588)
				)
				(arc
					(start 308.187598 -295.661588)
					(mid 308.151677 -295.676467)
					(end 308.136798 -295.712388)
				)
			)
		)
	)
	(zone
		(layers "In1.Cu" "In2.Cu")
		(hatch none 0.5)
		(connect_pads
			(clearance 0)
		)
		(min_thickness 0.25)
		(keepout
			(tracks not_allowed)
			(vias allowed)
			(pads allowed)
			(copperpour not_allowed)
			(footprints allowed)
		)
		(placement
			(enabled no)
			(sheetname "")
		)
		(fill yes
			(thermal_gap 0.5)
			(thermal_bridge_width 0.5)
			(island_removal_mode 0)
		)
		(polygon
			(pts
				(arc
					(start 308.136798 -218.77147)
					(mid 308.151677 -218.807391)
					(end 308.187598 -218.82227)
				)
				(arc
					(start 309.587138 -218.82227)
					(mid 309.623059 -218.807391)
					(end 309.637938 -218.77147)
				)
				(arc
					(start 309.637938 -218.36253)
					(mid 309.623059 -218.326609)
					(end 309.587138 -218.31173)
				)
				(arc
					(start 308.187598 -218.31173)
					(mid 308.151677 -218.326609)
					(end 308.136798 -218.36253)
				)
			)
		)
	)
	(zone
		(layers "In1.Cu" "In2.Cu")
		(hatch none 0.5)
		(connect_pads
			(clearance 0)
		)
		(min_thickness 0.25)
		(keepout
			(tracks not_allowed)
			(vias allowed)
			(pads allowed)
			(copperpour not_allowed)
			(footprints allowed)
		)
		(placement
			(enabled no)
			(sheetname "")
		)
		(fill yes
			(thermal_gap 0.5)
			(thermal_bridge_width 0.5)
			(island_removal_mode 0)
		)
		(polygon
			(pts
				(arc
					(start 417.646866 -313.971432)
					(mid 417.661745 -314.007353)
					(end 417.697666 -314.022232)
				)
				(arc
					(start 419.097206 -314.022232)
					(mid 419.133127 -314.007353)
					(end 419.148006 -313.971432)
				)
				(arc
					(start 419.148006 -313.562492)
					(mid 419.133127 -313.526571)
					(end 419.097206 -313.511692)
				)
				(arc
					(start 417.697666 -313.511692)
					(mid 417.661745 -313.526571)
					(end 417.646866 -313.562492)
				)
			)
		)
	)
	(zone
		(layers "In1.Cu" "In2.Cu")
		(hatch none 0.5)
		(connect_pads
			(clearance 0)
		)
		(min_thickness 0.25)
		(keepout
			(tracks not_allowed)
			(vias allowed)
			(pads allowed)
			(copperpour not_allowed)
			(footprints allowed)
		)
		(placement
			(enabled no)
			(sheetname "")
		)
		(fill yes
			(thermal_gap 0.5)
			(thermal_bridge_width 0.5)
			(island_removal_mode 0)
		)
		(polygon
			(pts
				(arc
					(start 304.693066 -246.821452)
					(mid 304.707945 -246.857373)
					(end 304.743866 -246.872252)
				)
				(arc
					(start 306.143406 -246.872252)
					(mid 306.179327 -246.857373)
					(end 306.194206 -246.821452)
				)
				(arc
					(start 306.194206 -246.412512)
					(mid 306.179327 -246.376591)
					(end 306.143406 -246.361712)
				)
				(arc
					(start 304.743866 -246.361712)
					(mid 304.707945 -246.376591)
					(end 304.693066 -246.412512)
				)
			)
		)
	)
	(zone
		(layers "In1.Cu" "In2.Cu")
		(hatch none 0.5)
		(connect_pads
			(clearance 0)
		)
		(min_thickness 0.25)
		(keepout
			(tracks not_allowed)
			(vias allowed)
			(pads allowed)
			(copperpour not_allowed)
			(footprints allowed)
		)
		(placement
			(enabled no)
			(sheetname "")
		)
		(fill yes
			(thermal_gap 0.5)
			(thermal_bridge_width 0.5)
			(island_removal_mode 0)
		)
		(polygon
			(pts
				(arc
					(start 308.136798 -240.021364)
					(mid 308.151677 -240.057285)
					(end 308.187598 -240.072164)
				)
				(arc
					(start 309.587138 -240.072164)
					(mid 309.623059 -240.057285)
					(end 309.637938 -240.021364)
				)
				(arc
					(start 309.637938 -239.612424)
					(mid 309.623059 -239.576503)
					(end 309.587138 -239.561624)
				)
				(arc
					(start 308.187598 -239.561624)
					(mid 308.151677 -239.576503)
					(end 308.136798 -239.612424)
				)
			)
		)
	)
	(zone
		(layers "In1.Cu" "In2.Cu")
		(hatch none 0.5)
		(connect_pads
			(clearance 0)
		)
		(min_thickness 0.25)
		(keepout
			(tracks not_allowed)
			(vias allowed)
			(pads allowed)
			(copperpour not_allowed)
			(footprints allowed)
		)
		(placement
			(enabled no)
			(sheetname "")
		)
		(fill yes
			(thermal_gap 0.5)
			(thermal_bridge_width 0.5)
			(island_removal_mode 0)
		)
		(polygon
			(pts
				(arc
					(start 49.209198 -205.171548)
					(mid 49.224077 -205.207469)
					(end 49.259998 -205.222348)
				)
				(arc
					(start 50.659538 -205.222348)
					(mid 50.695459 -205.207469)
					(end 50.710338 -205.171548)
				)
				(arc
					(start 50.710338 -204.762608)
					(mid 50.695459 -204.726687)
					(end 50.659538 -204.711808)
				)
				(arc
					(start 49.259998 -204.711808)
					(mid 49.224077 -204.726687)
					(end 49.209198 -204.762608)
				)
			)
		)
	)
	(zone
		(layers "In1.Cu" "In2.Cu")
		(hatch none 0.5)
		(connect_pads
			(clearance 0)
		)
		(min_thickness 0.25)
		(keepout
			(tracks not_allowed)
			(vias allowed)
			(pads allowed)
			(copperpour not_allowed)
			(footprints allowed)
		)
		(placement
			(enabled no)
			(sheetname "")
		)
		(fill yes
			(thermal_gap 0.5)
			(thermal_bridge_width 0.5)
			(island_removal_mode 0)
		)
		(polygon
			(pts
				(arc
					(start 413.546798 -307.171344)
					(mid 413.561677 -307.207265)
					(end 413.597598 -307.222144)
				)
				(arc
					(start 414.997138 -307.222144)
					(mid 415.033059 -307.207265)
					(end 415.047938 -307.171344)
				)
				(arc
					(start 415.047938 -306.762404)
					(mid 415.033059 -306.726483)
					(end 414.997138 -306.711604)
				)
				(arc
					(start 413.597598 -306.711604)
					(mid 413.561677 -306.726483)
					(end 413.546798 -306.762404)
				)
			)
		)
	)
	(zone
		(layers "In1.Cu" "In2.Cu")
		(hatch none 0.5)
		(connect_pads
			(clearance 0)
		)
		(min_thickness 0.25)
		(keepout
			(tracks not_allowed)
			(vias allowed)
			(pads allowed)
			(copperpour not_allowed)
			(footprints allowed)
		)
		(placement
			(enabled no)
			(sheetname "")
		)
		(fill yes
			(thermal_gap 0.5)
			(thermal_bridge_width 0.5)
			(island_removal_mode 0)
		)
		(polygon
			(pts
				(arc
					(start 300.592998 -235.771436)
					(mid 300.607877 -235.807357)
					(end 300.643798 -235.822236)
				)
				(arc
					(start 302.043338 -235.822236)
					(mid 302.079259 -235.807357)
					(end 302.094138 -235.771436)
				)
				(arc
					(start 302.094138 -235.362496)
					(mid 302.079259 -235.326575)
					(end 302.043338 -235.311696)
				)
				(arc
					(start 300.643798 -235.311696)
					(mid 300.607877 -235.326575)
					(end 300.592998 -235.362496)
				)
			)
		)
	)
	(zone
		(layers "In1.Cu" "In2.Cu")
		(hatch none 0.5)
		(connect_pads
			(clearance 0)
		)
		(min_thickness 0.25)
		(keepout
			(tracks not_allowed)
			(vias allowed)
			(pads allowed)
			(copperpour not_allowed)
			(footprints allowed)
		)
		(placement
			(enabled no)
			(sheetname "")
		)
		(fill yes
			(thermal_gap 0.5)
			(thermal_bridge_width 0.5)
			(island_removal_mode 0)
		)
		(polygon
			(pts
				(arc
					(start 169.706798 -285.92145)
					(mid 169.721677 -285.957371)
					(end 169.757598 -285.97225)
				)
				(arc
					(start 171.157138 -285.97225)
					(mid 171.193059 -285.957371)
					(end 171.207938 -285.92145)
				)
				(arc
					(start 171.207938 -285.51251)
					(mid 171.193059 -285.476589)
					(end 171.157138 -285.46171)
				)
				(arc
					(start 169.757598 -285.46171)
					(mid 169.721677 -285.476589)
					(end 169.706798 -285.51251)
				)
			)
		)
	)
	(zone
		(layers "In1.Cu" "In2.Cu")
		(hatch none 0.5)
		(connect_pads
			(clearance 0)
		)
		(min_thickness 0.25)
		(keepout
			(tracks not_allowed)
			(vias allowed)
			(pads allowed)
			(copperpour not_allowed)
			(footprints allowed)
		)
		(placement
			(enabled no)
			(sheetname "")
		)
		(fill yes
			(thermal_gap 0.5)
			(thermal_bridge_width 0.5)
			(island_removal_mode 0)
		)
		(polygon
			(pts
				(arc
					(start 26.577798 -291.021516)
					(mid 26.592677 -291.057437)
					(end 26.628598 -291.072316)
				)
				(arc
					(start 28.028138 -291.072316)
					(mid 28.064059 -291.057437)
					(end 28.078938 -291.021516)
				)
				(arc
					(start 28.078938 -290.612576)
					(mid 28.064059 -290.576655)
					(end 28.028138 -290.561776)
				)
				(arc
					(start 26.628598 -290.561776)
					(mid 26.592677 -290.576655)
					(end 26.577798 -290.612576)
				)
			)
		)
	)
	(zone
		(layers "In1.Cu" "In2.Cu")
		(hatch none 0.5)
		(connect_pads
			(clearance 0)
		)
		(min_thickness 0.25)
		(keepout
			(tracks not_allowed)
			(vias allowed)
			(pads allowed)
			(copperpour not_allowed)
			(footprints allowed)
		)
		(placement
			(enabled no)
			(sheetname "")
		)
		(fill yes
			(thermal_gap 0.5)
			(thermal_bridge_width 0.5)
			(island_removal_mode 0)
		)
		(polygon
			(pts
				(arc
					(start 417.646866 -281.671522)
					(mid 417.661745 -281.707443)
					(end 417.697666 -281.722322)
				)
				(arc
					(start 419.097206 -281.722322)
					(mid 419.133127 -281.707443)
					(end 419.148006 -281.671522)
				)
				(arc
					(start 419.148006 -281.262582)
					(mid 419.133127 -281.226661)
					(end 419.097206 -281.211782)
				)
				(arc
					(start 417.697666 -281.211782)
					(mid 417.661745 -281.226661)
					(end 417.646866 -281.262582)
				)
			)
		)
	)
	(zone
		(layers "In1.Cu" "In2.Cu")
		(hatch none 0.5)
		(connect_pads
			(clearance 0)
		)
		(min_thickness 0.25)
		(keepout
			(tracks not_allowed)
			(vias allowed)
			(pads allowed)
			(copperpour not_allowed)
			(footprints allowed)
		)
		(placement
			(enabled no)
			(sheetname "")
		)
		(fill yes
			(thermal_gap 0.5)
			(thermal_bridge_width 0.5)
			(island_removal_mode 0)
		)
		(polygon
			(pts
				(arc
					(start 158.06293 -209.421476)
					(mid 158.077809 -209.457397)
					(end 158.11373 -209.472276)
				)
				(arc
					(start 159.51327 -209.472276)
					(mid 159.549191 -209.457397)
					(end 159.56407 -209.421476)
				)
				(arc
					(start 159.56407 -209.012536)
					(mid 159.549191 -208.976615)
					(end 159.51327 -208.961736)
				)
				(arc
					(start 158.11373 -208.961736)
					(mid 158.077809 -208.976615)
					(end 158.06293 -209.012536)
				)
			)
		)
	)
	(zone
		(layers "In1.Cu" "In2.Cu")
		(hatch none 0.5)
		(connect_pads
			(clearance 0)
		)
		(min_thickness 0.25)
		(keepout
			(tracks not_allowed)
			(vias allowed)
			(pads allowed)
			(copperpour not_allowed)
			(footprints allowed)
		)
		(placement
			(enabled no)
			(sheetname "")
		)
		(fill yes
			(thermal_gap 0.5)
			(thermal_bridge_width 0.5)
			(island_removal_mode 0)
		)
		(polygon
			(pts
				(arc
					(start 436.178198 -313.121294)
					(mid 436.193077 -313.157215)
					(end 436.228998 -313.172094)
				)
				(arc
					(start 437.628538 -313.172094)
					(mid 437.664459 -313.157215)
					(end 437.679338 -313.121294)
				)
				(arc
					(start 437.679338 -312.712354)
					(mid 437.664459 -312.676433)
					(end 437.628538 -312.661554)
				)
				(arc
					(start 436.228998 -312.661554)
					(mid 436.193077 -312.676433)
					(end 436.178198 -312.712354)
				)
			)
		)
	)
	(zone
		(layers "In1.Cu" "In2.Cu")
		(hatch none 0.5)
		(connect_pads
			(clearance 0)
		)
		(min_thickness 0.25)
		(keepout
			(tracks not_allowed)
			(vias allowed)
			(pads allowed)
			(copperpour not_allowed)
			(footprints allowed)
		)
		(placement
			(enabled no)
			(sheetname "")
		)
		(fill yes
			(thermal_gap 0.5)
			(thermal_bridge_width 0.5)
			(island_removal_mode 0)
		)
		(polygon
			(pts
				(arc
					(start 169.706798 -300.37151)
					(mid 169.721677 -300.407431)
					(end 169.757598 -300.42231)
				)
				(arc
					(start 171.157138 -300.42231)
					(mid 171.193059 -300.407431)
					(end 171.207938 -300.37151)
				)
				(arc
					(start 171.207938 -299.96257)
					(mid 171.193059 -299.926649)
					(end 171.157138 -299.91177)
				)
				(arc
					(start 169.757598 -299.91177)
					(mid 169.721677 -299.926649)
					(end 169.706798 -299.96257)
				)
			)
		)
	)
	(zone
		(layers "In1.Cu" "In2.Cu")
		(hatch none 0.5)
		(connect_pads
			(clearance 0)
		)
		(min_thickness 0.25)
		(keepout
			(tracks not_allowed)
			(vias allowed)
			(pads allowed)
			(copperpour not_allowed)
			(footprints allowed)
		)
		(placement
			(enabled no)
			(sheetname "")
		)
		(fill yes
			(thermal_gap 0.5)
			(thermal_bridge_width 0.5)
			(island_removal_mode 0)
		)
		(polygon
			(pts
				(arc
					(start 455.365866 -284.221428)
					(mid 455.380745 -284.257349)
					(end 455.416666 -284.272228)
				)
				(arc
					(start 456.816206 -284.272228)
					(mid 456.852127 -284.257349)
					(end 456.867006 -284.221428)
				)
				(arc
					(start 456.867006 -283.812488)
					(mid 456.852127 -283.776567)
					(end 456.816206 -283.761688)
				)
				(arc
					(start 455.416666 -283.761688)
					(mid 455.380745 -283.776567)
					(end 455.365866 -283.812488)
				)
			)
		)
	)
	(zone
		(layers "In1.Cu" "In2.Cu")
		(hatch none 0.5)
		(connect_pads
			(clearance 0)
		)
		(min_thickness 0.25)
		(keepout
			(tracks not_allowed)
			(vias allowed)
			(pads allowed)
			(copperpour not_allowed)
			(footprints allowed)
		)
		(placement
			(enabled no)
			(sheetname "")
		)
		(fill yes
			(thermal_gap 0.5)
			(thermal_bridge_width 0.5)
			(island_removal_mode 0)
		)
		(polygon
			(pts
				(arc
					(start 11.490198 -223.871536)
					(mid 11.505077 -223.907457)
					(end 11.540998 -223.922336)
				)
				(arc
					(start 12.940538 -223.922336)
					(mid 12.976459 -223.907457)
					(end 12.991338 -223.871536)
				)
				(arc
					(start 12.991338 -223.462596)
					(mid 12.976459 -223.426675)
					(end 12.940538 -223.411796)
				)
				(arc
					(start 11.540998 -223.411796)
					(mid 11.505077 -223.426675)
					(end 11.490198 -223.462596)
				)
			)
		)
	)
	(zone
		(layers "In1.Cu" "In2.Cu")
		(hatch none 0.5)
		(connect_pads
			(clearance 0)
		)
		(min_thickness 0.25)
		(keepout
			(tracks not_allowed)
			(vias allowed)
			(pads allowed)
			(copperpour not_allowed)
			(footprints allowed)
		)
		(placement
			(enabled no)
			(sheetname "")
		)
		(fill yes
			(thermal_gap 0.5)
			(thermal_bridge_width 0.5)
			(island_removal_mode 0)
		)
		(polygon
			(pts
				(arc
					(start 207.425798 -289.321494)
					(mid 207.440677 -289.357415)
					(end 207.476598 -289.372294)
				)
				(arc
					(start 208.876138 -289.372294)
					(mid 208.912059 -289.357415)
					(end 208.926938 -289.321494)
				)
				(arc
					(start 208.926938 -288.912554)
					(mid 208.912059 -288.876633)
					(end 208.876138 -288.861754)
				)
				(arc
					(start 207.476598 -288.861754)
					(mid 207.440677 -288.876633)
					(end 207.425798 -288.912554)
				)
			)
		)
	)
	(zone
		(layers "In1.Cu" "In2.Cu")
		(hatch none 0.5)
		(connect_pads
			(clearance 0)
		)
		(min_thickness 0.25)
		(keepout
			(tracks not_allowed)
			(vias allowed)
			(pads allowed)
			(copperpour not_allowed)
			(footprints allowed)
		)
		(placement
			(enabled no)
			(sheetname "")
		)
		(fill yes
			(thermal_gap 0.5)
			(thermal_bridge_width 0.5)
			(island_removal_mode 0)
		)
		(polygon
			(pts
				(arc
					(start 285.505398 -252.771402)
					(mid 285.520277 -252.807323)
					(end 285.556198 -252.822202)
				)
				(arc
					(start 286.955738 -252.822202)
					(mid 286.991659 -252.807323)
					(end 287.006538 -252.771402)
				)
				(arc
					(start 287.006538 -252.362462)
					(mid 286.991659 -252.326541)
					(end 286.955738 -252.311662)
				)
				(arc
					(start 285.556198 -252.311662)
					(mid 285.520277 -252.326541)
					(end 285.505398 -252.362462)
				)
			)
		)
	)
	(zone
		(layers "In1.Cu" "In2.Cu")
		(hatch none 0.5)
		(connect_pads
			(clearance 0)
		)
		(min_thickness 0.25)
		(keepout
			(tracks not_allowed)
			(vias allowed)
			(pads allowed)
			(copperpour not_allowed)
			(footprints allowed)
		)
		(placement
			(enabled no)
			(sheetname "")
		)
		(fill yes
			(thermal_gap 0.5)
			(thermal_bridge_width 0.5)
			(island_removal_mode 0)
		)
		(polygon
			(pts
				(arc
					(start 406.002998 -297.82135)
					(mid 406.017877 -297.857271)
					(end 406.053798 -297.87215)
				)
				(arc
					(start 407.453338 -297.87215)
					(mid 407.489259 -297.857271)
					(end 407.504138 -297.82135)
				)
				(arc
					(start 407.504138 -297.41241)
					(mid 407.489259 -297.376489)
					(end 407.453338 -297.36161)
				)
				(arc
					(start 406.053798 -297.36161)
					(mid 406.017877 -297.376489)
					(end 406.002998 -297.41241)
				)
			)
		)
	)
	(zone
		(layers "In1.Cu" "In2.Cu")
		(hatch none 0.5)
		(connect_pads
			(clearance 0)
		)
		(min_thickness 0.25)
		(keepout
			(tracks not_allowed)
			(vias allowed)
			(pads allowed)
			(copperpour not_allowed)
			(footprints allowed)
		)
		(placement
			(enabled no)
			(sheetname "")
		)
		(fill yes
			(thermal_gap 0.5)
			(thermal_bridge_width 0.5)
			(island_removal_mode 0)
		)
		(polygon
			(pts
				(arc
					(start 192.338198 -289.321494)
					(mid 192.353077 -289.357415)
					(end 192.388998 -289.372294)
				)
				(arc
					(start 193.788538 -289.372294)
					(mid 193.824459 -289.357415)
					(end 193.839338 -289.321494)
				)
				(arc
					(start 193.839338 -288.912554)
					(mid 193.824459 -288.876633)
					(end 193.788538 -288.861754)
				)
				(arc
					(start 192.388998 -288.861754)
					(mid 192.353077 -288.876633)
					(end 192.338198 -288.912554)
				)
			)
		)
	)
	(zone
		(layers "In1.Cu" "In2.Cu")
		(hatch none 0.5)
		(connect_pads
			(clearance 0)
		)
		(min_thickness 0.25)
		(keepout
			(tracks not_allowed)
			(vias allowed)
			(pads allowed)
			(copperpour not_allowed)
			(footprints allowed)
		)
		(placement
			(enabled no)
			(sheetname "")
		)
		(fill yes
			(thermal_gap 0.5)
			(thermal_bridge_width 0.5)
			(island_removal_mode 0)
		)
		(polygon
			(pts
				(arc
					(start 428.634398 -313.121294)
					(mid 428.649277 -313.157215)
					(end 428.685198 -313.172094)
				)
				(arc
					(start 430.084738 -313.172094)
					(mid 430.120659 -313.157215)
					(end 430.135538 -313.121294)
				)
				(arc
					(start 430.135538 -312.712354)
					(mid 430.120659 -312.676433)
					(end 430.084738 -312.661554)
				)
				(arc
					(start 428.685198 -312.661554)
					(mid 428.649277 -312.676433)
					(end 428.634398 -312.712354)
				)
			)
		)
	)
	(zone
		(layers "In1.Cu" "In2.Cu")
		(hatch none 0.5)
		(connect_pads
			(clearance 0)
		)
		(min_thickness 0.25)
		(keepout
			(tracks not_allowed)
			(vias allowed)
			(pads allowed)
			(copperpour not_allowed)
			(footprints allowed)
		)
		(placement
			(enabled no)
			(sheetname "")
		)
		(fill yes
			(thermal_gap 0.5)
			(thermal_bridge_width 0.5)
			(island_removal_mode 0)
		)
		(polygon
			(pts
				(arc
					(start 297.149266 -285.92145)
					(mid 297.164145 -285.957371)
					(end 297.200066 -285.97225)
				)
				(arc
					(start 298.599606 -285.97225)
					(mid 298.635527 -285.957371)
					(end 298.650406 -285.92145)
				)
				(arc
					(start 298.650406 -285.51251)
					(mid 298.635527 -285.476589)
					(end 298.599606 -285.46171)
				)
				(arc
					(start 297.200066 -285.46171)
					(mid 297.164145 -285.476589)
					(end 297.149266 -285.51251)
				)
			)
		)
	)
	(zone
		(layers "In1.Cu" "In2.Cu")
		(hatch none 0.5)
		(connect_pads
			(clearance 0)
		)
		(min_thickness 0.25)
		(keepout
			(tracks not_allowed)
			(vias allowed)
			(pads allowed)
			(copperpour not_allowed)
			(footprints allowed)
		)
		(placement
			(enabled no)
			(sheetname "")
		)
		(fill yes
			(thermal_gap 0.5)
			(thermal_bridge_width 0.5)
			(island_removal_mode 0)
		)
		(polygon
			(pts
				(arc
					(start 300.592998 -200.921366)
					(mid 300.607877 -200.957287)
					(end 300.643798 -200.972166)
				)
				(arc
					(start 302.043338 -200.972166)
					(mid 302.079259 -200.957287)
					(end 302.094138 -200.921366)
				)
				(arc
					(start 302.094138 -200.512426)
					(mid 302.079259 -200.476505)
					(end 302.043338 -200.461626)
				)
				(arc
					(start 300.643798 -200.461626)
					(mid 300.607877 -200.476505)
					(end 300.592998 -200.512426)
				)
			)
		)
	)
	(zone
		(layers "In1.Cu" "In2.Cu")
		(hatch none 0.5)
		(connect_pads
			(clearance 0)
		)
		(min_thickness 0.25)
		(keepout
			(tracks not_allowed)
			(vias allowed)
			(pads allowed)
			(copperpour not_allowed)
			(footprints allowed)
		)
		(placement
			(enabled no)
			(sheetname "")
		)
		(fill yes
			(thermal_gap 0.5)
			(thermal_bridge_width 0.5)
			(island_removal_mode 0)
		)
		(polygon
			(pts
				(arc
					(start 428.634398 -264.671302)
					(mid 428.649277 -264.707223)
					(end 428.685198 -264.722102)
				)
				(arc
					(start 430.084738 -264.722102)
					(mid 430.120659 -264.707223)
					(end 430.135538 -264.671302)
				)
				(arc
					(start 430.135538 -264.262362)
					(mid 430.120659 -264.226441)
					(end 430.084738 -264.211562)
				)
				(arc
					(start 428.685198 -264.211562)
					(mid 428.649277 -264.226441)
					(end 428.634398 -264.262362)
				)
			)
		)
	)
	(zone
		(layers "In1.Cu" "In2.Cu")
		(hatch none 0.5)
		(connect_pads
			(clearance 0)
		)
		(min_thickness 0.25)
		(keepout
			(tracks not_allowed)
			(vias allowed)
			(pads allowed)
			(copperpour not_allowed)
			(footprints allowed)
		)
		(placement
			(enabled no)
			(sheetname "")
		)
		(fill yes
			(thermal_gap 0.5)
			(thermal_bridge_width 0.5)
			(island_removal_mode 0)
		)
		(polygon
			(pts
				(arc
					(start 413.546798 -198.37146)
					(mid 413.561677 -198.407381)
					(end 413.597598 -198.42226)
				)
				(arc
					(start 414.997138 -198.42226)
					(mid 415.033059 -198.407381)
					(end 415.047938 -198.37146)
				)
				(arc
					(start 415.047938 -197.96252)
					(mid 415.033059 -197.926599)
					(end 414.997138 -197.91172)
				)
				(arc
					(start 413.597598 -197.91172)
					(mid 413.561677 -197.926599)
					(end 413.546798 -197.96252)
				)
			)
		)
	)
	(zone
		(layers "In1.Cu" "In2.Cu")
		(hatch none 0.5)
		(connect_pads
			(clearance 0)
		)
		(min_thickness 0.25)
		(keepout
			(tracks not_allowed)
			(vias allowed)
			(pads allowed)
			(copperpour not_allowed)
			(footprints allowed)
		)
		(placement
			(enabled no)
			(sheetname "")
		)
		(fill yes
			(thermal_gap 0.5)
			(thermal_bridge_width 0.5)
			(island_removal_mode 0)
		)
		(polygon
			(pts
				(arc
					(start 180.69433 -290.171378)
					(mid 180.709209 -290.207299)
					(end 180.74513 -290.222178)
				)
				(arc
					(start 182.14467 -290.222178)
					(mid 182.180591 -290.207299)
					(end 182.19547 -290.171378)
				)
				(arc
					(start 182.19547 -289.762438)
					(mid 182.180591 -289.726517)
					(end 182.14467 -289.711638)
				)
				(arc
					(start 180.74513 -289.711638)
					(mid 180.709209 -289.726517)
					(end 180.69433 -289.762438)
				)
			)
		)
	)
	(zone
		(layers "In1.Cu" "In2.Cu")
		(hatch none 0.5)
		(connect_pads
			(clearance 0)
		)
		(min_thickness 0.25)
		(keepout
			(tracks not_allowed)
			(vias allowed)
			(pads allowed)
			(copperpour not_allowed)
			(footprints allowed)
		)
		(placement
			(enabled no)
			(sheetname "")
		)
		(fill yes
			(thermal_gap 0.5)
			(thermal_bridge_width 0.5)
			(island_removal_mode 0)
		)
		(polygon
			(pts
				(arc
					(start 300.592998 -226.421442)
					(mid 300.607877 -226.457363)
					(end 300.643798 -226.472242)
				)
				(arc
					(start 302.043338 -226.472242)
					(mid 302.079259 -226.457363)
					(end 302.094138 -226.421442)
				)
				(arc
					(start 302.094138 -226.012502)
					(mid 302.079259 -225.976581)
					(end 302.043338 -225.961702)
				)
				(arc
					(start 300.643798 -225.961702)
					(mid 300.607877 -225.976581)
					(end 300.592998 -226.012502)
				)
			)
		)
	)
	(zone
		(layers "In1.Cu" "In2.Cu")
		(hatch none 0.5)
		(connect_pads
			(clearance 0)
		)
		(min_thickness 0.25)
		(keepout
			(tracks not_allowed)
			(vias allowed)
			(pads allowed)
			(copperpour not_allowed)
			(footprints allowed)
		)
		(placement
			(enabled no)
			(sheetname "")
		)
		(fill yes
			(thermal_gap 0.5)
			(thermal_bridge_width 0.5)
			(island_removal_mode 0)
		)
		(polygon
			(pts
				(arc
					(start 406.002998 -303.7713)
					(mid 406.017877 -303.807221)
					(end 406.053798 -303.8221)
				)
				(arc
					(start 407.453338 -303.8221)
					(mid 407.489259 -303.807221)
					(end 407.504138 -303.7713)
				)
				(arc
					(start 407.504138 -303.36236)
					(mid 407.489259 -303.326439)
					(end 407.453338 -303.31156)
				)
				(arc
					(start 406.053798 -303.31156)
					(mid 406.017877 -303.326439)
					(end 406.002998 -303.36236)
				)
			)
		)
	)
	(zone
		(layers "In1.Cu" "In2.Cu")
		(hatch none 0.5)
		(connect_pads
			(clearance 0)
		)
		(min_thickness 0.25)
		(keepout
			(tracks not_allowed)
			(vias allowed)
			(pads allowed)
			(copperpour not_allowed)
			(footprints allowed)
		)
		(placement
			(enabled no)
			(sheetname "")
		)
		(fill yes
			(thermal_gap 0.5)
			(thermal_bridge_width 0.5)
			(island_removal_mode 0)
		)
		(polygon
			(pts
				(arc
					(start 165.60673 -275.721318)
					(mid 165.621609 -275.757239)
					(end 165.65753 -275.772118)
				)
				(arc
					(start 167.05707 -275.772118)
					(mid 167.092991 -275.757239)
					(end 167.10787 -275.721318)
				)
				(arc
					(start 167.10787 -275.312378)
					(mid 167.092991 -275.276457)
					(end 167.05707 -275.261578)
				)
				(arc
					(start 165.65753 -275.261578)
					(mid 165.621609 -275.276457)
					(end 165.60673 -275.312378)
				)
			)
		)
	)
	(zone
		(layers "In1.Cu" "In2.Cu")
		(hatch none 0.5)
		(connect_pads
			(clearance 0)
		)
		(min_thickness 0.25)
		(keepout
			(tracks not_allowed)
			(vias allowed)
			(pads allowed)
			(copperpour not_allowed)
			(footprints allowed)
		)
		(placement
			(enabled no)
			(sheetname "")
		)
		(fill yes
			(thermal_gap 0.5)
			(thermal_bridge_width 0.5)
			(island_removal_mode 0)
		)
		(polygon
			(pts
				(arc
					(start 410.103066 -197.521322)
					(mid 410.117945 -197.557243)
					(end 410.153866 -197.572122)
				)
				(arc
					(start 411.553406 -197.572122)
					(mid 411.589327 -197.557243)
					(end 411.604206 -197.521322)
				)
				(arc
					(start 411.604206 -197.112382)
					(mid 411.589327 -197.076461)
					(end 411.553406 -197.061582)
				)
				(arc
					(start 410.153866 -197.061582)
					(mid 410.117945 -197.076461)
					(end 410.103066 -197.112382)
				)
			)
		)
	)
	(zone
		(layers "In1.Cu" "In2.Cu")
		(hatch none 0.5)
		(connect_pads
			(clearance 0)
		)
		(min_thickness 0.25)
		(keepout
			(tracks not_allowed)
			(vias allowed)
			(pads allowed)
			(copperpour not_allowed)
			(footprints allowed)
		)
		(placement
			(enabled no)
			(sheetname "")
		)
		(fill yes
			(thermal_gap 0.5)
			(thermal_bridge_width 0.5)
			(island_removal_mode 0)
		)
		(polygon
			(pts
				(arc
					(start 300.592998 -210.27136)
					(mid 300.607877 -210.307281)
					(end 300.643798 -210.32216)
				)
				(arc
					(start 302.043338 -210.32216)
					(mid 302.079259 -210.307281)
					(end 302.094138 -210.27136)
				)
				(arc
					(start 302.094138 -209.86242)
					(mid 302.079259 -209.826499)
					(end 302.043338 -209.81162)
				)
				(arc
					(start 300.643798 -209.81162)
					(mid 300.607877 -209.826499)
					(end 300.592998 -209.86242)
				)
			)
		)
	)
	(zone
		(layers "In1.Cu" "In2.Cu")
		(hatch none 0.5)
		(connect_pads
			(clearance 0)
		)
		(min_thickness 0.25)
		(keepout
			(tracks not_allowed)
			(vias allowed)
			(pads allowed)
			(copperpour not_allowed)
			(footprints allowed)
		)
		(placement
			(enabled no)
			(sheetname "")
		)
		(fill yes
			(thermal_gap 0.5)
			(thermal_bridge_width 0.5)
			(island_removal_mode 0)
		)
		(polygon
			(pts
				(arc
					(start 41.665398 -291.021516)
					(mid 41.680277 -291.057437)
					(end 41.716198 -291.072316)
				)
				(arc
					(start 43.115738 -291.072316)
					(mid 43.151659 -291.057437)
					(end 43.166538 -291.021516)
				)
				(arc
					(start 43.166538 -290.612576)
					(mid 43.151659 -290.576655)
					(end 43.115738 -290.561776)
				)
				(arc
					(start 41.716198 -290.561776)
					(mid 41.680277 -290.576655)
					(end 41.665398 -290.612576)
				)
			)
		)
	)
	(zone
		(layers "In1.Cu" "In2.Cu")
		(hatch none 0.5)
		(connect_pads
			(clearance 0)
		)
		(min_thickness 0.25)
		(keepout
			(tracks not_allowed)
			(vias allowed)
			(pads allowed)
			(copperpour not_allowed)
			(footprints allowed)
		)
		(placement
			(enabled no)
			(sheetname "")
		)
		(fill yes
			(thermal_gap 0.5)
			(thermal_bridge_width 0.5)
			(island_removal_mode 0)
		)
		(polygon
			(pts
				(arc
					(start 177.250598 -302.921416)
					(mid 177.265477 -302.957337)
					(end 177.301398 -302.972216)
				)
				(arc
					(start 178.700938 -302.972216)
					(mid 178.736859 -302.957337)
					(end 178.751738 -302.921416)
				)
				(arc
					(start 178.751738 -302.512476)
					(mid 178.736859 -302.476555)
					(end 178.700938 -302.461676)
				)
				(arc
					(start 177.301398 -302.461676)
					(mid 177.265477 -302.476555)
					(end 177.250598 -302.512476)
				)
			)
		)
	)
	(zone
		(layers "In1.Cu" "In2.Cu")
		(hatch none 0.5)
		(connect_pads
			(clearance 0)
		)
		(min_thickness 0.25)
		(keepout
			(tracks not_allowed)
			(vias allowed)
			(pads allowed)
			(copperpour not_allowed)
			(footprints allowed)
		)
		(placement
			(enabled no)
			(sheetname "")
		)
		(fill yes
			(thermal_gap 0.5)
			(thermal_bridge_width 0.5)
			(island_removal_mode 0)
		)
		(polygon
			(pts
				(arc
					(start 192.338198 -246.821452)
					(mid 192.353077 -246.857373)
					(end 192.388998 -246.872252)
				)
				(arc
					(start 193.788538 -246.872252)
					(mid 193.824459 -246.857373)
					(end 193.839338 -246.821452)
				)
				(arc
					(start 193.839338 -246.412512)
					(mid 193.824459 -246.376591)
					(end 193.788538 -246.361712)
				)
				(arc
					(start 192.388998 -246.361712)
					(mid 192.353077 -246.376591)
					(end 192.338198 -246.412512)
				)
			)
		)
	)
	(zone
		(layers "In1.Cu" "In2.Cu")
		(hatch none 0.5)
		(connect_pads
			(clearance 0)
		)
		(min_thickness 0.25)
		(keepout
			(tracks not_allowed)
			(vias allowed)
			(pads allowed)
			(copperpour not_allowed)
			(footprints allowed)
		)
		(placement
			(enabled no)
			(sheetname "")
		)
		(fill yes
			(thermal_gap 0.5)
			(thermal_bridge_width 0.5)
			(island_removal_mode 0)
		)
		(polygon
			(pts
				(arc
					(start 432.734466 -272.321528)
					(mid 432.749345 -272.357449)
					(end 432.785266 -272.372328)
				)
				(arc
					(start 434.184806 -272.372328)
					(mid 434.220727 -272.357449)
					(end 434.235606 -272.321528)
				)
				(arc
					(start 434.235606 -271.912588)
					(mid 434.220727 -271.876667)
					(end 434.184806 -271.861788)
				)
				(arc
					(start 432.785266 -271.861788)
					(mid 432.749345 -271.876667)
					(end 432.734466 -271.912588)
				)
			)
		)
	)
	(zone
		(layers "In1.Cu" "In2.Cu")
		(hatch none 0.5)
		(connect_pads
			(clearance 0)
		)
		(min_thickness 0.25)
		(keepout
			(tracks not_allowed)
			(vias allowed)
			(pads allowed)
			(copperpour not_allowed)
			(footprints allowed)
		)
		(placement
			(enabled no)
			(sheetname "")
		)
		(fill yes
			(thermal_gap 0.5)
			(thermal_bridge_width 0.5)
			(island_removal_mode 0)
		)
		(polygon
			(pts
				(arc
					(start 34.121598 -218.77147)
					(mid 34.136477 -218.807391)
					(end 34.172398 -218.82227)
				)
				(arc
					(start 35.571938 -218.82227)
					(mid 35.607859 -218.807391)
					(end 35.622738 -218.77147)
				)
				(arc
					(start 35.622738 -218.36253)
					(mid 35.607859 -218.326609)
					(end 35.571938 -218.31173)
				)
				(arc
					(start 34.172398 -218.31173)
					(mid 34.136477 -218.326609)
					(end 34.121598 -218.36253)
				)
			)
		)
	)
	(zone
		(layers "In1.Cu" "In2.Cu")
		(hatch none 0.5)
		(connect_pads
			(clearance 0)
		)
		(min_thickness 0.25)
		(keepout
			(tracks not_allowed)
			(vias allowed)
			(pads allowed)
			(copperpour not_allowed)
			(footprints allowed)
		)
		(placement
			(enabled no)
			(sheetname "")
		)
		(fill yes
			(thermal_gap 0.5)
			(thermal_bridge_width 0.5)
			(island_removal_mode 0)
		)
		(polygon
			(pts
				(arc
					(start 195.78193 -299.521372)
					(mid 195.796809 -299.557293)
					(end 195.83273 -299.572172)
				)
				(arc
					(start 197.23227 -299.572172)
					(mid 197.268191 -299.557293)
					(end 197.28307 -299.521372)
				)
				(arc
					(start 197.28307 -299.112432)
					(mid 197.268191 -299.076511)
					(end 197.23227 -299.061632)
				)
				(arc
					(start 195.83273 -299.061632)
					(mid 195.796809 -299.076511)
					(end 195.78193 -299.112432)
				)
			)
		)
	)
	(zone
		(layers "In1.Cu" "In2.Cu")
		(hatch none 0.5)
		(connect_pads
			(clearance 0)
		)
		(min_thickness 0.25)
		(keepout
			(tracks not_allowed)
			(vias allowed)
			(pads allowed)
			(copperpour not_allowed)
			(footprints allowed)
		)
		(placement
			(enabled no)
			(sheetname "")
		)
		(fill yes
			(thermal_gap 0.5)
			(thermal_bridge_width 0.5)
			(island_removal_mode 0)
		)
		(polygon
			(pts
				(arc
					(start 421.090598 -262.971534)
					(mid 421.105477 -263.007455)
					(end 421.141398 -263.022334)
				)
				(arc
					(start 422.540938 -263.022334)
					(mid 422.576859 -263.007455)
					(end 422.591738 -262.971534)
				)
				(arc
					(start 422.591738 -262.562594)
					(mid 422.576859 -262.526673)
					(end 422.540938 -262.511794)
				)
				(arc
					(start 421.141398 -262.511794)
					(mid 421.105477 -262.526673)
					(end 421.090598 -262.562594)
				)
			)
		)
	)
	(zone
		(layers "In1.Cu" "In2.Cu")
		(hatch none 0.5)
		(connect_pads
			(clearance 0)
		)
		(min_thickness 0.25)
		(keepout
			(tracks not_allowed)
			(vias allowed)
			(pads allowed)
			(copperpour not_allowed)
			(footprints allowed)
		)
		(placement
			(enabled no)
			(sheetname "")
		)
		(fill yes
			(thermal_gap 0.5)
			(thermal_bridge_width 0.5)
			(island_removal_mode 0)
		)
		(polygon
			(pts
				(arc
					(start 169.706798 -278.271478)
					(mid 169.721677 -278.307399)
					(end 169.757598 -278.322278)
				)
				(arc
					(start 171.157138 -278.322278)
					(mid 171.193059 -278.307399)
					(end 171.207938 -278.271478)
				)
				(arc
					(start 171.207938 -277.862538)
					(mid 171.193059 -277.826617)
					(end 171.157138 -277.811738)
				)
				(arc
					(start 169.757598 -277.811738)
					(mid 169.721677 -277.826617)
					(end 169.706798 -277.862538)
				)
			)
		)
	)
	(zone
		(layers "In1.Cu" "In2.Cu")
		(hatch none 0.5)
		(connect_pads
			(clearance 0)
		)
		(min_thickness 0.25)
		(keepout
			(tracks not_allowed)
			(vias allowed)
			(pads allowed)
			(copperpour not_allowed)
			(footprints allowed)
		)
		(placement
			(enabled no)
			(sheetname "")
		)
		(fill yes
			(thermal_gap 0.5)
			(thermal_bridge_width 0.5)
			(island_removal_mode 0)
		)
		(polygon
			(pts
				(arc
					(start 207.425798 -265.52144)
					(mid 207.440677 -265.557361)
					(end 207.476598 -265.57224)
				)
				(arc
					(start 208.876138 -265.57224)
					(mid 208.912059 -265.557361)
					(end 208.926938 -265.52144)
				)
				(arc
					(start 208.926938 -265.1125)
					(mid 208.912059 -265.076579)
					(end 208.876138 -265.0617)
				)
				(arc
					(start 207.476598 -265.0617)
					(mid 207.440677 -265.076579)
					(end 207.425798 -265.1125)
				)
			)
		)
	)
	(zone
		(layers "In1.Cu" "In2.Cu")
		(hatch none 0.5)
		(connect_pads
			(clearance 0)
		)
		(min_thickness 0.25)
		(keepout
			(tracks not_allowed)
			(vias allowed)
			(pads allowed)
			(copperpour not_allowed)
			(footprints allowed)
		)
		(placement
			(enabled no)
			(sheetname "")
		)
		(fill yes
			(thermal_gap 0.5)
			(thermal_bridge_width 0.5)
			(island_removal_mode 0)
		)
		(polygon
			(pts
				(arc
					(start 462.909666 -203.471526)
					(mid 462.924545 -203.507447)
					(end 462.960466 -203.522326)
				)
				(arc
					(start 464.360006 -203.522326)
					(mid 464.395927 -203.507447)
					(end 464.410806 -203.471526)
				)
				(arc
					(start 464.410806 -203.062586)
					(mid 464.395927 -203.026665)
					(end 464.360006 -203.011786)
				)
				(arc
					(start 462.960466 -203.011786)
					(mid 462.924545 -203.026665)
					(end 462.909666 -203.062586)
				)
			)
		)
	)
	(zone
		(layers "In1.Cu" "In2.Cu")
		(hatch none 0.5)
		(connect_pads
			(clearance 0)
		)
		(min_thickness 0.25)
		(keepout
			(tracks not_allowed)
			(vias allowed)
			(pads allowed)
			(copperpour not_allowed)
			(footprints allowed)
		)
		(placement
			(enabled no)
			(sheetname "")
		)
		(fill yes
			(thermal_gap 0.5)
			(thermal_bridge_width 0.5)
			(island_removal_mode 0)
		)
		(polygon
			(pts
				(arc
					(start 447.822066 -304.621438)
					(mid 447.836945 -304.657359)
					(end 447.872866 -304.672238)
				)
				(arc
					(start 449.272406 -304.672238)
					(mid 449.308327 -304.657359)
					(end 449.323206 -304.621438)
				)
				(arc
					(start 449.323206 -304.212498)
					(mid 449.308327 -304.176577)
					(end 449.272406 -304.161698)
				)
				(arc
					(start 447.872866 -304.161698)
					(mid 447.836945 -304.176577)
					(end 447.822066 -304.212498)
				)
			)
		)
	)
	(zone
		(layers "In1.Cu" "In2.Cu")
		(hatch none 0.5)
		(connect_pads
			(clearance 0)
		)
		(min_thickness 0.25)
		(keepout
			(tracks not_allowed)
			(vias allowed)
			(pads allowed)
			(copperpour not_allowed)
			(footprints allowed)
		)
		(placement
			(enabled no)
			(sheetname "")
		)
		(fill yes
			(thermal_gap 0.5)
			(thermal_bridge_width 0.5)
			(island_removal_mode 0)
		)
		(polygon
			(pts
				(arc
					(start 297.149266 -248.521474)
					(mid 297.164145 -248.557395)
					(end 297.200066 -248.572274)
				)
				(arc
					(start 298.599606 -248.572274)
					(mid 298.635527 -248.557395)
					(end 298.650406 -248.521474)
				)
				(arc
					(start 298.650406 -248.112534)
					(mid 298.635527 -248.076613)
					(end 298.599606 -248.061734)
				)
				(arc
					(start 297.200066 -248.061734)
					(mid 297.164145 -248.076613)
					(end 297.149266 -248.112534)
				)
			)
		)
	)
	(zone
		(layers "In1.Cu" "In2.Cu")
		(hatch none 0.5)
		(connect_pads
			(clearance 0)
		)
		(min_thickness 0.25)
		(keepout
			(tracks not_allowed)
			(vias allowed)
			(pads allowed)
			(copperpour not_allowed)
			(footprints allowed)
		)
		(placement
			(enabled no)
			(sheetname "")
		)
		(fill yes
			(thermal_gap 0.5)
			(thermal_bridge_width 0.5)
			(island_removal_mode 0)
		)
		(polygon
			(pts
				(arc
					(start 421.090598 -297.82135)
					(mid 421.105477 -297.857271)
					(end 421.141398 -297.87215)
				)
				(arc
					(start 422.540938 -297.87215)
					(mid 422.576859 -297.857271)
					(end 422.591738 -297.82135)
				)
				(arc
					(start 422.591738 -297.41241)
					(mid 422.576859 -297.376489)
					(end 422.540938 -297.36161)
				)
				(arc
					(start 421.141398 -297.36161)
					(mid 421.105477 -297.376489)
					(end 421.090598 -297.41241)
				)
			)
		)
	)
	(zone
		(layers "In1.Cu" "In2.Cu")
		(hatch none 0.5)
		(connect_pads
			(clearance 0)
		)
		(min_thickness 0.25)
		(keepout
			(tracks not_allowed)
			(vias allowed)
			(pads allowed)
			(copperpour not_allowed)
			(footprints allowed)
		)
		(placement
			(enabled no)
			(sheetname "")
		)
		(fill yes
			(thermal_gap 0.5)
			(thermal_bridge_width 0.5)
			(island_removal_mode 0)
		)
		(polygon
			(pts
				(arc
					(start 293.049198 -312.27141)
					(mid 293.064077 -312.307331)
					(end 293.099998 -312.32221)
				)
				(arc
					(start 294.499538 -312.32221)
					(mid 294.535459 -312.307331)
					(end 294.550338 -312.27141)
				)
				(arc
					(start 294.550338 -311.86247)
					(mid 294.535459 -311.826549)
					(end 294.499538 -311.81167)
				)
				(arc
					(start 293.099998 -311.81167)
					(mid 293.064077 -311.826549)
					(end 293.049198 -311.86247)
				)
			)
		)
	)
	(zone
		(layers "In1.Cu" "In2.Cu")
		(hatch none 0.5)
		(connect_pads
			(clearance 0)
		)
		(min_thickness 0.25)
		(keepout
			(tracks not_allowed)
			(vias allowed)
			(pads allowed)
			(copperpour not_allowed)
			(footprints allowed)
		)
		(placement
			(enabled no)
			(sheetname "")
		)
		(fill yes
			(thermal_gap 0.5)
			(thermal_bridge_width 0.5)
			(island_removal_mode 0)
		)
		(polygon
			(pts
				(arc
					(start 274.517866 -302.921416)
					(mid 274.532745 -302.957337)
					(end 274.568666 -302.972216)
				)
				(arc
					(start 275.968206 -302.972216)
					(mid 276.004127 -302.957337)
					(end 276.019006 -302.921416)
				)
				(arc
					(start 276.019006 -302.512476)
					(mid 276.004127 -302.476555)
					(end 275.968206 -302.461676)
				)
				(arc
					(start 274.568666 -302.461676)
					(mid 274.532745 -302.476555)
					(end 274.517866 -302.512476)
				)
			)
		)
	)
	(zone
		(layers "In1.Cu" "In2.Cu")
		(hatch none 0.5)
		(connect_pads
			(clearance 0)
		)
		(min_thickness 0.25)
		(keepout
			(tracks not_allowed)
			(vias allowed)
			(pads allowed)
			(copperpour not_allowed)
			(footprints allowed)
		)
		(placement
			(enabled no)
			(sheetname "")
		)
		(fill yes
			(thermal_gap 0.5)
			(thermal_bridge_width 0.5)
			(island_removal_mode 0)
		)
		(polygon
			(pts
				(arc
					(start 173.15053 -293.571422)
					(mid 173.165409 -293.607343)
					(end 173.20133 -293.622222)
				)
				(arc
					(start 174.60087 -293.622222)
					(mid 174.636791 -293.607343)
					(end 174.65167 -293.571422)
				)
				(arc
					(start 174.65167 -293.162482)
					(mid 174.636791 -293.126561)
					(end 174.60087 -293.111682)
				)
				(arc
					(start 173.20133 -293.111682)
					(mid 173.165409 -293.126561)
					(end 173.15053 -293.162482)
				)
			)
		)
	)
	(zone
		(layers "In1.Cu" "In2.Cu")
		(hatch none 0.5)
		(connect_pads
			(clearance 0)
		)
		(min_thickness 0.25)
		(keepout
			(tracks not_allowed)
			(vias allowed)
			(pads allowed)
			(copperpour not_allowed)
			(footprints allowed)
		)
		(placement
			(enabled no)
			(sheetname "")
		)
		(fill yes
			(thermal_gap 0.5)
			(thermal_bridge_width 0.5)
			(island_removal_mode 0)
		)
		(polygon
			(pts
				(arc
					(start 41.665398 -311.421526)
					(mid 41.680277 -311.457447)
					(end 41.716198 -311.472326)
				)
				(arc
					(start 43.115738 -311.472326)
					(mid 43.151659 -311.457447)
					(end 43.166538 -311.421526)
				)
				(arc
					(start 43.166538 -311.012586)
					(mid 43.151659 -310.976665)
					(end 43.115738 -310.961786)
				)
				(arc
					(start 41.716198 -310.961786)
					(mid 41.680277 -310.976665)
					(end 41.665398 -311.012586)
				)
			)
		)
	)
	(zone
		(layers "In1.Cu" "In2.Cu")
		(hatch none 0.5)
		(connect_pads
			(clearance 0)
		)
		(min_thickness 0.25)
		(keepout
			(tracks not_allowed)
			(vias allowed)
			(pads allowed)
			(copperpour not_allowed)
			(footprints allowed)
		)
		(placement
			(enabled no)
			(sheetname "")
		)
		(fill yes
			(thermal_gap 0.5)
			(thermal_bridge_width 0.5)
			(island_removal_mode 0)
		)
		(polygon
			(pts
				(arc
					(start 458.809598 -207.721454)
					(mid 458.824477 -207.757375)
					(end 458.860398 -207.772254)
				)
				(arc
					(start 460.259938 -207.772254)
					(mid 460.295859 -207.757375)
					(end 460.310738 -207.721454)
				)
				(arc
					(start 460.310738 -207.312514)
					(mid 460.295859 -207.276593)
					(end 460.259938 -207.261714)
				)
				(arc
					(start 458.860398 -207.261714)
					(mid 458.824477 -207.276593)
					(end 458.809598 -207.312514)
				)
			)
		)
	)
	(zone
		(layers "In1.Cu" "In2.Cu")
		(hatch none 0.5)
		(connect_pads
			(clearance 0)
		)
		(min_thickness 0.25)
		(keepout
			(tracks not_allowed)
			(vias allowed)
			(pads allowed)
			(copperpour not_allowed)
			(footprints allowed)
		)
		(placement
			(enabled no)
			(sheetname "")
		)
		(fill yes
			(thermal_gap 0.5)
			(thermal_bridge_width 0.5)
			(island_removal_mode 0)
		)
		(polygon
			(pts
				(arc
					(start 300.592998 -269.771368)
					(mid 300.607877 -269.807289)
					(end 300.643798 -269.822168)
				)
				(arc
					(start 302.043338 -269.822168)
					(mid 302.079259 -269.807289)
					(end 302.094138 -269.771368)
				)
				(arc
					(start 302.094138 -269.362428)
					(mid 302.079259 -269.326507)
					(end 302.043338 -269.311628)
				)
				(arc
					(start 300.643798 -269.311628)
					(mid 300.607877 -269.326507)
					(end 300.592998 -269.362428)
				)
			)
		)
	)
	(zone
		(layers "In1.Cu" "In2.Cu")
		(hatch none 0.5)
		(connect_pads
			(clearance 0)
		)
		(min_thickness 0.25)
		(keepout
			(tracks not_allowed)
			(vias allowed)
			(pads allowed)
			(copperpour not_allowed)
			(footprints allowed)
		)
		(placement
			(enabled no)
			(sheetname "")
		)
		(fill yes
			(thermal_gap 0.5)
			(thermal_bridge_width 0.5)
			(island_removal_mode 0)
		)
		(polygon
			(pts
				(arc
					(start 158.06293 -280.821384)
					(mid 158.077809 -280.857305)
					(end 158.11373 -280.872184)
				)
				(arc
					(start 159.51327 -280.872184)
					(mid 159.549191 -280.857305)
					(end 159.56407 -280.821384)
				)
				(arc
					(start 159.56407 -280.412444)
					(mid 159.549191 -280.376523)
					(end 159.51327 -280.361644)
				)
				(arc
					(start 158.11373 -280.361644)
					(mid 158.077809 -280.376523)
					(end 158.06293 -280.412444)
				)
			)
		)
	)
	(zone
		(layers "In1.Cu" "In2.Cu")
		(hatch none 0.5)
		(connect_pads
			(clearance 0)
		)
		(min_thickness 0.25)
		(keepout
			(tracks not_allowed)
			(vias allowed)
			(pads allowed)
			(copperpour not_allowed)
			(footprints allowed)
		)
		(placement
			(enabled no)
			(sheetname "")
		)
		(fill yes
			(thermal_gap 0.5)
			(thermal_bridge_width 0.5)
			(island_removal_mode 0)
		)
		(polygon
			(pts
				(arc
					(start 297.149266 -234.921298)
					(mid 297.164145 -234.957219)
					(end 297.200066 -234.972098)
				)
				(arc
					(start 298.599606 -234.972098)
					(mid 298.635527 -234.957219)
					(end 298.650406 -234.921298)
				)
				(arc
					(start 298.650406 -234.512358)
					(mid 298.635527 -234.476437)
					(end 298.599606 -234.461558)
				)
				(arc
					(start 297.200066 -234.461558)
					(mid 297.164145 -234.476437)
					(end 297.149266 -234.512358)
				)
			)
		)
	)
	(zone
		(layers "In1.Cu" "In2.Cu")
		(hatch none 0.5)
		(connect_pads
			(clearance 0)
		)
		(min_thickness 0.25)
		(keepout
			(tracks not_allowed)
			(vias allowed)
			(pads allowed)
			(copperpour not_allowed)
			(footprints allowed)
		)
		(placement
			(enabled no)
			(sheetname "")
		)
		(fill yes
			(thermal_gap 0.5)
			(thermal_bridge_width 0.5)
			(island_removal_mode 0)
		)
		(polygon
			(pts
				(arc
					(start 308.136798 -285.071312)
					(mid 308.151677 -285.107233)
					(end 308.187598 -285.122112)
				)
				(arc
					(start 309.587138 -285.122112)
					(mid 309.623059 -285.107233)
					(end 309.637938 -285.071312)
				)
				(arc
					(start 309.637938 -284.662372)
					(mid 309.623059 -284.626451)
					(end 309.587138 -284.611572)
				)
				(arc
					(start 308.187598 -284.611572)
					(mid 308.151677 -284.626451)
					(end 308.136798 -284.662372)
				)
			)
		)
	)
	(zone
		(layers "In1.Cu" "In2.Cu")
		(hatch none 0.5)
		(connect_pads
			(clearance 0)
		)
		(min_thickness 0.25)
		(keepout
			(tracks not_allowed)
			(vias allowed)
			(pads allowed)
			(copperpour not_allowed)
			(footprints allowed)
		)
		(placement
			(enabled no)
			(sheetname "")
		)
		(fill yes
			(thermal_gap 0.5)
			(thermal_bridge_width 0.5)
			(island_removal_mode 0)
		)
		(polygon
			(pts
				(arc
					(start 169.706798 -306.32146)
					(mid 169.721677 -306.357381)
					(end 169.757598 -306.37226)
				)
				(arc
					(start 171.157138 -306.37226)
					(mid 171.193059 -306.357381)
					(end 171.207938 -306.32146)
				)
				(arc
					(start 171.207938 -305.91252)
					(mid 171.193059 -305.876599)
					(end 171.157138 -305.86172)
				)
				(arc
					(start 169.757598 -305.86172)
					(mid 169.721677 -305.876599)
					(end 169.706798 -305.91252)
				)
			)
		)
	)
	(zone
		(layers "In1.Cu" "In2.Cu")
		(hatch none 0.5)
		(connect_pads
			(clearance 0)
		)
		(min_thickness 0.25)
		(keepout
			(tracks not_allowed)
			(vias allowed)
			(pads allowed)
			(copperpour not_allowed)
			(footprints allowed)
		)
		(placement
			(enabled no)
			(sheetname "")
		)
		(fill yes
			(thermal_gap 0.5)
			(thermal_bridge_width 0.5)
			(island_removal_mode 0)
		)
		(polygon
			(pts
				(arc
					(start 451.265798 -238.321342)
					(mid 451.280677 -238.357263)
					(end 451.316598 -238.372142)
				)
				(arc
					(start 452.716138 -238.372142)
					(mid 452.752059 -238.357263)
					(end 452.766938 -238.321342)
				)
				(arc
					(start 452.766938 -237.912402)
					(mid 452.752059 -237.876481)
					(end 452.716138 -237.861602)
				)
				(arc
					(start 451.316598 -237.861602)
					(mid 451.280677 -237.876481)
					(end 451.265798 -237.912402)
				)
			)
		)
	)
	(zone
		(layers "In1.Cu" "In2.Cu")
		(hatch none 0.5)
		(connect_pads
			(clearance 0)
		)
		(min_thickness 0.25)
		(keepout
			(tracks not_allowed)
			(vias allowed)
			(pads allowed)
			(copperpour not_allowed)
			(footprints allowed)
		)
		(placement
			(enabled no)
			(sheetname "")
		)
		(fill yes
			(thermal_gap 0.5)
			(thermal_bridge_width 0.5)
			(island_removal_mode 0)
		)
		(polygon
			(pts
				(arc
					(start 199.881998 -195.821554)
					(mid 199.896877 -195.857475)
					(end 199.932798 -195.872354)
				)
				(arc
					(start 201.332338 -195.872354)
					(mid 201.368259 -195.857475)
					(end 201.383138 -195.821554)
				)
				(arc
					(start 201.383138 -195.412614)
					(mid 201.368259 -195.376693)
					(end 201.332338 -195.361814)
				)
				(arc
					(start 199.932798 -195.361814)
					(mid 199.896877 -195.376693)
					(end 199.881998 -195.412614)
				)
			)
		)
	)
	(zone
		(layers "In1.Cu" "In2.Cu")
		(hatch none 0.5)
		(connect_pads
			(clearance 0)
		)
		(min_thickness 0.25)
		(keepout
			(tracks not_allowed)
			(vias allowed)
			(pads allowed)
			(copperpour not_allowed)
			(footprints allowed)
		)
		(placement
			(enabled no)
			(sheetname "")
		)
		(fill yes
			(thermal_gap 0.5)
			(thermal_bridge_width 0.5)
			(island_removal_mode 0)
		)
		(polygon
			(pts
				(arc
					(start 195.78193 -285.071312)
					(mid 195.796809 -285.107233)
					(end 195.83273 -285.122112)
				)
				(arc
					(start 197.23227 -285.122112)
					(mid 197.268191 -285.107233)
					(end 197.28307 -285.071312)
				)
				(arc
					(start 197.28307 -284.662372)
					(mid 197.268191 -284.626451)
					(end 197.23227 -284.611572)
				)
				(arc
					(start 195.83273 -284.611572)
					(mid 195.796809 -284.626451)
					(end 195.78193 -284.662372)
				)
			)
		)
	)
	(zone
		(layers "In1.Cu" "In2.Cu")
		(hatch none 0.5)
		(connect_pads
			(clearance 0)
		)
		(min_thickness 0.25)
		(keepout
			(tracks not_allowed)
			(vias allowed)
			(pads allowed)
			(copperpour not_allowed)
			(footprints allowed)
		)
		(placement
			(enabled no)
			(sheetname "")
		)
		(fill yes
			(thermal_gap 0.5)
			(thermal_bridge_width 0.5)
			(island_removal_mode 0)
		)
		(polygon
			(pts
				(arc
					(start 64.296798 -304.621438)
					(mid 64.311677 -304.657359)
					(end 64.347598 -304.672238)
				)
				(arc
					(start 65.747138 -304.672238)
					(mid 65.783059 -304.657359)
					(end 65.797938 -304.621438)
				)
				(arc
					(start 65.797938 -304.212498)
					(mid 65.783059 -304.176577)
					(end 65.747138 -304.161698)
				)
				(arc
					(start 64.347598 -304.161698)
					(mid 64.311677 -304.176577)
					(end 64.296798 -304.212498)
				)
			)
		)
	)
	(zone
		(layers "In1.Cu" "In2.Cu")
		(hatch none 0.5)
		(connect_pads
			(clearance 0)
		)
		(min_thickness 0.25)
		(keepout
			(tracks not_allowed)
			(vias allowed)
			(pads allowed)
			(copperpour not_allowed)
			(footprints allowed)
		)
		(placement
			(enabled no)
			(sheetname "")
		)
		(fill yes
			(thermal_gap 0.5)
			(thermal_bridge_width 0.5)
			(island_removal_mode 0)
		)
		(polygon
			(pts
				(arc
					(start 60.19673 -301.221394)
					(mid 60.211609 -301.257315)
					(end 60.24753 -301.272194)
				)
				(arc
					(start 61.64707 -301.272194)
					(mid 61.682991 -301.257315)
					(end 61.69787 -301.221394)
				)
				(arc
					(start 61.69787 -300.812454)
					(mid 61.682991 -300.776533)
					(end 61.64707 -300.761654)
				)
				(arc
					(start 60.24753 -300.761654)
					(mid 60.211609 -300.776533)
					(end 60.19673 -300.812454)
				)
			)
		)
	)
	(zone
		(layers "In1.Cu" "In2.Cu")
		(hatch none 0.5)
		(connect_pads
			(clearance 0)
		)
		(min_thickness 0.25)
		(keepout
			(tracks not_allowed)
			(vias allowed)
			(pads allowed)
			(copperpour not_allowed)
			(footprints allowed)
		)
		(placement
			(enabled no)
			(sheetname "")
		)
		(fill yes
			(thermal_gap 0.5)
			(thermal_bridge_width 0.5)
			(island_removal_mode 0)
		)
		(polygon
			(pts
				(arc
					(start 162.162998 -298.671488)
					(mid 162.177877 -298.707409)
					(end 162.213798 -298.722288)
				)
				(arc
					(start 163.613338 -298.722288)
					(mid 163.649259 -298.707409)
					(end 163.664138 -298.671488)
				)
				(arc
					(start 163.664138 -298.262548)
					(mid 163.649259 -298.226627)
					(end 163.613338 -298.211748)
				)
				(arc
					(start 162.213798 -298.211748)
					(mid 162.177877 -298.226627)
					(end 162.162998 -298.262548)
				)
			)
		)
	)
	(zone
		(layers "In1.Cu" "In2.Cu")
		(hatch none 0.5)
		(connect_pads
			(clearance 0)
		)
		(min_thickness 0.25)
		(keepout
			(tracks not_allowed)
			(vias allowed)
			(pads allowed)
			(copperpour not_allowed)
			(footprints allowed)
		)
		(placement
			(enabled no)
			(sheetname "")
		)
		(fill yes
			(thermal_gap 0.5)
			(thermal_bridge_width 0.5)
			(island_removal_mode 0)
		)
		(polygon
			(pts
				(arc
					(start 447.822066 -239.17148)
					(mid 447.836945 -239.207401)
					(end 447.872866 -239.22228)
				)
				(arc
					(start 449.272406 -239.22228)
					(mid 449.308327 -239.207401)
					(end 449.323206 -239.17148)
				)
				(arc
					(start 449.323206 -238.76254)
					(mid 449.308327 -238.726619)
					(end 449.272406 -238.71174)
				)
				(arc
					(start 447.872866 -238.71174)
					(mid 447.836945 -238.726619)
					(end 447.822066 -238.76254)
				)
			)
		)
	)
	(zone
		(layers "In1.Cu" "In2.Cu")
		(hatch none 0.5)
		(connect_pads
			(clearance 0)
		)
		(min_thickness 0.25)
		(keepout
			(tracks not_allowed)
			(vias allowed)
			(pads allowed)
			(copperpour not_allowed)
			(footprints allowed)
		)
		(placement
			(enabled no)
			(sheetname "")
		)
		(fill yes
			(thermal_gap 0.5)
			(thermal_bridge_width 0.5)
			(island_removal_mode 0)
		)
		(polygon
			(pts
				(arc
					(start 266.974066 -291.021516)
					(mid 266.988945 -291.057437)
					(end 267.024866 -291.072316)
				)
				(arc
					(start 268.424406 -291.072316)
					(mid 268.460327 -291.057437)
					(end 268.475206 -291.021516)
				)
				(arc
					(start 268.475206 -290.612576)
					(mid 268.460327 -290.576655)
					(end 268.424406 -290.561776)
				)
				(arc
					(start 267.024866 -290.561776)
					(mid 266.988945 -290.576655)
					(end 266.974066 -290.612576)
				)
			)
		)
	)
	(zone
		(layers "In1.Cu" "In2.Cu")
		(hatch none 0.5)
		(connect_pads
			(clearance 0)
		)
		(min_thickness 0.25)
		(keepout
			(tracks not_allowed)
			(vias allowed)
			(pads allowed)
			(copperpour not_allowed)
			(footprints allowed)
		)
		(placement
			(enabled no)
			(sheetname "")
		)
		(fill yes
			(thermal_gap 0.5)
			(thermal_bridge_width 0.5)
			(island_removal_mode 0)
		)
		(polygon
			(pts
				(arc
					(start 274.517866 -211.121498)
					(mid 274.532745 -211.157419)
					(end 274.568666 -211.172298)
				)
				(arc
					(start 275.968206 -211.172298)
					(mid 276.004127 -211.157419)
					(end 276.019006 -211.121498)
				)
				(arc
					(start 276.019006 -210.712558)
					(mid 276.004127 -210.676637)
					(end 275.968206 -210.661758)
				)
				(arc
					(start 274.568666 -210.661758)
					(mid 274.532745 -210.676637)
					(end 274.517866 -210.712558)
				)
			)
		)
	)
	(zone
		(layers "In1.Cu" "In2.Cu")
		(hatch none 0.5)
		(connect_pads
			(clearance 0)
		)
		(min_thickness 0.25)
		(keepout
			(tracks not_allowed)
			(vias allowed)
			(pads allowed)
			(copperpour not_allowed)
			(footprints allowed)
		)
		(placement
			(enabled no)
			(sheetname "")
		)
		(fill yes
			(thermal_gap 0.5)
			(thermal_bridge_width 0.5)
			(island_removal_mode 0)
		)
		(polygon
			(pts
				(arc
					(start 173.15053 -226.421442)
					(mid 173.165409 -226.457363)
					(end 173.20133 -226.472242)
				)
				(arc
					(start 174.60087 -226.472242)
					(mid 174.636791 -226.457363)
					(end 174.65167 -226.421442)
				)
				(arc
					(start 174.65167 -226.012502)
					(mid 174.636791 -225.976581)
					(end 174.60087 -225.961702)
				)
				(arc
					(start 173.20133 -225.961702)
					(mid 173.165409 -225.976581)
					(end 173.15053 -226.012502)
				)
			)
		)
	)
	(zone
		(layers "In1.Cu" "In2.Cu")
		(hatch none 0.5)
		(connect_pads
			(clearance 0)
		)
		(min_thickness 0.25)
		(keepout
			(tracks not_allowed)
			(vias allowed)
			(pads allowed)
			(copperpour not_allowed)
			(footprints allowed)
		)
		(placement
			(enabled no)
			(sheetname "")
		)
		(fill yes
			(thermal_gap 0.5)
			(thermal_bridge_width 0.5)
			(island_removal_mode 0)
		)
		(polygon
			(pts
				(arc
					(start 192.338198 -283.371544)
					(mid 192.353077 -283.407465)
					(end 192.388998 -283.422344)
				)
				(arc
					(start 193.788538 -283.422344)
					(mid 193.824459 -283.407465)
					(end 193.839338 -283.371544)
				)
				(arc
					(start 193.839338 -282.962604)
					(mid 193.824459 -282.926683)
					(end 193.788538 -282.911804)
				)
				(arc
					(start 192.388998 -282.911804)
					(mid 192.353077 -282.926683)
					(end 192.338198 -282.962604)
				)
			)
		)
	)
	(zone
		(layers "In1.Cu" "In2.Cu")
		(hatch none 0.5)
		(connect_pads
			(clearance 0)
		)
		(min_thickness 0.25)
		(keepout
			(tracks not_allowed)
			(vias allowed)
			(pads allowed)
			(copperpour not_allowed)
			(footprints allowed)
		)
		(placement
			(enabled no)
			(sheetname "")
		)
		(fill yes
			(thermal_gap 0.5)
			(thermal_bridge_width 0.5)
			(island_removal_mode 0)
		)
		(polygon
			(pts
				(arc
					(start 180.69433 -305.471322)
					(mid 180.709209 -305.507243)
					(end 180.74513 -305.522122)
				)
				(arc
					(start 182.14467 -305.522122)
					(mid 182.180591 -305.507243)
					(end 182.19547 -305.471322)
				)
				(arc
					(start 182.19547 -305.062382)
					(mid 182.180591 -305.026461)
					(end 182.14467 -305.011582)
				)
				(arc
					(start 180.74513 -305.011582)
					(mid 180.709209 -305.026461)
					(end 180.69433 -305.062382)
				)
			)
		)
	)
	(zone
		(layers "In1.Cu" "In2.Cu")
		(hatch none 0.5)
		(connect_pads
			(clearance 0)
		)
		(min_thickness 0.25)
		(keepout
			(tracks not_allowed)
			(vias allowed)
			(pads allowed)
			(copperpour not_allowed)
			(footprints allowed)
		)
		(placement
			(enabled no)
			(sheetname "")
		)
		(fill yes
			(thermal_gap 0.5)
			(thermal_bridge_width 0.5)
			(island_removal_mode 0)
		)
		(polygon
			(pts
				(arc
					(start 19.033998 -199.221344)
					(mid 19.048877 -199.257265)
					(end 19.084798 -199.272144)
				)
				(arc
					(start 20.484338 -199.272144)
					(mid 20.520259 -199.257265)
					(end 20.535138 -199.221344)
				)
				(arc
					(start 20.535138 -198.812404)
					(mid 20.520259 -198.776483)
					(end 20.484338 -198.761604)
				)
				(arc
					(start 19.084798 -198.761604)
					(mid 19.048877 -198.776483)
					(end 19.033998 -198.812404)
				)
			)
		)
	)
	(zone
		(layers "In1.Cu" "In2.Cu")
		(hatch none 0.5)
		(connect_pads
			(clearance 0)
		)
		(min_thickness 0.25)
		(keepout
			(tracks not_allowed)
			(vias allowed)
			(pads allowed)
			(copperpour not_allowed)
			(footprints allowed)
		)
		(placement
			(enabled no)
			(sheetname "")
		)
		(fill yes
			(thermal_gap 0.5)
			(thermal_bridge_width 0.5)
			(island_removal_mode 0)
		)
		(polygon
			(pts
				(arc
					(start 52.65293 -219.621354)
					(mid 52.667809 -219.657275)
					(end 52.70373 -219.672154)
				)
				(arc
					(start 54.10327 -219.672154)
					(mid 54.139191 -219.657275)
					(end 54.15407 -219.621354)
				)
				(arc
					(start 54.15407 -219.212414)
					(mid 54.139191 -219.176493)
					(end 54.10327 -219.161614)
				)
				(arc
					(start 52.70373 -219.161614)
					(mid 52.667809 -219.176493)
					(end 52.65293 -219.212414)
				)
			)
		)
	)
	(zone
		(layers "In1.Cu" "In2.Cu")
		(hatch none 0.5)
		(connect_pads
			(clearance 0)
		)
		(min_thickness 0.25)
		(keepout
			(tracks not_allowed)
			(vias allowed)
			(pads allowed)
			(copperpour not_allowed)
			(footprints allowed)
		)
		(placement
			(enabled no)
			(sheetname "")
		)
		(fill yes
			(thermal_gap 0.5)
			(thermal_bridge_width 0.5)
			(island_removal_mode 0)
		)
		(polygon
			(pts
				(arc
					(start 425.190666 -227.271326)
					(mid 425.205545 -227.307247)
					(end 425.241466 -227.322126)
				)
				(arc
					(start 426.641006 -227.322126)
					(mid 426.676927 -227.307247)
					(end 426.691806 -227.271326)
				)
				(arc
					(start 426.691806 -226.862386)
					(mid 426.676927 -226.826465)
					(end 426.641006 -226.811586)
				)
				(arc
					(start 425.241466 -226.811586)
					(mid 425.205545 -226.826465)
					(end 425.190666 -226.862386)
				)
			)
		)
	)
	(zone
		(layers "In1.Cu" "In2.Cu")
		(hatch none 0.5)
		(connect_pads
			(clearance 0)
		)
		(min_thickness 0.25)
		(keepout
			(tracks not_allowed)
			(vias allowed)
			(pads allowed)
			(copperpour not_allowed)
			(footprints allowed)
		)
		(placement
			(enabled no)
			(sheetname "")
		)
		(fill yes
			(thermal_gap 0.5)
			(thermal_bridge_width 0.5)
			(island_removal_mode 0)
		)
		(polygon
			(pts
				(arc
					(start 447.822066 -237.471458)
					(mid 447.836945 -237.507379)
					(end 447.872866 -237.522258)
				)
				(arc
					(start 449.272406 -237.522258)
					(mid 449.308327 -237.507379)
					(end 449.323206 -237.471458)
				)
				(arc
					(start 449.323206 -237.062518)
					(mid 449.308327 -237.026597)
					(end 449.272406 -237.011718)
				)
				(arc
					(start 447.872866 -237.011718)
					(mid 447.836945 -237.026597)
					(end 447.822066 -237.062518)
				)
			)
		)
	)
	(zone
		(layers "In1.Cu" "In2.Cu")
		(hatch none 0.5)
		(connect_pads
			(clearance 0)
		)
		(min_thickness 0.25)
		(keepout
			(tracks not_allowed)
			(vias allowed)
			(pads allowed)
			(copperpour not_allowed)
			(footprints allowed)
		)
		(placement
			(enabled no)
			(sheetname "")
		)
		(fill yes
			(thermal_gap 0.5)
			(thermal_bridge_width 0.5)
			(island_removal_mode 0)
		)
		(polygon
			(pts
				(arc
					(start 210.86953 -308.871366)
					(mid 210.884409 -308.907287)
					(end 210.92033 -308.922166)
				)
				(arc
					(start 212.31987 -308.922166)
					(mid 212.355791 -308.907287)
					(end 212.37067 -308.871366)
				)
				(arc
					(start 212.37067 -308.462426)
					(mid 212.355791 -308.426505)
					(end 212.31987 -308.411626)
				)
				(arc
					(start 210.92033 -308.411626)
					(mid 210.884409 -308.426505)
					(end 210.86953 -308.462426)
				)
			)
		)
	)
	(zone
		(layers "In1.Cu" "In2.Cu")
		(hatch none 0.5)
		(connect_pads
			(clearance 0)
		)
		(min_thickness 0.25)
		(keepout
			(tracks not_allowed)
			(vias allowed)
			(pads allowed)
			(copperpour not_allowed)
			(footprints allowed)
		)
		(placement
			(enabled no)
			(sheetname "")
		)
		(fill yes
			(thermal_gap 0.5)
			(thermal_bridge_width 0.5)
			(island_removal_mode 0)
		)
		(polygon
			(pts
				(arc
					(start 432.734466 -231.521508)
					(mid 432.749345 -231.557429)
					(end 432.785266 -231.572308)
				)
				(arc
					(start 434.184806 -231.572308)
					(mid 434.220727 -231.557429)
					(end 434.235606 -231.521508)
				)
				(arc
					(start 434.235606 -231.112568)
					(mid 434.220727 -231.076647)
					(end 434.184806 -231.061768)
				)
				(arc
					(start 432.785266 -231.061768)
					(mid 432.749345 -231.076647)
					(end 432.734466 -231.112568)
				)
			)
		)
	)
	(zone
		(layers "In1.Cu" "In2.Cu")
		(hatch none 0.5)
		(connect_pads
			(clearance 0)
		)
		(min_thickness 0.25)
		(keepout
			(tracks not_allowed)
			(vias allowed)
			(pads allowed)
			(copperpour not_allowed)
			(footprints allowed)
		)
		(placement
			(enabled no)
			(sheetname "")
		)
		(fill yes
			(thermal_gap 0.5)
			(thermal_bridge_width 0.5)
			(island_removal_mode 0)
		)
		(polygon
			(pts
				(arc
					(start 188.23813 -241.721386)
					(mid 188.253009 -241.757307)
					(end 188.28893 -241.772186)
				)
				(arc
					(start 189.68847 -241.772186)
					(mid 189.724391 -241.757307)
					(end 189.73927 -241.721386)
				)
				(arc
					(start 189.73927 -241.312446)
					(mid 189.724391 -241.276525)
					(end 189.68847 -241.261646)
				)
				(arc
					(start 188.28893 -241.261646)
					(mid 188.253009 -241.276525)
					(end 188.23813 -241.312446)
				)
			)
		)
	)
	(zone
		(layers "In1.Cu" "In2.Cu")
		(hatch none 0.5)
		(connect_pads
			(clearance 0)
		)
		(min_thickness 0.25)
		(keepout
			(tracks not_allowed)
			(vias allowed)
			(pads allowed)
			(copperpour not_allowed)
			(footprints allowed)
		)
		(placement
			(enabled no)
			(sheetname "")
		)
		(fill yes
			(thermal_gap 0.5)
			(thermal_bridge_width 0.5)
			(island_removal_mode 0)
		)
		(polygon
			(pts
				(arc
					(start 266.974066 -236.62132)
					(mid 266.988945 -236.657241)
					(end 267.024866 -236.67212)
				)
				(arc
					(start 268.424406 -236.67212)
					(mid 268.460327 -236.657241)
					(end 268.475206 -236.62132)
				)
				(arc
					(start 268.475206 -236.21238)
					(mid 268.460327 -236.176459)
					(end 268.424406 -236.16158)
				)
				(arc
					(start 267.024866 -236.16158)
					(mid 266.988945 -236.176459)
					(end 266.974066 -236.21238)
				)
			)
		)
	)
	(zone
		(layers "In1.Cu" "In2.Cu")
		(hatch none 0.5)
		(connect_pads
			(clearance 0)
		)
		(min_thickness 0.25)
		(keepout
			(tracks not_allowed)
			(vias allowed)
			(pads allowed)
			(copperpour not_allowed)
			(footprints allowed)
		)
		(placement
			(enabled no)
			(sheetname "")
		)
		(fill yes
			(thermal_gap 0.5)
			(thermal_bridge_width 0.5)
			(island_removal_mode 0)
		)
		(polygon
			(pts
				(arc
					(start 262.873998 -240.021364)
					(mid 262.888877 -240.057285)
					(end 262.924798 -240.072164)
				)
				(arc
					(start 264.324338 -240.072164)
					(mid 264.360259 -240.057285)
					(end 264.375138 -240.021364)
				)
				(arc
					(start 264.375138 -239.612424)
					(mid 264.360259 -239.576503)
					(end 264.324338 -239.561624)
				)
				(arc
					(start 262.924798 -239.561624)
					(mid 262.888877 -239.576503)
					(end 262.873998 -239.612424)
				)
			)
		)
	)
	(zone
		(layers "In1.Cu" "In2.Cu")
		(hatch none 0.5)
		(connect_pads
			(clearance 0)
		)
		(min_thickness 0.25)
		(keepout
			(tracks not_allowed)
			(vias allowed)
			(pads allowed)
			(copperpour not_allowed)
			(footprints allowed)
		)
		(placement
			(enabled no)
			(sheetname "")
		)
		(fill yes
			(thermal_gap 0.5)
			(thermal_bridge_width 0.5)
			(island_removal_mode 0)
		)
		(polygon
			(pts
				(arc
					(start 184.794398 -262.121396)
					(mid 184.809277 -262.157317)
					(end 184.845198 -262.172196)
				)
				(arc
					(start 186.244738 -262.172196)
					(mid 186.280659 -262.157317)
					(end 186.295538 -262.121396)
				)
				(arc
					(start 186.295538 -261.712456)
					(mid 186.280659 -261.676535)
					(end 186.244738 -261.661656)
				)
				(arc
					(start 184.845198 -261.661656)
					(mid 184.809277 -261.676535)
					(end 184.794398 -261.712456)
				)
			)
		)
	)
	(zone
		(layers "In1.Cu" "In2.Cu")
		(hatch none 0.5)
		(connect_pads
			(clearance 0)
		)
		(min_thickness 0.25)
		(keepout
			(tracks not_allowed)
			(vias allowed)
			(pads allowed)
			(copperpour not_allowed)
			(footprints allowed)
		)
		(placement
			(enabled no)
			(sheetname "")
		)
		(fill yes
			(thermal_gap 0.5)
			(thermal_bridge_width 0.5)
			(island_removal_mode 0)
		)
		(polygon
			(pts
				(arc
					(start 277.961598 -305.471322)
					(mid 277.976477 -305.507243)
					(end 278.012398 -305.522122)
				)
				(arc
					(start 279.411938 -305.522122)
					(mid 279.447859 -305.507243)
					(end 279.462738 -305.471322)
				)
				(arc
					(start 279.462738 -305.062382)
					(mid 279.447859 -305.026461)
					(end 279.411938 -305.011582)
				)
				(arc
					(start 278.012398 -305.011582)
					(mid 277.976477 -305.026461)
					(end 277.961598 -305.062382)
				)
			)
		)
	)
	(zone
		(layers "In1.Cu" "In2.Cu")
		(hatch none 0.5)
		(connect_pads
			(clearance 0)
		)
		(min_thickness 0.25)
		(keepout
			(tracks not_allowed)
			(vias allowed)
			(pads allowed)
			(copperpour not_allowed)
			(footprints allowed)
		)
		(placement
			(enabled no)
			(sheetname "")
		)
		(fill yes
			(thermal_gap 0.5)
			(thermal_bridge_width 0.5)
			(island_removal_mode 0)
		)
		(polygon
			(pts
				(arc
					(start 56.752998 -295.271444)
					(mid 56.767877 -295.307365)
					(end 56.803798 -295.322244)
				)
				(arc
					(start 58.203338 -295.322244)
					(mid 58.239259 -295.307365)
					(end 58.254138 -295.271444)
				)
				(arc
					(start 58.254138 -294.862504)
					(mid 58.239259 -294.826583)
					(end 58.203338 -294.811704)
				)
				(arc
					(start 56.803798 -294.811704)
					(mid 56.767877 -294.826583)
					(end 56.752998 -294.862504)
				)
			)
		)
	)
	(zone
		(layers "In1.Cu" "In2.Cu")
		(hatch none 0.5)
		(connect_pads
			(clearance 0)
		)
		(min_thickness 0.25)
		(keepout
			(tracks not_allowed)
			(vias allowed)
			(pads allowed)
			(copperpour not_allowed)
			(footprints allowed)
		)
		(placement
			(enabled no)
			(sheetname "")
		)
		(fill yes
			(thermal_gap 0.5)
			(thermal_bridge_width 0.5)
			(island_removal_mode 0)
		)
		(polygon
			(pts
				(arc
					(start 64.296798 -201.771504)
					(mid 64.311677 -201.807425)
					(end 64.347598 -201.822304)
				)
				(arc
					(start 65.747138 -201.822304)
					(mid 65.783059 -201.807425)
					(end 65.797938 -201.771504)
				)
				(arc
					(start 65.797938 -201.362564)
					(mid 65.783059 -201.326643)
					(end 65.747138 -201.311764)
				)
				(arc
					(start 64.347598 -201.311764)
					(mid 64.311677 -201.326643)
					(end 64.296798 -201.362564)
				)
			)
		)
	)
	(zone
		(layers "In1.Cu" "In2.Cu")
		(hatch none 0.5)
		(connect_pads
			(clearance 0)
		)
		(min_thickness 0.25)
		(keepout
			(tracks not_allowed)
			(vias allowed)
			(pads allowed)
			(copperpour not_allowed)
			(footprints allowed)
		)
		(placement
			(enabled no)
			(sheetname "")
		)
		(fill yes
			(thermal_gap 0.5)
			(thermal_bridge_width 0.5)
			(island_removal_mode 0)
		)
		(polygon
			(pts
				(arc
					(start 210.86953 -228.121464)
					(mid 210.884409 -228.157385)
					(end 210.92033 -228.172264)
				)
				(arc
					(start 212.31987 -228.172264)
					(mid 212.355791 -228.157385)
					(end 212.37067 -228.121464)
				)
				(arc
					(start 212.37067 -227.712524)
					(mid 212.355791 -227.676603)
					(end 212.31987 -227.661724)
				)
				(arc
					(start 210.92033 -227.661724)
					(mid 210.884409 -227.676603)
					(end 210.86953 -227.712524)
				)
			)
		)
	)
	(zone
		(layers "In1.Cu" "In2.Cu")
		(hatch none 0.5)
		(connect_pads
			(clearance 0)
		)
		(min_thickness 0.25)
		(keepout
			(tracks not_allowed)
			(vias allowed)
			(pads allowed)
			(copperpour not_allowed)
			(footprints allowed)
		)
		(placement
			(enabled no)
			(sheetname "")
		)
		(fill yes
			(thermal_gap 0.5)
			(thermal_bridge_width 0.5)
			(island_removal_mode 0)
		)
		(polygon
			(pts
				(arc
					(start 308.136798 -308.871366)
					(mid 308.151677 -308.907287)
					(end 308.187598 -308.922166)
				)
				(arc
					(start 309.587138 -308.922166)
					(mid 309.623059 -308.907287)
					(end 309.637938 -308.871366)
				)
				(arc
					(start 309.637938 -308.462426)
					(mid 309.623059 -308.426505)
					(end 309.587138 -308.411626)
				)
				(arc
					(start 308.187598 -308.411626)
					(mid 308.151677 -308.426505)
					(end 308.136798 -308.462426)
				)
			)
		)
	)
	(zone
		(layers "In1.Cu" "In2.Cu")
		(hatch none 0.5)
		(connect_pads
			(clearance 0)
		)
		(min_thickness 0.25)
		(keepout
			(tracks not_allowed)
			(vias allowed)
			(pads allowed)
			(copperpour not_allowed)
			(footprints allowed)
		)
		(placement
			(enabled no)
			(sheetname "")
		)
		(fill yes
			(thermal_gap 0.5)
			(thermal_bridge_width 0.5)
			(island_removal_mode 0)
		)
		(polygon
			(pts
				(arc
					(start 428.634398 -284.221428)
					(mid 428.649277 -284.257349)
					(end 428.685198 -284.272228)
				)
				(arc
					(start 430.084738 -284.272228)
					(mid 430.120659 -284.257349)
					(end 430.135538 -284.221428)
				)
				(arc
					(start 430.135538 -283.812488)
					(mid 430.120659 -283.776567)
					(end 430.084738 -283.761688)
				)
				(arc
					(start 428.685198 -283.761688)
					(mid 428.649277 -283.776567)
					(end 428.634398 -283.812488)
				)
			)
		)
	)
	(zone
		(layers "In1.Cu" "In2.Cu")
		(hatch none 0.5)
		(connect_pads
			(clearance 0)
		)
		(min_thickness 0.25)
		(keepout
			(tracks not_allowed)
			(vias allowed)
			(pads allowed)
			(copperpour not_allowed)
			(footprints allowed)
		)
		(placement
			(enabled no)
			(sheetname "")
		)
		(fill yes
			(thermal_gap 0.5)
			(thermal_bridge_width 0.5)
			(island_removal_mode 0)
		)
		(polygon
			(pts
				(arc
					(start 432.734466 -306.32146)
					(mid 432.749345 -306.357381)
					(end 432.785266 -306.37226)
				)
				(arc
					(start 434.184806 -306.37226)
					(mid 434.220727 -306.357381)
					(end 434.235606 -306.32146)
				)
				(arc
					(start 434.235606 -305.91252)
					(mid 434.220727 -305.876599)
					(end 434.184806 -305.86172)
				)
				(arc
					(start 432.785266 -305.86172)
					(mid 432.749345 -305.876599)
					(end 432.734466 -305.91252)
				)
			)
		)
	)
	(zone
		(layers "In1.Cu" "In2.Cu")
		(hatch none 0.5)
		(connect_pads
			(clearance 0)
		)
		(min_thickness 0.25)
		(keepout
			(tracks not_allowed)
			(vias allowed)
			(pads allowed)
			(copperpour not_allowed)
			(footprints allowed)
		)
		(placement
			(enabled no)
			(sheetname "")
		)
		(fill yes
			(thermal_gap 0.5)
			(thermal_bridge_width 0.5)
			(island_removal_mode 0)
		)
		(polygon
			(pts
				(arc
					(start 45.10913 -251.07138)
					(mid 45.124009 -251.107301)
					(end 45.15993 -251.12218)
				)
				(arc
					(start 46.55947 -251.12218)
					(mid 46.595391 -251.107301)
					(end 46.61027 -251.07138)
				)
				(arc
					(start 46.61027 -250.66244)
					(mid 46.595391 -250.626519)
					(end 46.55947 -250.61164)
				)
				(arc
					(start 45.15993 -250.61164)
					(mid 45.124009 -250.626519)
					(end 45.10913 -250.66244)
				)
			)
		)
	)
	(zone
		(layers "In1.Cu" "In2.Cu")
		(hatch none 0.5)
		(connect_pads
			(clearance 0)
		)
		(min_thickness 0.25)
		(keepout
			(tracks not_allowed)
			(vias allowed)
			(pads allowed)
			(copperpour not_allowed)
			(footprints allowed)
		)
		(placement
			(enabled no)
			(sheetname "")
		)
		(fill yes
			(thermal_gap 0.5)
			(thermal_bridge_width 0.5)
			(island_removal_mode 0)
		)
		(polygon
			(pts
				(arc
					(start 440.278266 -245.12143)
					(mid 440.293145 -245.157351)
					(end 440.329066 -245.17223)
				)
				(arc
					(start 441.728606 -245.17223)
					(mid 441.764527 -245.157351)
					(end 441.779406 -245.12143)
				)
				(arc
					(start 441.779406 -244.71249)
					(mid 441.764527 -244.676569)
					(end 441.728606 -244.66169)
				)
				(arc
					(start 440.329066 -244.66169)
					(mid 440.293145 -244.676569)
					(end 440.278266 -244.71249)
				)
			)
		)
	)
	(zone
		(layers "In1.Cu" "In2.Cu")
		(hatch none 0.5)
		(connect_pads
			(clearance 0)
		)
		(min_thickness 0.25)
		(keepout
			(tracks not_allowed)
			(vias allowed)
			(pads allowed)
			(copperpour not_allowed)
			(footprints allowed)
		)
		(placement
			(enabled no)
			(sheetname "")
		)
		(fill yes
			(thermal_gap 0.5)
			(thermal_bridge_width 0.5)
			(island_removal_mode 0)
		)
		(polygon
			(pts
				(arc
					(start 199.881998 -284.221428)
					(mid 199.896877 -284.257349)
					(end 199.932798 -284.272228)
				)
				(arc
					(start 201.332338 -284.272228)
					(mid 201.368259 -284.257349)
					(end 201.383138 -284.221428)
				)
				(arc
					(start 201.383138 -283.812488)
					(mid 201.368259 -283.776567)
					(end 201.332338 -283.761688)
				)
				(arc
					(start 199.932798 -283.761688)
					(mid 199.896877 -283.776567)
					(end 199.881998 -283.812488)
				)
			)
		)
	)
	(zone
		(layers "In1.Cu" "In2.Cu")
		(hatch none 0.5)
		(connect_pads
			(clearance 0)
		)
		(min_thickness 0.25)
		(keepout
			(tracks not_allowed)
			(vias allowed)
			(pads allowed)
			(copperpour not_allowed)
			(footprints allowed)
		)
		(placement
			(enabled no)
			(sheetname "")
		)
		(fill yes
			(thermal_gap 0.5)
			(thermal_bridge_width 0.5)
			(island_removal_mode 0)
		)
		(polygon
			(pts
				(arc
					(start 458.809598 -273.171412)
					(mid 458.824477 -273.207333)
					(end 458.860398 -273.222212)
				)
				(arc
					(start 460.259938 -273.222212)
					(mid 460.295859 -273.207333)
					(end 460.310738 -273.171412)
				)
				(arc
					(start 460.310738 -272.762472)
					(mid 460.295859 -272.726551)
					(end 460.259938 -272.711672)
				)
				(arc
					(start 458.860398 -272.711672)
					(mid 458.824477 -272.726551)
					(end 458.809598 -272.762472)
				)
			)
		)
	)
	(zone
		(layers "In1.Cu" "In2.Cu")
		(hatch none 0.5)
		(connect_pads
			(clearance 0)
		)
		(min_thickness 0.25)
		(keepout
			(tracks not_allowed)
			(vias allowed)
			(pads allowed)
			(copperpour not_allowed)
			(footprints allowed)
		)
		(placement
			(enabled no)
			(sheetname "")
		)
		(fill yes
			(thermal_gap 0.5)
			(thermal_bridge_width 0.5)
			(island_removal_mode 0)
		)
		(polygon
			(pts
				(arc
					(start 49.209198 -259.57149)
					(mid 49.224077 -259.607411)
					(end 49.259998 -259.62229)
				)
				(arc
					(start 50.659538 -259.62229)
					(mid 50.695459 -259.607411)
					(end 50.710338 -259.57149)
				)
				(arc
					(start 50.710338 -259.16255)
					(mid 50.695459 -259.126629)
					(end 50.659538 -259.11175)
				)
				(arc
					(start 49.259998 -259.11175)
					(mid 49.224077 -259.126629)
					(end 49.209198 -259.16255)
				)
			)
		)
	)
	(zone
		(layers "In1.Cu" "In2.Cu")
		(hatch none 0.5)
		(connect_pads
			(clearance 0)
		)
		(min_thickness 0.25)
		(keepout
			(tracks not_allowed)
			(vias allowed)
			(pads allowed)
			(copperpour not_allowed)
			(footprints allowed)
		)
		(placement
			(enabled no)
			(sheetname "")
		)
		(fill yes
			(thermal_gap 0.5)
			(thermal_bridge_width 0.5)
			(island_removal_mode 0)
		)
		(polygon
			(pts
				(arc
					(start 462.909666 -291.021516)
					(mid 462.924545 -291.057437)
					(end 462.960466 -291.072316)
				)
				(arc
					(start 464.360006 -291.072316)
					(mid 464.395927 -291.057437)
					(end 464.410806 -291.021516)
				)
				(arc
					(start 464.410806 -290.612576)
					(mid 464.395927 -290.576655)
					(end 464.360006 -290.561776)
				)
				(arc
					(start 462.960466 -290.561776)
					(mid 462.924545 -290.576655)
					(end 462.909666 -290.612576)
				)
			)
		)
	)
	(zone
		(layers "In1.Cu" "In2.Cu")
		(hatch none 0.5)
		(connect_pads
			(clearance 0)
		)
		(min_thickness 0.25)
		(keepout
			(tracks not_allowed)
			(vias allowed)
			(pads allowed)
			(copperpour not_allowed)
			(footprints allowed)
		)
		(placement
			(enabled no)
			(sheetname "")
		)
		(fill yes
			(thermal_gap 0.5)
			(thermal_bridge_width 0.5)
			(island_removal_mode 0)
		)
		(polygon
			(pts
				(arc
					(start 11.490198 -225.571304)
					(mid 11.505077 -225.607225)
					(end 11.540998 -225.622104)
				)
				(arc
					(start 12.940538 -225.622104)
					(mid 12.976459 -225.607225)
					(end 12.991338 -225.571304)
				)
				(arc
					(start 12.991338 -225.162364)
					(mid 12.976459 -225.126443)
					(end 12.940538 -225.111564)
				)
				(arc
					(start 11.540998 -225.111564)
					(mid 11.505077 -225.126443)
					(end 11.490198 -225.162364)
				)
			)
		)
	)
	(zone
		(layers "In1.Cu" "In2.Cu")
		(hatch none 0.5)
		(connect_pads
			(clearance 0)
		)
		(min_thickness 0.25)
		(keepout
			(tracks not_allowed)
			(vias allowed)
			(pads allowed)
			(copperpour not_allowed)
			(footprints allowed)
		)
		(placement
			(enabled no)
			(sheetname "")
		)
		(fill yes
			(thermal_gap 0.5)
			(thermal_bridge_width 0.5)
			(island_removal_mode 0)
		)
		(polygon
			(pts
				(arc
					(start 177.250598 -309.721504)
					(mid 177.265477 -309.757425)
					(end 177.301398 -309.772304)
				)
				(arc
					(start 178.700938 -309.772304)
					(mid 178.736859 -309.757425)
					(end 178.751738 -309.721504)
				)
				(arc
					(start 178.751738 -309.312564)
					(mid 178.736859 -309.276643)
					(end 178.700938 -309.261764)
				)
				(arc
					(start 177.301398 -309.261764)
					(mid 177.265477 -309.276643)
					(end 177.250598 -309.312564)
				)
			)
		)
	)
	(zone
		(layers "In1.Cu" "In2.Cu")
		(hatch none 0.5)
		(connect_pads
			(clearance 0)
		)
		(min_thickness 0.25)
		(keepout
			(tracks not_allowed)
			(vias allowed)
			(pads allowed)
			(copperpour not_allowed)
			(footprints allowed)
		)
		(placement
			(enabled no)
			(sheetname "")
		)
		(fill yes
			(thermal_gap 0.5)
			(thermal_bridge_width 0.5)
			(island_removal_mode 0)
		)
		(polygon
			(pts
				(arc
					(start 7.39013 -232.371392)
					(mid 7.405009 -232.407313)
					(end 7.44093 -232.422192)
				)
				(arc
					(start 8.84047 -232.422192)
					(mid 8.876391 -232.407313)
					(end 8.89127 -232.371392)
				)
				(arc
					(start 8.89127 -231.962452)
					(mid 8.876391 -231.926531)
					(end 8.84047 -231.911652)
				)
				(arc
					(start 7.44093 -231.911652)
					(mid 7.405009 -231.926531)
					(end 7.39013 -231.962452)
				)
			)
		)
	)
	(zone
		(layers "In1.Cu" "In2.Cu")
		(hatch none 0.5)
		(connect_pads
			(clearance 0)
		)
		(min_thickness 0.25)
		(keepout
			(tracks not_allowed)
			(vias allowed)
			(pads allowed)
			(copperpour not_allowed)
			(footprints allowed)
		)
		(placement
			(enabled no)
			(sheetname "")
		)
		(fill yes
			(thermal_gap 0.5)
			(thermal_bridge_width 0.5)
			(island_removal_mode 0)
		)
		(polygon
			(pts
				(arc
					(start 406.002998 -285.071312)
					(mid 406.017877 -285.107233)
					(end 406.053798 -285.122112)
				)
				(arc
					(start 407.453338 -285.122112)
					(mid 407.489259 -285.107233)
					(end 407.504138 -285.071312)
				)
				(arc
					(start 407.504138 -284.662372)
					(mid 407.489259 -284.626451)
					(end 407.453338 -284.611572)
				)
				(arc
					(start 406.053798 -284.611572)
					(mid 406.017877 -284.626451)
					(end 406.002998 -284.662372)
				)
			)
		)
	)
	(zone
		(layers "In1.Cu" "In2.Cu")
		(hatch none 0.5)
		(connect_pads
			(clearance 0)
		)
		(min_thickness 0.25)
		(keepout
			(tracks not_allowed)
			(vias allowed)
			(pads allowed)
			(copperpour not_allowed)
			(footprints allowed)
		)
		(placement
			(enabled no)
			(sheetname "")
		)
		(fill yes
			(thermal_gap 0.5)
			(thermal_bridge_width 0.5)
			(island_removal_mode 0)
		)
		(polygon
			(pts
				(arc
					(start 169.706798 -312.27141)
					(mid 169.721677 -312.307331)
					(end 169.757598 -312.32221)
				)
				(arc
					(start 171.157138 -312.32221)
					(mid 171.193059 -312.307331)
					(end 171.207938 -312.27141)
				)
				(arc
					(start 171.207938 -311.86247)
					(mid 171.193059 -311.826549)
					(end 171.157138 -311.81167)
				)
				(arc
					(start 169.757598 -311.81167)
					(mid 169.721677 -311.826549)
					(end 169.706798 -311.86247)
				)
			)
		)
	)
	(zone
		(layers "In1.Cu" "In2.Cu")
		(hatch none 0.5)
		(connect_pads
			(clearance 0)
		)
		(min_thickness 0.25)
		(keepout
			(tracks not_allowed)
			(vias allowed)
			(pads allowed)
			(copperpour not_allowed)
			(footprints allowed)
		)
		(placement
			(enabled no)
			(sheetname "")
		)
		(fill yes
			(thermal_gap 0.5)
			(thermal_bridge_width 0.5)
			(island_removal_mode 0)
		)
		(polygon
			(pts
				(arc
					(start 34.121598 -296.971466)
					(mid 34.136477 -297.007387)
					(end 34.172398 -297.022266)
				)
				(arc
					(start 35.571938 -297.022266)
					(mid 35.607859 -297.007387)
					(end 35.622738 -296.971466)
				)
				(arc
					(start 35.622738 -296.562526)
					(mid 35.607859 -296.526605)
					(end 35.571938 -296.511726)
				)
				(arc
					(start 34.172398 -296.511726)
					(mid 34.136477 -296.526605)
					(end 34.121598 -296.562526)
				)
			)
		)
	)
	(zone
		(layers "In1.Cu" "In2.Cu")
		(hatch none 0.5)
		(connect_pads
			(clearance 0)
		)
		(min_thickness 0.25)
		(keepout
			(tracks not_allowed)
			(vias allowed)
			(pads allowed)
			(copperpour not_allowed)
			(footprints allowed)
		)
		(placement
			(enabled no)
			(sheetname "")
		)
		(fill yes
			(thermal_gap 0.5)
			(thermal_bridge_width 0.5)
			(island_removal_mode 0)
		)
		(polygon
			(pts
				(arc
					(start 158.06293 -228.121464)
					(mid 158.077809 -228.157385)
					(end 158.11373 -228.172264)
				)
				(arc
					(start 159.51327 -228.172264)
					(mid 159.549191 -228.157385)
					(end 159.56407 -228.121464)
				)
				(arc
					(start 159.56407 -227.712524)
					(mid 159.549191 -227.676603)
					(end 159.51327 -227.661724)
				)
				(arc
					(start 158.11373 -227.661724)
					(mid 158.077809 -227.676603)
					(end 158.06293 -227.712524)
				)
			)
		)
	)
	(zone
		(layers "In1.Cu" "In2.Cu")
		(hatch none 0.5)
		(connect_pads
			(clearance 0)
		)
		(min_thickness 0.25)
		(keepout
			(tracks not_allowed)
			(vias allowed)
			(pads allowed)
			(copperpour not_allowed)
			(footprints allowed)
		)
		(placement
			(enabled no)
			(sheetname "")
		)
		(fill yes
			(thermal_gap 0.5)
			(thermal_bridge_width 0.5)
			(island_removal_mode 0)
		)
		(polygon
			(pts
				(arc
					(start 199.881998 -201.771504)
					(mid 199.896877 -201.807425)
					(end 199.932798 -201.822304)
				)
				(arc
					(start 201.332338 -201.822304)
					(mid 201.368259 -201.807425)
					(end 201.383138 -201.771504)
				)
				(arc
					(start 201.383138 -201.362564)
					(mid 201.368259 -201.326643)
					(end 201.332338 -201.311764)
				)
				(arc
					(start 199.932798 -201.311764)
					(mid 199.896877 -201.326643)
					(end 199.881998 -201.362564)
				)
			)
		)
	)
	(zone
		(layers "In1.Cu" "In2.Cu")
		(hatch none 0.5)
		(connect_pads
			(clearance 0)
		)
		(min_thickness 0.25)
		(keepout
			(tracks not_allowed)
			(vias allowed)
			(pads allowed)
			(copperpour not_allowed)
			(footprints allowed)
		)
		(placement
			(enabled no)
			(sheetname "")
		)
		(fill yes
			(thermal_gap 0.5)
			(thermal_bridge_width 0.5)
			(island_removal_mode 0)
		)
		(polygon
			(pts
				(arc
					(start 22.47773 -261.271512)
					(mid 22.492609 -261.307433)
					(end 22.52853 -261.322312)
				)
				(arc
					(start 23.92807 -261.322312)
					(mid 23.963991 -261.307433)
					(end 23.97887 -261.271512)
				)
				(arc
					(start 23.97887 -260.862572)
					(mid 23.963991 -260.826651)
					(end 23.92807 -260.811772)
				)
				(arc
					(start 22.52853 -260.811772)
					(mid 22.492609 -260.826651)
					(end 22.47773 -260.862572)
				)
			)
		)
	)
	(zone
		(layers "In1.Cu" "In2.Cu")
		(hatch none 0.5)
		(connect_pads
			(clearance 0)
		)
		(min_thickness 0.25)
		(keepout
			(tracks not_allowed)
			(vias allowed)
			(pads allowed)
			(copperpour not_allowed)
			(footprints allowed)
		)
		(placement
			(enabled no)
			(sheetname "")
		)
		(fill yes
			(thermal_gap 0.5)
			(thermal_bridge_width 0.5)
			(island_removal_mode 0)
		)
		(polygon
			(pts
				(arc
					(start 199.881998 -206.871316)
					(mid 199.896877 -206.907237)
					(end 199.932798 -206.922116)
				)
				(arc
					(start 201.332338 -206.922116)
					(mid 201.368259 -206.907237)
					(end 201.383138 -206.871316)
				)
				(arc
					(start 201.383138 -206.462376)
					(mid 201.368259 -206.426455)
					(end 201.332338 -206.411576)
				)
				(arc
					(start 199.932798 -206.411576)
					(mid 199.896877 -206.426455)
					(end 199.881998 -206.462376)
				)
			)
		)
	)
	(zone
		(layers "In1.Cu" "In2.Cu")
		(hatch none 0.5)
		(connect_pads
			(clearance 0)
		)
		(min_thickness 0.25)
		(keepout
			(tracks not_allowed)
			(vias allowed)
			(pads allowed)
			(copperpour not_allowed)
			(footprints allowed)
		)
		(placement
			(enabled no)
			(sheetname "")
		)
		(fill yes
			(thermal_gap 0.5)
			(thermal_bridge_width 0.5)
			(island_removal_mode 0)
		)
		(polygon
			(pts
				(arc
					(start 462.909666 -304.621438)
					(mid 462.924545 -304.657359)
					(end 462.960466 -304.672238)
				)
				(arc
					(start 464.360006 -304.672238)
					(mid 464.395927 -304.657359)
					(end 464.410806 -304.621438)
				)
				(arc
					(start 464.410806 -304.212498)
					(mid 464.395927 -304.176577)
					(end 464.360006 -304.161698)
				)
				(arc
					(start 462.960466 -304.161698)
					(mid 462.924545 -304.176577)
					(end 462.909666 -304.212498)
				)
			)
		)
	)
	(zone
		(layers "In1.Cu" "In2.Cu")
		(hatch none 0.5)
		(connect_pads
			(clearance 0)
		)
		(min_thickness 0.25)
		(keepout
			(tracks not_allowed)
			(vias allowed)
			(pads allowed)
			(copperpour not_allowed)
			(footprints allowed)
		)
		(placement
			(enabled no)
			(sheetname "")
		)
		(fill yes
			(thermal_gap 0.5)
			(thermal_bridge_width 0.5)
			(island_removal_mode 0)
		)
		(polygon
			(pts
				(arc
					(start 308.136798 -264.671302)
					(mid 308.151677 -264.707223)
					(end 308.187598 -264.722102)
				)
				(arc
					(start 309.587138 -264.722102)
					(mid 309.623059 -264.707223)
					(end 309.637938 -264.671302)
				)
				(arc
					(start 309.637938 -264.262362)
					(mid 309.623059 -264.226441)
					(end 309.587138 -264.211562)
				)
				(arc
					(start 308.187598 -264.211562)
					(mid 308.151677 -264.226441)
					(end 308.136798 -264.262362)
				)
			)
		)
	)
	(zone
		(layers "In1.Cu" "In2.Cu")
		(hatch none 0.5)
		(connect_pads
			(clearance 0)
		)
		(min_thickness 0.25)
		(keepout
			(tracks not_allowed)
			(vias allowed)
			(pads allowed)
			(copperpour not_allowed)
			(footprints allowed)
		)
		(placement
			(enabled no)
			(sheetname "")
		)
		(fill yes
			(thermal_gap 0.5)
			(thermal_bridge_width 0.5)
			(island_removal_mode 0)
		)
		(polygon
			(pts
				(arc
					(start 451.265798 -262.971534)
					(mid 451.280677 -263.007455)
					(end 451.316598 -263.022334)
				)
				(arc
					(start 452.716138 -263.022334)
					(mid 452.752059 -263.007455)
					(end 452.766938 -262.971534)
				)
				(arc
					(start 452.766938 -262.562594)
					(mid 452.752059 -262.526673)
					(end 452.716138 -262.511794)
				)
				(arc
					(start 451.316598 -262.511794)
					(mid 451.280677 -262.526673)
					(end 451.265798 -262.562594)
				)
			)
		)
	)
	(zone
		(layers "In1.Cu" "In2.Cu")
		(hatch none 0.5)
		(connect_pads
			(clearance 0)
		)
		(min_thickness 0.25)
		(keepout
			(tracks not_allowed)
			(vias allowed)
			(pads allowed)
			(copperpour not_allowed)
			(footprints allowed)
		)
		(placement
			(enabled no)
			(sheetname "")
		)
		(fill yes
			(thermal_gap 0.5)
			(thermal_bridge_width 0.5)
			(island_removal_mode 0)
		)
		(polygon
			(pts
				(arc
					(start 158.06293 -307.171344)
					(mid 158.077809 -307.207265)
					(end 158.11373 -307.222144)
				)
				(arc
					(start 159.51327 -307.222144)
					(mid 159.549191 -307.207265)
					(end 159.56407 -307.171344)
				)
				(arc
					(start 159.56407 -306.762404)
					(mid 159.549191 -306.726483)
					(end 159.51327 -306.711604)
				)
				(arc
					(start 158.11373 -306.711604)
					(mid 158.077809 -306.726483)
					(end 158.06293 -306.762404)
				)
			)
		)
	)
	(zone
		(layers "In1.Cu" "In2.Cu")
		(hatch none 0.5)
		(connect_pads
			(clearance 0)
		)
		(min_thickness 0.25)
		(keepout
			(tracks not_allowed)
			(vias allowed)
			(pads allowed)
			(copperpour not_allowed)
			(footprints allowed)
		)
		(placement
			(enabled no)
			(sheetname "")
		)
		(fill yes
			(thermal_gap 0.5)
			(thermal_bridge_width 0.5)
			(island_removal_mode 0)
		)
		(polygon
			(pts
				(arc
					(start 7.39013 -230.67137)
					(mid 7.405009 -230.707291)
					(end 7.44093 -230.72217)
				)
				(arc
					(start 8.84047 -230.72217)
					(mid 8.876391 -230.707291)
					(end 8.89127 -230.67137)
				)
				(arc
					(start 8.89127 -230.26243)
					(mid 8.876391 -230.226509)
					(end 8.84047 -230.21163)
				)
				(arc
					(start 7.44093 -230.21163)
					(mid 7.405009 -230.226509)
					(end 7.39013 -230.26243)
				)
			)
		)
	)
	(zone
		(layers "In1.Cu" "In2.Cu")
		(hatch none 0.5)
		(connect_pads
			(clearance 0)
		)
		(min_thickness 0.25)
		(keepout
			(tracks not_allowed)
			(vias allowed)
			(pads allowed)
			(copperpour not_allowed)
			(footprints allowed)
		)
		(placement
			(enabled no)
			(sheetname "")
		)
		(fill yes
			(thermal_gap 0.5)
			(thermal_bridge_width 0.5)
			(island_removal_mode 0)
		)
		(polygon
			(pts
				(arc
					(start 455.365866 -200.071482)
					(mid 455.380745 -200.107403)
					(end 455.416666 -200.122282)
				)
				(arc
					(start 456.816206 -200.122282)
					(mid 456.852127 -200.107403)
					(end 456.867006 -200.071482)
				)
				(arc
					(start 456.867006 -199.662542)
					(mid 456.852127 -199.626621)
					(end 456.816206 -199.611742)
				)
				(arc
					(start 455.416666 -199.611742)
					(mid 455.380745 -199.626621)
					(end 455.365866 -199.662542)
				)
			)
		)
	)
	(zone
		(layers "In1.Cu" "In2.Cu")
		(hatch none 0.5)
		(connect_pads
			(clearance 0)
		)
		(min_thickness 0.25)
		(keepout
			(tracks not_allowed)
			(vias allowed)
			(pads allowed)
			(copperpour not_allowed)
			(footprints allowed)
		)
		(placement
			(enabled no)
			(sheetname "")
		)
		(fill yes
			(thermal_gap 0.5)
			(thermal_bridge_width 0.5)
			(island_removal_mode 0)
		)
		(polygon
			(pts
				(arc
					(start 162.162998 -293.571422)
					(mid 162.177877 -293.607343)
					(end 162.213798 -293.622222)
				)
				(arc
					(start 163.613338 -293.622222)
					(mid 163.649259 -293.607343)
					(end 163.664138 -293.571422)
				)
				(arc
					(start 163.664138 -293.162482)
					(mid 163.649259 -293.126561)
					(end 163.613338 -293.111682)
				)
				(arc
					(start 162.213798 -293.111682)
					(mid 162.177877 -293.126561)
					(end 162.162998 -293.162482)
				)
			)
		)
	)
	(zone
		(layers "In1.Cu" "In2.Cu")
		(hatch none 0.5)
		(connect_pads
			(clearance 0)
		)
		(min_thickness 0.25)
		(keepout
			(tracks not_allowed)
			(vias allowed)
			(pads allowed)
			(copperpour not_allowed)
			(footprints allowed)
		)
		(placement
			(enabled no)
			(sheetname "")
		)
		(fill yes
			(thermal_gap 0.5)
			(thermal_bridge_width 0.5)
			(island_removal_mode 0)
		)
		(polygon
			(pts
				(arc
					(start 26.577798 -236.62132)
					(mid 26.592677 -236.657241)
					(end 26.628598 -236.67212)
				)
				(arc
					(start 28.028138 -236.67212)
					(mid 28.064059 -236.657241)
					(end 28.078938 -236.62132)
				)
				(arc
					(start 28.078938 -236.21238)
					(mid 28.064059 -236.176459)
					(end 28.028138 -236.16158)
				)
				(arc
					(start 26.628598 -236.16158)
					(mid 26.592677 -236.176459)
					(end 26.577798 -236.21238)
				)
			)
		)
	)
	(zone
		(layers "In1.Cu" "In2.Cu")
		(hatch none 0.5)
		(connect_pads
			(clearance 0)
		)
		(min_thickness 0.25)
		(keepout
			(tracks not_allowed)
			(vias allowed)
			(pads allowed)
			(copperpour not_allowed)
			(footprints allowed)
		)
		(placement
			(enabled no)
			(sheetname "")
		)
		(fill yes
			(thermal_gap 0.5)
			(thermal_bridge_width 0.5)
			(island_removal_mode 0)
		)
		(polygon
			(pts
				(arc
					(start 64.296798 -283.371544)
					(mid 64.311677 -283.407465)
					(end 64.347598 -283.422344)
				)
				(arc
					(start 65.747138 -283.422344)
					(mid 65.783059 -283.407465)
					(end 65.797938 -283.371544)
				)
				(arc
					(start 65.797938 -282.962604)
					(mid 65.783059 -282.926683)
					(end 65.747138 -282.911804)
				)
				(arc
					(start 64.347598 -282.911804)
					(mid 64.311677 -282.926683)
					(end 64.296798 -282.962604)
				)
			)
		)
	)
	(zone
		(layers "In1.Cu" "In2.Cu")
		(hatch none 0.5)
		(connect_pads
			(clearance 0)
		)
		(min_thickness 0.25)
		(keepout
			(tracks not_allowed)
			(vias allowed)
			(pads allowed)
			(copperpour not_allowed)
			(footprints allowed)
		)
		(placement
			(enabled no)
			(sheetname "")
		)
		(fill yes
			(thermal_gap 0.5)
			(thermal_bridge_width 0.5)
			(island_removal_mode 0)
		)
		(polygon
			(pts
				(arc
					(start 312.236866 -311.421526)
					(mid 312.251745 -311.457447)
					(end 312.287666 -311.472326)
				)
				(arc
					(start 313.687206 -311.472326)
					(mid 313.723127 -311.457447)
					(end 313.738006 -311.421526)
				)
				(arc
					(start 313.738006 -311.012586)
					(mid 313.723127 -310.976665)
					(end 313.687206 -310.961786)
				)
				(arc
					(start 312.287666 -310.961786)
					(mid 312.251745 -310.976665)
					(end 312.236866 -311.012586)
				)
			)
		)
	)
	(zone
		(layers "In1.Cu" "In2.Cu")
		(hatch none 0.5)
		(connect_pads
			(clearance 0)
		)
		(min_thickness 0.25)
		(keepout
			(tracks not_allowed)
			(vias allowed)
			(pads allowed)
			(copperpour not_allowed)
			(footprints allowed)
		)
		(placement
			(enabled no)
			(sheetname "")
		)
		(fill yes
			(thermal_gap 0.5)
			(thermal_bridge_width 0.5)
			(island_removal_mode 0)
		)
		(polygon
			(pts
				(arc
					(start 162.162998 -220.471492)
					(mid 162.177877 -220.507413)
					(end 162.213798 -220.522292)
				)
				(arc
					(start 163.613338 -220.522292)
					(mid 163.649259 -220.507413)
					(end 163.664138 -220.471492)
				)
				(arc
					(start 163.664138 -220.062552)
					(mid 163.649259 -220.026631)
					(end 163.613338 -220.011752)
				)
				(arc
					(start 162.213798 -220.011752)
					(mid 162.177877 -220.026631)
					(end 162.162998 -220.062552)
				)
			)
		)
	)
	(zone
		(layers "In1.Cu" "In2.Cu")
		(hatch none 0.5)
		(connect_pads
			(clearance 0)
		)
		(min_thickness 0.25)
		(keepout
			(tracks not_allowed)
			(vias allowed)
			(pads allowed)
			(copperpour not_allowed)
			(footprints allowed)
		)
		(placement
			(enabled no)
			(sheetname "")
		)
		(fill yes
			(thermal_gap 0.5)
			(thermal_bridge_width 0.5)
			(island_removal_mode 0)
		)
		(polygon
			(pts
				(arc
					(start 169.706798 -293.571422)
					(mid 169.721677 -293.607343)
					(end 169.757598 -293.622222)
				)
				(arc
					(start 171.157138 -293.622222)
					(mid 171.193059 -293.607343)
					(end 171.207938 -293.571422)
				)
				(arc
					(start 171.207938 -293.162482)
					(mid 171.193059 -293.126561)
					(end 171.157138 -293.111682)
				)
				(arc
					(start 169.757598 -293.111682)
					(mid 169.721677 -293.126561)
					(end 169.706798 -293.162482)
				)
			)
		)
	)
	(zone
		(layers "In1.Cu" "In2.Cu")
		(hatch none 0.5)
		(connect_pads
			(clearance 0)
		)
		(min_thickness 0.25)
		(keepout
			(tracks not_allowed)
			(vias allowed)
			(pads allowed)
			(copperpour not_allowed)
			(footprints allowed)
		)
		(placement
			(enabled no)
			(sheetname "")
		)
		(fill yes
			(thermal_gap 0.5)
			(thermal_bridge_width 0.5)
			(island_removal_mode 0)
		)
		(polygon
			(pts
				(arc
					(start 11.490198 -287.621472)
					(mid 11.505077 -287.657393)
					(end 11.540998 -287.672272)
				)
				(arc
					(start 12.940538 -287.672272)
					(mid 12.976459 -287.657393)
					(end 12.991338 -287.621472)
				)
				(arc
					(start 12.991338 -287.212532)
					(mid 12.976459 -287.176611)
					(end 12.940538 -287.161732)
				)
				(arc
					(start 11.540998 -287.161732)
					(mid 11.505077 -287.176611)
					(end 11.490198 -287.212532)
				)
			)
		)
	)
	(zone
		(layers "In1.Cu" "In2.Cu")
		(hatch none 0.5)
		(connect_pads
			(clearance 0)
		)
		(min_thickness 0.25)
		(keepout
			(tracks not_allowed)
			(vias allowed)
			(pads allowed)
			(copperpour not_allowed)
			(footprints allowed)
		)
		(placement
			(enabled no)
			(sheetname "")
		)
		(fill yes
			(thermal_gap 0.5)
			(thermal_bridge_width 0.5)
			(island_removal_mode 0)
		)
		(polygon
			(pts
				(arc
					(start 428.634398 -312.27141)
					(mid 428.649277 -312.307331)
					(end 428.685198 -312.32221)
				)
				(arc
					(start 430.084738 -312.32221)
					(mid 430.120659 -312.307331)
					(end 430.135538 -312.27141)
				)
				(arc
					(start 430.135538 -311.86247)
					(mid 430.120659 -311.826549)
					(end 430.084738 -311.81167)
				)
				(arc
					(start 428.685198 -311.81167)
					(mid 428.649277 -311.826549)
					(end 428.634398 -311.86247)
				)
			)
		)
	)
	(zone
		(layers "In1.Cu" "In2.Cu")
		(hatch none 0.5)
		(connect_pads
			(clearance 0)
		)
		(min_thickness 0.25)
		(keepout
			(tracks not_allowed)
			(vias allowed)
			(pads allowed)
			(copperpour not_allowed)
			(footprints allowed)
		)
		(placement
			(enabled no)
			(sheetname "")
		)
		(fill yes
			(thermal_gap 0.5)
			(thermal_bridge_width 0.5)
			(island_removal_mode 0)
		)
		(polygon
			(pts
				(arc
					(start 162.162998 -214.521542)
					(mid 162.177877 -214.557463)
					(end 162.213798 -214.572342)
				)
				(arc
					(start 163.613338 -214.572342)
					(mid 163.649259 -214.557463)
					(end 163.664138 -214.521542)
				)
				(arc
					(start 163.664138 -214.112602)
					(mid 163.649259 -214.076681)
					(end 163.613338 -214.061802)
				)
				(arc
					(start 162.213798 -214.061802)
					(mid 162.177877 -214.076681)
					(end 162.162998 -214.112602)
				)
			)
		)
	)
	(zone
		(layers "In1.Cu" "In2.Cu")
		(hatch none 0.5)
		(connect_pads
			(clearance 0)
		)
		(min_thickness 0.25)
		(keepout
			(tracks not_allowed)
			(vias allowed)
			(pads allowed)
			(copperpour not_allowed)
			(footprints allowed)
		)
		(placement
			(enabled no)
			(sheetname "")
		)
		(fill yes
			(thermal_gap 0.5)
			(thermal_bridge_width 0.5)
			(island_removal_mode 0)
		)
		(polygon
			(pts
				(arc
					(start 417.646866 -199.221344)
					(mid 417.661745 -199.257265)
					(end 417.697666 -199.272144)
				)
				(arc
					(start 419.097206 -199.272144)
					(mid 419.133127 -199.257265)
					(end 419.148006 -199.221344)
				)
				(arc
					(start 419.148006 -198.812404)
					(mid 419.133127 -198.776483)
					(end 419.097206 -198.761604)
				)
				(arc
					(start 417.697666 -198.761604)
					(mid 417.661745 -198.776483)
					(end 417.646866 -198.812404)
				)
			)
		)
	)
	(zone
		(layers "In1.Cu" "In2.Cu")
		(hatch none 0.5)
		(connect_pads
			(clearance 0)
		)
		(min_thickness 0.25)
		(keepout
			(tracks not_allowed)
			(vias allowed)
			(pads allowed)
			(copperpour not_allowed)
			(footprints allowed)
		)
		(placement
			(enabled no)
			(sheetname "")
		)
		(fill yes
			(thermal_gap 0.5)
			(thermal_bridge_width 0.5)
			(island_removal_mode 0)
		)
		(polygon
			(pts
				(arc
					(start 37.56533 -273.171412)
					(mid 37.580209 -273.207333)
					(end 37.61613 -273.222212)
				)
				(arc
					(start 39.01567 -273.222212)
					(mid 39.051591 -273.207333)
					(end 39.06647 -273.171412)
				)
				(arc
					(start 39.06647 -272.762472)
					(mid 39.051591 -272.726551)
					(end 39.01567 -272.711672)
				)
				(arc
					(start 37.61613 -272.711672)
					(mid 37.580209 -272.726551)
					(end 37.56533 -272.762472)
				)
			)
		)
	)
	(zone
		(layers "In1.Cu" "In2.Cu")
		(hatch none 0.5)
		(connect_pads
			(clearance 0)
		)
		(min_thickness 0.25)
		(keepout
			(tracks not_allowed)
			(vias allowed)
			(pads allowed)
			(copperpour not_allowed)
			(footprints allowed)
		)
		(placement
			(enabled no)
			(sheetname "")
		)
		(fill yes
			(thermal_gap 0.5)
			(thermal_bridge_width 0.5)
			(island_removal_mode 0)
		)
		(polygon
			(pts
				(arc
					(start 19.033998 -312.27141)
					(mid 19.048877 -312.307331)
					(end 19.084798 -312.32221)
				)
				(arc
					(start 20.484338 -312.32221)
					(mid 20.520259 -312.307331)
					(end 20.535138 -312.27141)
				)
				(arc
					(start 20.535138 -311.86247)
					(mid 20.520259 -311.826549)
					(end 20.484338 -311.81167)
				)
				(arc
					(start 19.084798 -311.81167)
					(mid 19.048877 -311.826549)
					(end 19.033998 -311.86247)
				)
			)
		)
	)
	(zone
		(layers "In1.Cu" "In2.Cu")
		(hatch none 0.5)
		(connect_pads
			(clearance 0)
		)
		(min_thickness 0.25)
		(keepout
			(tracks not_allowed)
			(vias allowed)
			(pads allowed)
			(copperpour not_allowed)
			(footprints allowed)
		)
		(placement
			(enabled no)
			(sheetname "")
		)
		(fill yes
			(thermal_gap 0.5)
			(thermal_bridge_width 0.5)
			(island_removal_mode 0)
		)
		(polygon
			(pts
				(arc
					(start 180.69433 -293.571422)
					(mid 180.709209 -293.607343)
					(end 180.74513 -293.622222)
				)
				(arc
					(start 182.14467 -293.622222)
					(mid 182.180591 -293.607343)
					(end 182.19547 -293.571422)
				)
				(arc
					(start 182.19547 -293.162482)
					(mid 182.180591 -293.126561)
					(end 182.14467 -293.111682)
				)
				(arc
					(start 180.74513 -293.111682)
					(mid 180.709209 -293.126561)
					(end 180.69433 -293.162482)
				)
			)
		)
	)
	(zone
		(layers "In1.Cu" "In2.Cu")
		(hatch none 0.5)
		(connect_pads
			(clearance 0)
		)
		(min_thickness 0.25)
		(keepout
			(tracks not_allowed)
			(vias allowed)
			(pads allowed)
			(copperpour not_allowed)
			(footprints allowed)
		)
		(placement
			(enabled no)
			(sheetname "")
		)
		(fill yes
			(thermal_gap 0.5)
			(thermal_bridge_width 0.5)
			(island_removal_mode 0)
		)
		(polygon
			(pts
				(arc
					(start 443.721998 -280.821384)
					(mid 443.736877 -280.857305)
					(end 443.772798 -280.872184)
				)
				(arc
					(start 445.172338 -280.872184)
					(mid 445.208259 -280.857305)
					(end 445.223138 -280.821384)
				)
				(arc
					(start 445.223138 -280.412444)
					(mid 445.208259 -280.376523)
					(end 445.172338 -280.361644)
				)
				(arc
					(start 443.772798 -280.361644)
					(mid 443.736877 -280.376523)
					(end 443.721998 -280.412444)
				)
			)
		)
	)
	(zone
		(layers "In1.Cu" "In2.Cu")
		(hatch none 0.5)
		(connect_pads
			(clearance 0)
		)
		(min_thickness 0.25)
		(keepout
			(tracks not_allowed)
			(vias allowed)
			(pads allowed)
			(copperpour not_allowed)
			(footprints allowed)
		)
		(placement
			(enabled no)
			(sheetname "")
		)
		(fill yes
			(thermal_gap 0.5)
			(thermal_bridge_width 0.5)
			(island_removal_mode 0)
		)
		(polygon
			(pts
				(arc
					(start 158.06293 -291.8714)
					(mid 158.077809 -291.907321)
					(end 158.11373 -291.9222)
				)
				(arc
					(start 159.51327 -291.9222)
					(mid 159.549191 -291.907321)
					(end 159.56407 -291.8714)
				)
				(arc
					(start 159.56407 -291.46246)
					(mid 159.549191 -291.426539)
					(end 159.51327 -291.41166)
				)
				(arc
					(start 158.11373 -291.41166)
					(mid 158.077809 -291.426539)
					(end 158.06293 -291.46246)
				)
			)
		)
	)
	(zone
		(layers "In1.Cu" "In2.Cu")
		(hatch none 0.5)
		(connect_pads
			(clearance 0)
		)
		(min_thickness 0.25)
		(keepout
			(tracks not_allowed)
			(vias allowed)
			(pads allowed)
			(copperpour not_allowed)
			(footprints allowed)
		)
		(placement
			(enabled no)
			(sheetname "")
		)
		(fill yes
			(thermal_gap 0.5)
			(thermal_bridge_width 0.5)
			(island_removal_mode 0)
		)
		(polygon
			(pts
				(arc
					(start 177.250598 -312.27141)
					(mid 177.265477 -312.307331)
					(end 177.301398 -312.32221)
				)
				(arc
					(start 178.700938 -312.32221)
					(mid 178.736859 -312.307331)
					(end 178.751738 -312.27141)
				)
				(arc
					(start 178.751738 -311.86247)
					(mid 178.736859 -311.826549)
					(end 178.700938 -311.81167)
				)
				(arc
					(start 177.301398 -311.81167)
					(mid 177.265477 -311.826549)
					(end 177.250598 -311.86247)
				)
			)
		)
	)
	(zone
		(layers "In1.Cu" "In2.Cu")
		(hatch none 0.5)
		(connect_pads
			(clearance 0)
		)
		(min_thickness 0.25)
		(keepout
			(tracks not_allowed)
			(vias allowed)
			(pads allowed)
			(copperpour not_allowed)
			(footprints allowed)
		)
		(placement
			(enabled no)
			(sheetname "")
		)
		(fill yes
			(thermal_gap 0.5)
			(thermal_bridge_width 0.5)
			(island_removal_mode 0)
		)
		(polygon
			(pts
				(arc
					(start 312.236866 -227.271326)
					(mid 312.251745 -227.307247)
					(end 312.287666 -227.322126)
				)
				(arc
					(start 313.687206 -227.322126)
					(mid 313.723127 -227.307247)
					(end 313.738006 -227.271326)
				)
				(arc
					(start 313.738006 -226.862386)
					(mid 313.723127 -226.826465)
					(end 313.687206 -226.811586)
				)
				(arc
					(start 312.287666 -226.811586)
					(mid 312.251745 -226.826465)
					(end 312.236866 -226.862386)
				)
			)
		)
	)
	(zone
		(layers "In1.Cu" "In2.Cu")
		(hatch none 0.5)
		(connect_pads
			(clearance 0)
		)
		(min_thickness 0.25)
		(keepout
			(tracks not_allowed)
			(vias allowed)
			(pads allowed)
			(copperpour not_allowed)
			(footprints allowed)
		)
		(placement
			(enabled no)
			(sheetname "")
		)
		(fill yes
			(thermal_gap 0.5)
			(thermal_bridge_width 0.5)
			(island_removal_mode 0)
		)
		(polygon
			(pts
				(arc
					(start 259.430266 -200.071482)
					(mid 259.445145 -200.107403)
					(end 259.481066 -200.122282)
				)
				(arc
					(start 260.880606 -200.122282)
					(mid 260.916527 -200.107403)
					(end 260.931406 -200.071482)
				)
				(arc
					(start 260.931406 -199.662542)
					(mid 260.916527 -199.626621)
					(end 260.880606 -199.611742)
				)
				(arc
					(start 259.481066 -199.611742)
					(mid 259.445145 -199.626621)
					(end 259.430266 -199.662542)
				)
			)
		)
	)
	(zone
		(layers "In1.Cu" "In2.Cu")
		(hatch none 0.5)
		(connect_pads
			(clearance 0)
		)
		(min_thickness 0.25)
		(keepout
			(tracks not_allowed)
			(vias allowed)
			(pads allowed)
			(copperpour not_allowed)
			(footprints allowed)
		)
		(placement
			(enabled no)
			(sheetname "")
		)
		(fill yes
			(thermal_gap 0.5)
			(thermal_bridge_width 0.5)
			(island_removal_mode 0)
		)
		(polygon
			(pts
				(arc
					(start 266.974066 -220.471492)
					(mid 266.988945 -220.507413)
					(end 267.024866 -220.522292)
				)
				(arc
					(start 268.424406 -220.522292)
					(mid 268.460327 -220.507413)
					(end 268.475206 -220.471492)
				)
				(arc
					(start 268.475206 -220.062552)
					(mid 268.460327 -220.026631)
					(end 268.424406 -220.011752)
				)
				(arc
					(start 267.024866 -220.011752)
					(mid 266.988945 -220.026631)
					(end 266.974066 -220.062552)
				)
			)
		)
	)
	(zone
		(layers "In1.Cu" "In2.Cu")
		(hatch none 0.5)
		(connect_pads
			(clearance 0)
		)
		(min_thickness 0.25)
		(keepout
			(tracks not_allowed)
			(vias allowed)
			(pads allowed)
			(copperpour not_allowed)
			(footprints allowed)
		)
		(placement
			(enabled no)
			(sheetname "")
		)
		(fill yes
			(thermal_gap 0.5)
			(thermal_bridge_width 0.5)
			(island_removal_mode 0)
		)
		(polygon
			(pts
				(arc
					(start 300.592998 -302.921416)
					(mid 300.607877 -302.957337)
					(end 300.643798 -302.972216)
				)
				(arc
					(start 302.043338 -302.972216)
					(mid 302.079259 -302.957337)
					(end 302.094138 -302.921416)
				)
				(arc
					(start 302.094138 -302.512476)
					(mid 302.079259 -302.476555)
					(end 302.043338 -302.461676)
				)
				(arc
					(start 300.643798 -302.461676)
					(mid 300.607877 -302.476555)
					(end 300.592998 -302.512476)
				)
			)
		)
	)
	(zone
		(layers "In1.Cu" "In2.Cu")
		(hatch none 0.5)
		(connect_pads
			(clearance 0)
		)
		(min_thickness 0.25)
		(keepout
			(tracks not_allowed)
			(vias allowed)
			(pads allowed)
			(copperpour not_allowed)
			(footprints allowed)
		)
		(placement
			(enabled no)
			(sheetname "")
		)
		(fill yes
			(thermal_gap 0.5)
			(thermal_bridge_width 0.5)
			(island_removal_mode 0)
		)
		(polygon
			(pts
				(arc
					(start 26.577798 -250.221496)
					(mid 26.592677 -250.257417)
					(end 26.628598 -250.272296)
				)
				(arc
					(start 28.028138 -250.272296)
					(mid 28.064059 -250.257417)
					(end 28.078938 -250.221496)
				)
				(arc
					(start 28.078938 -249.812556)
					(mid 28.064059 -249.776635)
					(end 28.028138 -249.761756)
				)
				(arc
					(start 26.628598 -249.761756)
					(mid 26.592677 -249.776635)
					(end 26.577798 -249.812556)
				)
			)
		)
	)
	(zone
		(layers "In1.Cu" "In2.Cu")
		(hatch none 0.5)
		(connect_pads
			(clearance 0)
		)
		(min_thickness 0.25)
		(keepout
			(tracks not_allowed)
			(vias allowed)
			(pads allowed)
			(copperpour not_allowed)
			(footprints allowed)
		)
		(placement
			(enabled no)
			(sheetname "")
		)
		(fill yes
			(thermal_gap 0.5)
			(thermal_bridge_width 0.5)
			(island_removal_mode 0)
		)
		(polygon
			(pts
				(arc
					(start 52.65293 -224.72142)
					(mid 52.667809 -224.757341)
					(end 52.70373 -224.77222)
				)
				(arc
					(start 54.10327 -224.77222)
					(mid 54.139191 -224.757341)
					(end 54.15407 -224.72142)
				)
				(arc
					(start 54.15407 -224.31248)
					(mid 54.139191 -224.276559)
					(end 54.10327 -224.26168)
				)
				(arc
					(start 52.70373 -224.26168)
					(mid 52.667809 -224.276559)
					(end 52.65293 -224.31248)
				)
			)
		)
	)
	(zone
		(layers "In1.Cu" "In2.Cu")
		(hatch none 0.5)
		(connect_pads
			(clearance 0)
		)
		(min_thickness 0.25)
		(keepout
			(tracks not_allowed)
			(vias allowed)
			(pads allowed)
			(copperpour not_allowed)
			(footprints allowed)
		)
		(placement
			(enabled no)
			(sheetname "")
		)
		(fill yes
			(thermal_gap 0.5)
			(thermal_bridge_width 0.5)
			(island_removal_mode 0)
		)
		(polygon
			(pts
				(arc
					(start 184.794398 -245.12143)
					(mid 184.809277 -245.157351)
					(end 184.845198 -245.17223)
				)
				(arc
					(start 186.244738 -245.17223)
					(mid 186.280659 -245.157351)
					(end 186.295538 -245.12143)
				)
				(arc
					(start 186.295538 -244.71249)
					(mid 186.280659 -244.676569)
					(end 186.244738 -244.66169)
				)
				(arc
					(start 184.845198 -244.66169)
					(mid 184.809277 -244.676569)
					(end 184.794398 -244.71249)
				)
			)
		)
	)
	(zone
		(layers "In1.Cu" "In2.Cu")
		(hatch none 0.5)
		(connect_pads
			(clearance 0)
		)
		(min_thickness 0.25)
		(keepout
			(tracks not_allowed)
			(vias allowed)
			(pads allowed)
			(copperpour not_allowed)
			(footprints allowed)
		)
		(placement
			(enabled no)
			(sheetname "")
		)
		(fill yes
			(thermal_gap 0.5)
			(thermal_bridge_width 0.5)
			(island_removal_mode 0)
		)
		(polygon
			(pts
				(arc
					(start 447.822066 -285.92145)
					(mid 447.836945 -285.957371)
					(end 447.872866 -285.97225)
				)
				(arc
					(start 449.272406 -285.97225)
					(mid 449.308327 -285.957371)
					(end 449.323206 -285.92145)
				)
				(arc
					(start 449.323206 -285.51251)
					(mid 449.308327 -285.476589)
					(end 449.272406 -285.46171)
				)
				(arc
					(start 447.872866 -285.46171)
					(mid 447.836945 -285.476589)
					(end 447.822066 -285.51251)
				)
			)
		)
	)
	(zone
		(layers "In1.Cu" "In2.Cu")
		(hatch none 0.5)
		(connect_pads
			(clearance 0)
		)
		(min_thickness 0.25)
		(keepout
			(tracks not_allowed)
			(vias allowed)
			(pads allowed)
			(copperpour not_allowed)
			(footprints allowed)
		)
		(placement
			(enabled no)
			(sheetname "")
		)
		(fill yes
			(thermal_gap 0.5)
			(thermal_bridge_width 0.5)
			(island_removal_mode 0)
		)
		(polygon
			(pts
				(arc
					(start 308.136798 -221.321376)
					(mid 308.151677 -221.357297)
					(end 308.187598 -221.372176)
				)
				(arc
					(start 309.587138 -221.372176)
					(mid 309.623059 -221.357297)
					(end 309.637938 -221.321376)
				)
				(arc
					(start 309.637938 -220.912436)
					(mid 309.623059 -220.876515)
					(end 309.587138 -220.861636)
				)
				(arc
					(start 308.187598 -220.861636)
					(mid 308.151677 -220.876515)
					(end 308.136798 -220.912436)
				)
			)
		)
	)
	(zone
		(layers "In1.Cu" "In2.Cu")
		(hatch none 0.5)
		(connect_pads
			(clearance 0)
		)
		(min_thickness 0.25)
		(keepout
			(tracks not_allowed)
			(vias allowed)
			(pads allowed)
			(copperpour not_allowed)
			(footprints allowed)
		)
		(placement
			(enabled no)
			(sheetname "")
		)
		(fill yes
			(thermal_gap 0.5)
			(thermal_bridge_width 0.5)
			(island_removal_mode 0)
		)
		(polygon
			(pts
				(arc
					(start 440.278266 -209.421476)
					(mid 440.293145 -209.457397)
					(end 440.329066 -209.472276)
				)
				(arc
					(start 441.728606 -209.472276)
					(mid 441.764527 -209.457397)
					(end 441.779406 -209.421476)
				)
				(arc
					(start 441.779406 -209.012536)
					(mid 441.764527 -208.976615)
					(end 441.728606 -208.961736)
				)
				(arc
					(start 440.329066 -208.961736)
					(mid 440.293145 -208.976615)
					(end 440.278266 -209.012536)
				)
			)
		)
	)
	(zone
		(layers "In1.Cu" "In2.Cu")
		(hatch none 0.5)
		(connect_pads
			(clearance 0)
		)
		(min_thickness 0.25)
		(keepout
			(tracks not_allowed)
			(vias allowed)
			(pads allowed)
			(copperpour not_allowed)
			(footprints allowed)
		)
		(placement
			(enabled no)
			(sheetname "")
		)
		(fill yes
			(thermal_gap 0.5)
			(thermal_bridge_width 0.5)
			(island_removal_mode 0)
		)
		(polygon
			(pts
				(arc
					(start 274.517866 -274.02155)
					(mid 274.532745 -274.057471)
					(end 274.568666 -274.07235)
				)
				(arc
					(start 275.968206 -274.07235)
					(mid 276.004127 -274.057471)
					(end 276.019006 -274.02155)
				)
				(arc
					(start 276.019006 -273.61261)
					(mid 276.004127 -273.576689)
					(end 275.968206 -273.56181)
				)
				(arc
					(start 274.568666 -273.56181)
					(mid 274.532745 -273.576689)
					(end 274.517866 -273.61261)
				)
			)
		)
	)
	(zone
		(layers "In1.Cu" "In2.Cu")
		(hatch none 0.5)
		(connect_pads
			(clearance 0)
		)
		(min_thickness 0.25)
		(keepout
			(tracks not_allowed)
			(vias allowed)
			(pads allowed)
			(copperpour not_allowed)
			(footprints allowed)
		)
		(placement
			(enabled no)
			(sheetname "")
		)
		(fill yes
			(thermal_gap 0.5)
			(thermal_bridge_width 0.5)
			(island_removal_mode 0)
		)
		(polygon
			(pts
				(arc
					(start 37.56533 -228.971348)
					(mid 37.580209 -229.007269)
					(end 37.61613 -229.022148)
				)
				(arc
					(start 39.01567 -229.022148)
					(mid 39.051591 -229.007269)
					(end 39.06647 -228.971348)
				)
				(arc
					(start 39.06647 -228.562408)
					(mid 39.051591 -228.526487)
					(end 39.01567 -228.511608)
				)
				(arc
					(start 37.61613 -228.511608)
					(mid 37.580209 -228.526487)
					(end 37.56533 -228.562408)
				)
			)
		)
	)
	(zone
		(layers "In1.Cu" "In2.Cu")
		(hatch none 0.5)
		(connect_pads
			(clearance 0)
		)
		(min_thickness 0.25)
		(keepout
			(tracks not_allowed)
			(vias allowed)
			(pads allowed)
			(copperpour not_allowed)
			(footprints allowed)
		)
		(placement
			(enabled no)
			(sheetname "")
		)
		(fill yes
			(thermal_gap 0.5)
			(thermal_bridge_width 0.5)
			(island_removal_mode 0)
		)
		(polygon
			(pts
				(arc
					(start 304.693066 -279.9715)
					(mid 304.707945 -280.007421)
					(end 304.743866 -280.0223)
				)
				(arc
					(start 306.143406 -280.0223)
					(mid 306.179327 -280.007421)
					(end 306.194206 -279.9715)
				)
				(arc
					(start 306.194206 -279.56256)
					(mid 306.179327 -279.526639)
					(end 306.143406 -279.51176)
				)
				(arc
					(start 304.743866 -279.51176)
					(mid 304.707945 -279.526639)
					(end 304.693066 -279.56256)
				)
			)
		)
	)
	(zone
		(layers "In1.Cu" "In2.Cu")
		(hatch none 0.5)
		(connect_pads
			(clearance 0)
		)
		(min_thickness 0.25)
		(keepout
			(tracks not_allowed)
			(vias allowed)
			(pads allowed)
			(copperpour not_allowed)
			(footprints allowed)
		)
		(placement
			(enabled no)
			(sheetname "")
		)
		(fill yes
			(thermal_gap 0.5)
			(thermal_bridge_width 0.5)
			(island_removal_mode 0)
		)
		(polygon
			(pts
				(arc
					(start 14.93393 -228.121464)
					(mid 14.948809 -228.157385)
					(end 14.98473 -228.172264)
				)
				(arc
					(start 16.38427 -228.172264)
					(mid 16.420191 -228.157385)
					(end 16.43507 -228.121464)
				)
				(arc
					(start 16.43507 -227.712524)
					(mid 16.420191 -227.676603)
					(end 16.38427 -227.661724)
				)
				(arc
					(start 14.98473 -227.661724)
					(mid 14.948809 -227.676603)
					(end 14.93393 -227.712524)
				)
			)
		)
	)
	(zone
		(layers "In1.Cu" "In2.Cu")
		(hatch none 0.5)
		(connect_pads
			(clearance 0)
		)
		(min_thickness 0.25)
		(keepout
			(tracks not_allowed)
			(vias allowed)
			(pads allowed)
			(copperpour not_allowed)
			(footprints allowed)
		)
		(placement
			(enabled no)
			(sheetname "")
		)
		(fill yes
			(thermal_gap 0.5)
			(thermal_bridge_width 0.5)
			(island_removal_mode 0)
		)
		(polygon
			(pts
				(arc
					(start 7.39013 -269.771368)
					(mid 7.405009 -269.807289)
					(end 7.44093 -269.822168)
				)
				(arc
					(start 8.84047 -269.822168)
					(mid 8.876391 -269.807289)
					(end 8.89127 -269.771368)
				)
				(arc
					(start 8.89127 -269.362428)
					(mid 8.876391 -269.326507)
					(end 8.84047 -269.311628)
				)
				(arc
					(start 7.44093 -269.311628)
					(mid 7.405009 -269.326507)
					(end 7.39013 -269.362428)
				)
			)
		)
	)
	(zone
		(layers "In1.Cu" "In2.Cu")
		(hatch none 0.5)
		(connect_pads
			(clearance 0)
		)
		(min_thickness 0.25)
		(keepout
			(tracks not_allowed)
			(vias allowed)
			(pads allowed)
			(copperpour not_allowed)
			(footprints allowed)
		)
		(placement
			(enabled no)
			(sheetname "")
		)
		(fill yes
			(thermal_gap 0.5)
			(thermal_bridge_width 0.5)
			(island_removal_mode 0)
		)
		(polygon
			(pts
				(arc
					(start 64.296798 -312.27141)
					(mid 64.311677 -312.307331)
					(end 64.347598 -312.32221)
				)
				(arc
					(start 65.747138 -312.32221)
					(mid 65.783059 -312.307331)
					(end 65.797938 -312.27141)
				)
				(arc
					(start 65.797938 -311.86247)
					(mid 65.783059 -311.826549)
					(end 65.747138 -311.81167)
				)
				(arc
					(start 64.347598 -311.81167)
					(mid 64.311677 -311.826549)
					(end 64.296798 -311.86247)
				)
			)
		)
	)
	(zone
		(layers "In1.Cu" "In2.Cu")
		(hatch none 0.5)
		(connect_pads
			(clearance 0)
		)
		(min_thickness 0.25)
		(keepout
			(tracks not_allowed)
			(vias allowed)
			(pads allowed)
			(copperpour not_allowed)
			(footprints allowed)
		)
		(placement
			(enabled no)
			(sheetname "")
		)
		(fill yes
			(thermal_gap 0.5)
			(thermal_bridge_width 0.5)
			(island_removal_mode 0)
		)
		(polygon
			(pts
				(arc
					(start 162.162998 -262.121396)
					(mid 162.177877 -262.157317)
					(end 162.213798 -262.172196)
				)
				(arc
					(start 163.613338 -262.172196)
					(mid 163.649259 -262.157317)
					(end 163.664138 -262.121396)
				)
				(arc
					(start 163.664138 -261.712456)
					(mid 163.649259 -261.676535)
					(end 163.613338 -261.661656)
				)
				(arc
					(start 162.213798 -261.661656)
					(mid 162.177877 -261.676535)
					(end 162.162998 -261.712456)
				)
			)
		)
	)
	(zone
		(layers "In1.Cu" "In2.Cu")
		(hatch none 0.5)
		(connect_pads
			(clearance 0)
		)
		(min_thickness 0.25)
		(keepout
			(tracks not_allowed)
			(vias allowed)
			(pads allowed)
			(copperpour not_allowed)
			(footprints allowed)
		)
		(placement
			(enabled no)
			(sheetname "")
		)
		(fill yes
			(thermal_gap 0.5)
			(thermal_bridge_width 0.5)
			(island_removal_mode 0)
		)
		(polygon
			(pts
				(arc
					(start 195.78193 -210.27136)
					(mid 195.796809 -210.307281)
					(end 195.83273 -210.32216)
				)
				(arc
					(start 197.23227 -210.32216)
					(mid 197.268191 -210.307281)
					(end 197.28307 -210.27136)
				)
				(arc
					(start 197.28307 -209.86242)
					(mid 197.268191 -209.826499)
					(end 197.23227 -209.81162)
				)
				(arc
					(start 195.83273 -209.81162)
					(mid 195.796809 -209.826499)
					(end 195.78193 -209.86242)
				)
			)
		)
	)
	(zone
		(layers "In1.Cu" "In2.Cu")
		(hatch none 0.5)
		(connect_pads
			(clearance 0)
		)
		(min_thickness 0.25)
		(keepout
			(tracks not_allowed)
			(vias allowed)
			(pads allowed)
			(copperpour not_allowed)
			(footprints allowed)
		)
		(placement
			(enabled no)
			(sheetname "")
		)
		(fill yes
			(thermal_gap 0.5)
			(thermal_bridge_width 0.5)
			(island_removal_mode 0)
		)
		(polygon
			(pts
				(arc
					(start 262.873998 -307.171344)
					(mid 262.888877 -307.207265)
					(end 262.924798 -307.222144)
				)
				(arc
					(start 264.324338 -307.222144)
					(mid 264.360259 -307.207265)
					(end 264.375138 -307.171344)
				)
				(arc
					(start 264.375138 -306.762404)
					(mid 264.360259 -306.726483)
					(end 264.324338 -306.711604)
				)
				(arc
					(start 262.924798 -306.711604)
					(mid 262.888877 -306.726483)
					(end 262.873998 -306.762404)
				)
			)
		)
	)
	(zone
		(layers "In1.Cu" "In2.Cu")
		(hatch none 0.5)
		(connect_pads
			(clearance 0)
		)
		(min_thickness 0.25)
		(keepout
			(tracks not_allowed)
			(vias allowed)
			(pads allowed)
			(copperpour not_allowed)
			(footprints allowed)
		)
		(placement
			(enabled no)
			(sheetname "")
		)
		(fill yes
			(thermal_gap 0.5)
			(thermal_bridge_width 0.5)
			(island_removal_mode 0)
		)
		(polygon
			(pts
				(arc
					(start 300.592998 -259.57149)
					(mid 300.607877 -259.607411)
					(end 300.643798 -259.62229)
				)
				(arc
					(start 302.043338 -259.62229)
					(mid 302.079259 -259.607411)
					(end 302.094138 -259.57149)
				)
				(arc
					(start 302.094138 -259.16255)
					(mid 302.079259 -259.126629)
					(end 302.043338 -259.11175)
				)
				(arc
					(start 300.643798 -259.11175)
					(mid 300.607877 -259.126629)
					(end 300.592998 -259.16255)
				)
			)
		)
	)
	(zone
		(layers "In1.Cu" "In2.Cu")
		(hatch none 0.5)
		(connect_pads
			(clearance 0)
		)
		(min_thickness 0.25)
		(keepout
			(tracks not_allowed)
			(vias allowed)
			(pads allowed)
			(copperpour not_allowed)
			(footprints allowed)
		)
		(placement
			(enabled no)
			(sheetname "")
		)
		(fill yes
			(thermal_gap 0.5)
			(thermal_bridge_width 0.5)
			(island_removal_mode 0)
		)
		(polygon
			(pts
				(arc
					(start 304.693066 -295.271444)
					(mid 304.707945 -295.307365)
					(end 304.743866 -295.322244)
				)
				(arc
					(start 306.143406 -295.322244)
					(mid 306.179327 -295.307365)
					(end 306.194206 -295.271444)
				)
				(arc
					(start 306.194206 -294.862504)
					(mid 306.179327 -294.826583)
					(end 306.143406 -294.811704)
				)
				(arc
					(start 304.743866 -294.811704)
					(mid 304.707945 -294.826583)
					(end 304.693066 -294.862504)
				)
			)
		)
	)
	(zone
		(layers "In1.Cu" "In2.Cu")
		(hatch none 0.5)
		(connect_pads
			(clearance 0)
		)
		(min_thickness 0.25)
		(keepout
			(tracks not_allowed)
			(vias allowed)
			(pads allowed)
			(copperpour not_allowed)
			(footprints allowed)
		)
		(placement
			(enabled no)
			(sheetname "")
		)
		(fill yes
			(thermal_gap 0.5)
			(thermal_bridge_width 0.5)
			(island_removal_mode 0)
		)
		(polygon
			(pts
				(arc
					(start 177.250598 -212.82152)
					(mid 177.265477 -212.857441)
					(end 177.301398 -212.87232)
				)
				(arc
					(start 178.700938 -212.87232)
					(mid 178.736859 -212.857441)
					(end 178.751738 -212.82152)
				)
				(arc
					(start 178.751738 -212.41258)
					(mid 178.736859 -212.376659)
					(end 178.700938 -212.36178)
				)
				(arc
					(start 177.301398 -212.36178)
					(mid 177.265477 -212.376659)
					(end 177.250598 -212.41258)
				)
			)
		)
	)
	(zone
		(layers "In1.Cu" "In2.Cu")
		(hatch none 0.5)
		(connect_pads
			(clearance 0)
		)
		(min_thickness 0.25)
		(keepout
			(tracks not_allowed)
			(vias allowed)
			(pads allowed)
			(copperpour not_allowed)
			(footprints allowed)
		)
		(placement
			(enabled no)
			(sheetname "")
		)
		(fill yes
			(thermal_gap 0.5)
			(thermal_bridge_width 0.5)
			(island_removal_mode 0)
		)
		(polygon
			(pts
				(arc
					(start 255.330198 -251.07138)
					(mid 255.345077 -251.107301)
					(end 255.380998 -251.12218)
				)
				(arc
					(start 256.780538 -251.12218)
					(mid 256.816459 -251.107301)
					(end 256.831338 -251.07138)
				)
				(arc
					(start 256.831338 -250.66244)
					(mid 256.816459 -250.626519)
					(end 256.780538 -250.61164)
				)
				(arc
					(start 255.380998 -250.61164)
					(mid 255.345077 -250.626519)
					(end 255.330198 -250.66244)
				)
			)
		)
	)
	(zone
		(layers "In1.Cu" "In2.Cu")
		(hatch none 0.5)
		(connect_pads
			(clearance 0)
		)
		(min_thickness 0.25)
		(keepout
			(tracks not_allowed)
			(vias allowed)
			(pads allowed)
			(copperpour not_allowed)
			(footprints allowed)
		)
		(placement
			(enabled no)
			(sheetname "")
		)
		(fill yes
			(thermal_gap 0.5)
			(thermal_bridge_width 0.5)
			(island_removal_mode 0)
		)
		(polygon
			(pts
				(arc
					(start 214.969598 -205.171548)
					(mid 214.984477 -205.207469)
					(end 215.020398 -205.222348)
				)
				(arc
					(start 216.419938 -205.222348)
					(mid 216.455859 -205.207469)
					(end 216.470738 -205.171548)
				)
				(arc
					(start 216.470738 -204.762608)
					(mid 216.455859 -204.726687)
					(end 216.419938 -204.711808)
				)
				(arc
					(start 215.020398 -204.711808)
					(mid 214.984477 -204.726687)
					(end 214.969598 -204.762608)
				)
			)
		)
	)
	(zone
		(layers "In1.Cu" "In2.Cu")
		(hatch none 0.5)
		(connect_pads
			(clearance 0)
		)
		(min_thickness 0.25)
		(keepout
			(tracks not_allowed)
			(vias allowed)
			(pads allowed)
			(copperpour not_allowed)
			(footprints allowed)
		)
		(placement
			(enabled no)
			(sheetname "")
		)
		(fill yes
			(thermal_gap 0.5)
			(thermal_bridge_width 0.5)
			(island_removal_mode 0)
		)
		(polygon
			(pts
				(arc
					(start 266.974066 -268.921484)
					(mid 266.988945 -268.957405)
					(end 267.024866 -268.972284)
				)
				(arc
					(start 268.424406 -268.972284)
					(mid 268.460327 -268.957405)
					(end 268.475206 -268.921484)
				)
				(arc
					(start 268.475206 -268.512544)
					(mid 268.460327 -268.476623)
					(end 268.424406 -268.461744)
				)
				(arc
					(start 267.024866 -268.461744)
					(mid 266.988945 -268.476623)
					(end 266.974066 -268.512544)
				)
			)
		)
	)
	(zone
		(layers "In1.Cu" "In2.Cu")
		(hatch none 0.5)
		(connect_pads
			(clearance 0)
		)
		(min_thickness 0.25)
		(keepout
			(tracks not_allowed)
			(vias allowed)
			(pads allowed)
			(copperpour not_allowed)
			(footprints allowed)
		)
		(placement
			(enabled no)
			(sheetname "")
		)
		(fill yes
			(thermal_gap 0.5)
			(thermal_bridge_width 0.5)
			(island_removal_mode 0)
		)
		(polygon
			(pts
				(arc
					(start 421.090598 -314.821316)
					(mid 421.105477 -314.857237)
					(end 421.141398 -314.872116)
				)
				(arc
					(start 422.540938 -314.872116)
					(mid 422.576859 -314.857237)
					(end 422.591738 -314.821316)
				)
				(arc
					(start 422.591738 -314.412376)
					(mid 422.576859 -314.376455)
					(end 422.540938 -314.361576)
				)
				(arc
					(start 421.141398 -314.361576)
					(mid 421.105477 -314.376455)
					(end 421.090598 -314.412376)
				)
			)
		)
	)
	(zone
		(layers "In1.Cu" "In2.Cu")
		(hatch none 0.5)
		(connect_pads
			(clearance 0)
		)
		(min_thickness 0.25)
		(keepout
			(tracks not_allowed)
			(vias allowed)
			(pads allowed)
			(copperpour not_allowed)
			(footprints allowed)
		)
		(placement
			(enabled no)
			(sheetname "")
		)
		(fill yes
			(thermal_gap 0.5)
			(thermal_bridge_width 0.5)
			(island_removal_mode 0)
		)
		(polygon
			(pts
				(arc
					(start 255.330198 -247.671336)
					(mid 255.345077 -247.707257)
					(end 255.380998 -247.722136)
				)
				(arc
					(start 256.780538 -247.722136)
					(mid 256.816459 -247.707257)
					(end 256.831338 -247.671336)
				)
				(arc
					(start 256.831338 -247.262396)
					(mid 256.816459 -247.226475)
					(end 256.780538 -247.211596)
				)
				(arc
					(start 255.380998 -247.211596)
					(mid 255.345077 -247.226475)
					(end 255.330198 -247.262396)
				)
			)
		)
	)
	(zone
		(layers "In1.Cu" "In2.Cu")
		(hatch none 0.5)
		(connect_pads
			(clearance 0)
		)
		(min_thickness 0.25)
		(keepout
			(tracks not_allowed)
			(vias allowed)
			(pads allowed)
			(copperpour not_allowed)
			(footprints allowed)
		)
		(placement
			(enabled no)
			(sheetname "")
		)
		(fill yes
			(thermal_gap 0.5)
			(thermal_bridge_width 0.5)
			(island_removal_mode 0)
		)
		(polygon
			(pts
				(arc
					(start 158.06293 -297.82135)
					(mid 158.077809 -297.857271)
					(end 158.11373 -297.87215)
				)
				(arc
					(start 159.51327 -297.87215)
					(mid 159.549191 -297.857271)
					(end 159.56407 -297.82135)
				)
				(arc
					(start 159.56407 -297.41241)
					(mid 159.549191 -297.376489)
					(end 159.51327 -297.36161)
				)
				(arc
					(start 158.11373 -297.36161)
					(mid 158.077809 -297.376489)
					(end 158.06293 -297.41241)
				)
			)
		)
	)
	(zone
		(layers "In1.Cu" "In2.Cu")
		(hatch none 0.5)
		(connect_pads
			(clearance 0)
		)
		(min_thickness 0.25)
		(keepout
			(tracks not_allowed)
			(vias allowed)
			(pads allowed)
			(copperpour not_allowed)
			(footprints allowed)
		)
		(placement
			(enabled no)
			(sheetname "")
		)
		(fill yes
			(thermal_gap 0.5)
			(thermal_bridge_width 0.5)
			(island_removal_mode 0)
		)
		(polygon
			(pts
				(arc
					(start 45.10913 -241.721386)
					(mid 45.124009 -241.757307)
					(end 45.15993 -241.772186)
				)
				(arc
					(start 46.55947 -241.772186)
					(mid 46.595391 -241.757307)
					(end 46.61027 -241.721386)
				)
				(arc
					(start 46.61027 -241.312446)
					(mid 46.595391 -241.276525)
					(end 46.55947 -241.261646)
				)
				(arc
					(start 45.15993 -241.261646)
					(mid 45.124009 -241.276525)
					(end 45.10913 -241.312446)
				)
			)
		)
	)
	(zone
		(layers "In1.Cu" "In2.Cu")
		(hatch none 0.5)
		(connect_pads
			(clearance 0)
		)
		(min_thickness 0.25)
		(keepout
			(tracks not_allowed)
			(vias allowed)
			(pads allowed)
			(copperpour not_allowed)
			(footprints allowed)
		)
		(placement
			(enabled no)
			(sheetname "")
		)
		(fill yes
			(thermal_gap 0.5)
			(thermal_bridge_width 0.5)
			(island_removal_mode 0)
		)
		(polygon
			(pts
				(arc
					(start 56.752998 -315.671454)
					(mid 56.767877 -315.707375)
					(end 56.803798 -315.722254)
				)
				(arc
					(start 58.203338 -315.722254)
					(mid 58.239259 -315.707375)
					(end 58.254138 -315.671454)
				)
				(arc
					(start 58.254138 -315.262514)
					(mid 58.239259 -315.226593)
					(end 58.203338 -315.211714)
				)
				(arc
					(start 56.803798 -315.211714)
					(mid 56.767877 -315.226593)
					(end 56.752998 -315.262514)
				)
			)
		)
	)
	(zone
		(layers "In1.Cu" "In2.Cu")
		(hatch none 0.5)
		(connect_pads
			(clearance 0)
		)
		(min_thickness 0.25)
		(keepout
			(tracks not_allowed)
			(vias allowed)
			(pads allowed)
			(copperpour not_allowed)
			(footprints allowed)
		)
		(placement
			(enabled no)
			(sheetname "")
		)
		(fill yes
			(thermal_gap 0.5)
			(thermal_bridge_width 0.5)
			(island_removal_mode 0)
		)
		(polygon
			(pts
				(arc
					(start 432.734466 -304.621438)
					(mid 432.749345 -304.657359)
					(end 432.785266 -304.672238)
				)
				(arc
					(start 434.184806 -304.672238)
					(mid 434.220727 -304.657359)
					(end 434.235606 -304.621438)
				)
				(arc
					(start 434.235606 -304.212498)
					(mid 434.220727 -304.176577)
					(end 434.184806 -304.161698)
				)
				(arc
					(start 432.785266 -304.161698)
					(mid 432.749345 -304.176577)
					(end 432.734466 -304.212498)
				)
			)
		)
	)
	(zone
		(layers "In1.Cu" "In2.Cu")
		(hatch none 0.5)
		(connect_pads
			(clearance 0)
		)
		(min_thickness 0.25)
		(keepout
			(tracks not_allowed)
			(vias allowed)
			(pads allowed)
			(copperpour not_allowed)
			(footprints allowed)
		)
		(placement
			(enabled no)
			(sheetname "")
		)
		(fill yes
			(thermal_gap 0.5)
			(thermal_bridge_width 0.5)
			(island_removal_mode 0)
		)
		(polygon
			(pts
				(arc
					(start 45.10913 -252.771402)
					(mid 45.124009 -252.807323)
					(end 45.15993 -252.822202)
				)
				(arc
					(start 46.55947 -252.822202)
					(mid 46.595391 -252.807323)
					(end 46.61027 -252.771402)
				)
				(arc
					(start 46.61027 -252.362462)
					(mid 46.595391 -252.326541)
					(end 46.55947 -252.311662)
				)
				(arc
					(start 45.15993 -252.311662)
					(mid 45.124009 -252.326541)
					(end 45.10913 -252.362462)
				)
			)
		)
	)
	(zone
		(layers "In1.Cu" "In2.Cu")
		(hatch none 0.5)
		(connect_pads
			(clearance 0)
		)
		(min_thickness 0.25)
		(keepout
			(tracks not_allowed)
			(vias allowed)
			(pads allowed)
			(copperpour not_allowed)
			(footprints allowed)
		)
		(placement
			(enabled no)
			(sheetname "")
		)
		(fill yes
			(thermal_gap 0.5)
			(thermal_bridge_width 0.5)
			(island_removal_mode 0)
		)
		(polygon
			(pts
				(arc
					(start 214.969598 -201.771504)
					(mid 214.984477 -201.807425)
					(end 215.020398 -201.822304)
				)
				(arc
					(start 216.419938 -201.822304)
					(mid 216.455859 -201.807425)
					(end 216.470738 -201.771504)
				)
				(arc
					(start 216.470738 -201.362564)
					(mid 216.455859 -201.326643)
					(end 216.419938 -201.311764)
				)
				(arc
					(start 215.020398 -201.311764)
					(mid 214.984477 -201.326643)
					(end 214.969598 -201.362564)
				)
			)
		)
	)
	(zone
		(layers "In1.Cu" "In2.Cu")
		(hatch none 0.5)
		(connect_pads
			(clearance 0)
		)
		(min_thickness 0.25)
		(keepout
			(tracks not_allowed)
			(vias allowed)
			(pads allowed)
			(copperpour not_allowed)
			(footprints allowed)
		)
		(placement
			(enabled no)
			(sheetname "")
		)
		(fill yes
			(thermal_gap 0.5)
			(thermal_bridge_width 0.5)
			(island_removal_mode 0)
		)
		(polygon
			(pts
				(arc
					(start 34.121598 -220.471492)
					(mid 34.136477 -220.507413)
					(end 34.172398 -220.522292)
				)
				(arc
					(start 35.571938 -220.522292)
					(mid 35.607859 -220.507413)
					(end 35.622738 -220.471492)
				)
				(arc
					(start 35.622738 -220.062552)
					(mid 35.607859 -220.026631)
					(end 35.571938 -220.011752)
				)
				(arc
					(start 34.172398 -220.011752)
					(mid 34.136477 -220.026631)
					(end 34.121598 -220.062552)
				)
			)
		)
	)
	(zone
		(layers "In1.Cu" "In2.Cu")
		(hatch none 0.5)
		(connect_pads
			(clearance 0)
		)
		(min_thickness 0.25)
		(keepout
			(tracks not_allowed)
			(vias allowed)
			(pads allowed)
			(copperpour not_allowed)
			(footprints allowed)
		)
		(placement
			(enabled no)
			(sheetname "")
		)
		(fill yes
			(thermal_gap 0.5)
			(thermal_bridge_width 0.5)
			(island_removal_mode 0)
		)
		(polygon
			(pts
				(arc
					(start 214.969598 -289.321494)
					(mid 214.984477 -289.357415)
					(end 215.020398 -289.372294)
				)
				(arc
					(start 216.419938 -289.372294)
					(mid 216.455859 -289.357415)
					(end 216.470738 -289.321494)
				)
				(arc
					(start 216.470738 -288.912554)
					(mid 216.455859 -288.876633)
					(end 216.419938 -288.861754)
				)
				(arc
					(start 215.020398 -288.861754)
					(mid 214.984477 -288.876633)
					(end 214.969598 -288.912554)
				)
			)
		)
	)
	(zone
		(layers "In1.Cu" "In2.Cu")
		(hatch none 0.5)
		(connect_pads
			(clearance 0)
		)
		(min_thickness 0.25)
		(keepout
			(tracks not_allowed)
			(vias allowed)
			(pads allowed)
			(copperpour not_allowed)
			(footprints allowed)
		)
		(placement
			(enabled no)
			(sheetname "")
		)
		(fill yes
			(thermal_gap 0.5)
			(thermal_bridge_width 0.5)
			(island_removal_mode 0)
		)
		(polygon
			(pts
				(arc
					(start 210.86953 -273.171412)
					(mid 210.884409 -273.207333)
					(end 210.92033 -273.222212)
				)
				(arc
					(start 212.31987 -273.222212)
					(mid 212.355791 -273.207333)
					(end 212.37067 -273.171412)
				)
				(arc
					(start 212.37067 -272.762472)
					(mid 212.355791 -272.726551)
					(end 212.31987 -272.711672)
				)
				(arc
					(start 210.92033 -272.711672)
					(mid 210.884409 -272.726551)
					(end 210.86953 -272.762472)
				)
			)
		)
	)
	(zone
		(layers "In1.Cu" "In2.Cu")
		(hatch none 0.5)
		(connect_pads
			(clearance 0)
		)
		(min_thickness 0.25)
		(keepout
			(tracks not_allowed)
			(vias allowed)
			(pads allowed)
			(copperpour not_allowed)
			(footprints allowed)
		)
		(placement
			(enabled no)
			(sheetname "")
		)
		(fill yes
			(thermal_gap 0.5)
			(thermal_bridge_width 0.5)
			(island_removal_mode 0)
		)
		(polygon
			(pts
				(arc
					(start 410.103066 -272.321528)
					(mid 410.117945 -272.357449)
					(end 410.153866 -272.372328)
				)
				(arc
					(start 411.553406 -272.372328)
					(mid 411.589327 -272.357449)
					(end 411.604206 -272.321528)
				)
				(arc
					(start 411.604206 -271.912588)
					(mid 411.589327 -271.876667)
					(end 411.553406 -271.861788)
				)
				(arc
					(start 410.153866 -271.861788)
					(mid 410.117945 -271.876667)
					(end 410.103066 -271.912588)
				)
			)
		)
	)
	(zone
		(layers "In1.Cu" "In2.Cu")
		(hatch none 0.5)
		(connect_pads
			(clearance 0)
		)
		(min_thickness 0.25)
		(keepout
			(tracks not_allowed)
			(vias allowed)
			(pads allowed)
			(copperpour not_allowed)
			(footprints allowed)
		)
		(placement
			(enabled no)
			(sheetname "")
		)
		(fill yes
			(thermal_gap 0.5)
			(thermal_bridge_width 0.5)
			(island_removal_mode 0)
		)
		(polygon
			(pts
				(arc
					(start 188.23813 -234.071414)
					(mid 188.253009 -234.107335)
					(end 188.28893 -234.122214)
				)
				(arc
					(start 189.68847 -234.122214)
					(mid 189.724391 -234.107335)
					(end 189.73927 -234.071414)
				)
				(arc
					(start 189.73927 -233.662474)
					(mid 189.724391 -233.626553)
					(end 189.68847 -233.611674)
				)
				(arc
					(start 188.28893 -233.611674)
					(mid 188.253009 -233.626553)
					(end 188.23813 -233.662474)
				)
			)
		)
	)
	(zone
		(layers "In1.Cu" "In2.Cu")
		(hatch none 0.5)
		(connect_pads
			(clearance 0)
		)
		(min_thickness 0.25)
		(keepout
			(tracks not_allowed)
			(vias allowed)
			(pads allowed)
			(copperpour not_allowed)
			(footprints allowed)
		)
		(placement
			(enabled no)
			(sheetname "")
		)
		(fill yes
			(thermal_gap 0.5)
			(thermal_bridge_width 0.5)
			(island_removal_mode 0)
		)
		(polygon
			(pts
				(arc
					(start 293.049198 -251.07138)
					(mid 293.064077 -251.107301)
					(end 293.099998 -251.12218)
				)
				(arc
					(start 294.499538 -251.12218)
					(mid 294.535459 -251.107301)
					(end 294.550338 -251.07138)
				)
				(arc
					(start 294.550338 -250.66244)
					(mid 294.535459 -250.626519)
					(end 294.499538 -250.61164)
				)
				(arc
					(start 293.099998 -250.61164)
					(mid 293.064077 -250.626519)
					(end 293.049198 -250.66244)
				)
			)
		)
	)
	(zone
		(layers "In1.Cu" "In2.Cu")
		(hatch none 0.5)
		(connect_pads
			(clearance 0)
		)
		(min_thickness 0.25)
		(keepout
			(tracks not_allowed)
			(vias allowed)
			(pads allowed)
			(copperpour not_allowed)
			(footprints allowed)
		)
		(placement
			(enabled no)
			(sheetname "")
		)
		(fill yes
			(thermal_gap 0.5)
			(thermal_bridge_width 0.5)
			(island_removal_mode 0)
		)
		(polygon
			(pts
				(arc
					(start 277.961598 -266.371324)
					(mid 277.976477 -266.407245)
					(end 278.012398 -266.422124)
				)
				(arc
					(start 279.411938 -266.422124)
					(mid 279.447859 -266.407245)
					(end 279.462738 -266.371324)
				)
				(arc
					(start 279.462738 -265.962384)
					(mid 279.447859 -265.926463)
					(end 279.411938 -265.911584)
				)
				(arc
					(start 278.012398 -265.911584)
					(mid 277.976477 -265.926463)
					(end 277.961598 -265.962384)
				)
			)
		)
	)
	(zone
		(layers "In1.Cu" "In2.Cu")
		(hatch none 0.5)
		(connect_pads
			(clearance 0)
		)
		(min_thickness 0.25)
		(keepout
			(tracks not_allowed)
			(vias allowed)
			(pads allowed)
			(copperpour not_allowed)
			(footprints allowed)
		)
		(placement
			(enabled no)
			(sheetname "")
		)
		(fill yes
			(thermal_gap 0.5)
			(thermal_bridge_width 0.5)
			(island_removal_mode 0)
		)
		(polygon
			(pts
				(arc
					(start 52.65293 -228.971348)
					(mid 52.667809 -229.007269)
					(end 52.70373 -229.022148)
				)
				(arc
					(start 54.10327 -229.022148)
					(mid 54.139191 -229.007269)
					(end 54.15407 -228.971348)
				)
				(arc
					(start 54.15407 -228.562408)
					(mid 54.139191 -228.526487)
					(end 54.10327 -228.511608)
				)
				(arc
					(start 52.70373 -228.511608)
					(mid 52.667809 -228.526487)
					(end 52.65293 -228.562408)
				)
			)
		)
	)
	(zone
		(layers "In1.Cu" "In2.Cu")
		(hatch none 0.5)
		(connect_pads
			(clearance 0)
		)
		(min_thickness 0.25)
		(keepout
			(tracks not_allowed)
			(vias allowed)
			(pads allowed)
			(copperpour not_allowed)
			(footprints allowed)
		)
		(placement
			(enabled no)
			(sheetname "")
		)
		(fill yes
			(thermal_gap 0.5)
			(thermal_bridge_width 0.5)
			(island_removal_mode 0)
		)
		(polygon
			(pts
				(arc
					(start 207.425798 -225.571304)
					(mid 207.440677 -225.607225)
					(end 207.476598 -225.622104)
				)
				(arc
					(start 208.876138 -225.622104)
					(mid 208.912059 -225.607225)
					(end 208.926938 -225.571304)
				)
				(arc
					(start 208.926938 -225.162364)
					(mid 208.912059 -225.126443)
					(end 208.876138 -225.111564)
				)
				(arc
					(start 207.476598 -225.111564)
					(mid 207.440677 -225.126443)
					(end 207.425798 -225.162364)
				)
			)
		)
	)
	(zone
		(layers "In1.Cu" "In2.Cu")
		(hatch none 0.5)
		(connect_pads
			(clearance 0)
		)
		(min_thickness 0.25)
		(keepout
			(tracks not_allowed)
			(vias allowed)
			(pads allowed)
			(copperpour not_allowed)
			(footprints allowed)
		)
		(placement
			(enabled no)
			(sheetname "")
		)
		(fill yes
			(thermal_gap 0.5)
			(thermal_bridge_width 0.5)
			(island_removal_mode 0)
		)
		(polygon
			(pts
				(arc
					(start 158.06293 -305.471322)
					(mid 158.077809 -305.507243)
					(end 158.11373 -305.522122)
				)
				(arc
					(start 159.51327 -305.522122)
					(mid 159.549191 -305.507243)
					(end 159.56407 -305.471322)
				)
				(arc
					(start 159.56407 -305.062382)
					(mid 159.549191 -305.026461)
					(end 159.51327 -305.011582)
				)
				(arc
					(start 158.11373 -305.011582)
					(mid 158.077809 -305.026461)
					(end 158.06293 -305.062382)
				)
			)
		)
	)
	(zone
		(layers "In1.Cu" "In2.Cu")
		(hatch none 0.5)
		(connect_pads
			(clearance 0)
		)
		(min_thickness 0.25)
		(keepout
			(tracks not_allowed)
			(vias allowed)
			(pads allowed)
			(copperpour not_allowed)
			(footprints allowed)
		)
		(placement
			(enabled no)
			(sheetname "")
		)
		(fill yes
			(thermal_gap 0.5)
			(thermal_bridge_width 0.5)
			(island_removal_mode 0)
		)
		(polygon
			(pts
				(arc
					(start 259.430266 -246.821452)
					(mid 259.445145 -246.857373)
					(end 259.481066 -246.872252)
				)
				(arc
					(start 260.880606 -246.872252)
					(mid 260.916527 -246.857373)
					(end 260.931406 -246.821452)
				)
				(arc
					(start 260.931406 -246.412512)
					(mid 260.916527 -246.376591)
					(end 260.880606 -246.361712)
				)
				(arc
					(start 259.481066 -246.361712)
					(mid 259.445145 -246.376591)
					(end 259.430266 -246.412512)
				)
			)
		)
	)
	(zone
		(layers "In1.Cu" "In2.Cu")
		(hatch none 0.5)
		(connect_pads
			(clearance 0)
		)
		(min_thickness 0.25)
		(keepout
			(tracks not_allowed)
			(vias allowed)
			(pads allowed)
			(copperpour not_allowed)
			(footprints allowed)
		)
		(placement
			(enabled no)
			(sheetname "")
		)
		(fill yes
			(thermal_gap 0.5)
			(thermal_bridge_width 0.5)
			(island_removal_mode 0)
		)
		(polygon
			(pts
				(arc
					(start 180.69433 -198.37146)
					(mid 180.709209 -198.407381)
					(end 180.74513 -198.42226)
				)
				(arc
					(start 182.14467 -198.42226)
					(mid 182.180591 -198.407381)
					(end 182.19547 -198.37146)
				)
				(arc
					(start 182.19547 -197.96252)
					(mid 182.180591 -197.926599)
					(end 182.14467 -197.91172)
				)
				(arc
					(start 180.74513 -197.91172)
					(mid 180.709209 -197.926599)
					(end 180.69433 -197.96252)
				)
			)
		)
	)
	(zone
		(layers "In1.Cu" "In2.Cu")
		(hatch none 0.5)
		(connect_pads
			(clearance 0)
		)
		(min_thickness 0.25)
		(keepout
			(tracks not_allowed)
			(vias allowed)
			(pads allowed)
			(copperpour not_allowed)
			(footprints allowed)
		)
		(placement
			(enabled no)
			(sheetname "")
		)
		(fill yes
			(thermal_gap 0.5)
			(thermal_bridge_width 0.5)
			(island_removal_mode 0)
		)
		(polygon
			(pts
				(arc
					(start 458.809598 -293.571422)
					(mid 458.824477 -293.607343)
					(end 458.860398 -293.622222)
				)
				(arc
					(start 460.259938 -293.622222)
					(mid 460.295859 -293.607343)
					(end 460.310738 -293.571422)
				)
				(arc
					(start 460.310738 -293.162482)
					(mid 460.295859 -293.126561)
					(end 460.259938 -293.111682)
				)
				(arc
					(start 458.860398 -293.111682)
					(mid 458.824477 -293.126561)
					(end 458.809598 -293.162482)
				)
			)
		)
	)
	(zone
		(layers "In1.Cu" "In2.Cu")
		(hatch none 0.5)
		(connect_pads
			(clearance 0)
		)
		(min_thickness 0.25)
		(keepout
			(tracks not_allowed)
			(vias allowed)
			(pads allowed)
			(copperpour not_allowed)
			(footprints allowed)
		)
		(placement
			(enabled no)
			(sheetname "")
		)
		(fill yes
			(thermal_gap 0.5)
			(thermal_bridge_width 0.5)
			(island_removal_mode 0)
		)
		(polygon
			(pts
				(arc
					(start 277.961598 -249.371358)
					(mid 277.976477 -249.407279)
					(end 278.012398 -249.422158)
				)
				(arc
					(start 279.411938 -249.422158)
					(mid 279.447859 -249.407279)
					(end 279.462738 -249.371358)
				)
				(arc
					(start 279.462738 -248.962418)
					(mid 279.447859 -248.926497)
					(end 279.411938 -248.911618)
				)
				(arc
					(start 278.012398 -248.911618)
					(mid 277.976477 -248.926497)
					(end 277.961598 -248.962418)
				)
			)
		)
	)
	(zone
		(layers "In1.Cu" "In2.Cu")
		(hatch none 0.5)
		(connect_pads
			(clearance 0)
		)
		(min_thickness 0.25)
		(keepout
			(tracks not_allowed)
			(vias allowed)
			(pads allowed)
			(copperpour not_allowed)
			(footprints allowed)
		)
		(placement
			(enabled no)
			(sheetname "")
		)
		(fill yes
			(thermal_gap 0.5)
			(thermal_bridge_width 0.5)
			(island_removal_mode 0)
		)
		(polygon
			(pts
				(arc
					(start 41.665398 -289.321494)
					(mid 41.680277 -289.357415)
					(end 41.716198 -289.372294)
				)
				(arc
					(start 43.115738 -289.372294)
					(mid 43.151659 -289.357415)
					(end 43.166538 -289.321494)
				)
				(arc
					(start 43.166538 -288.912554)
					(mid 43.151659 -288.876633)
					(end 43.115738 -288.861754)
				)
				(arc
					(start 41.716198 -288.861754)
					(mid 41.680277 -288.876633)
					(end 41.665398 -288.912554)
				)
			)
		)
	)
	(zone
		(layers "In1.Cu" "In2.Cu")
		(hatch none 0.5)
		(connect_pads
			(clearance 0)
		)
		(min_thickness 0.25)
		(keepout
			(tracks not_allowed)
			(vias allowed)
			(pads allowed)
			(copperpour not_allowed)
			(footprints allowed)
		)
		(placement
			(enabled no)
			(sheetname "")
		)
		(fill yes
			(thermal_gap 0.5)
			(thermal_bridge_width 0.5)
			(island_removal_mode 0)
		)
		(polygon
			(pts
				(arc
					(start 210.86953 -291.8714)
					(mid 210.884409 -291.907321)
					(end 210.92033 -291.9222)
				)
				(arc
					(start 212.31987 -291.9222)
					(mid 212.355791 -291.907321)
					(end 212.37067 -291.8714)
				)
				(arc
					(start 212.37067 -291.46246)
					(mid 212.355791 -291.426539)
					(end 212.31987 -291.41166)
				)
				(arc
					(start 210.92033 -291.41166)
					(mid 210.884409 -291.426539)
					(end 210.86953 -291.46246)
				)
			)
		)
	)
	(zone
		(layers "In1.Cu" "In2.Cu")
		(hatch none 0.5)
		(connect_pads
			(clearance 0)
		)
		(min_thickness 0.25)
		(keepout
			(tracks not_allowed)
			(vias allowed)
			(pads allowed)
			(copperpour not_allowed)
			(footprints allowed)
		)
		(placement
			(enabled no)
			(sheetname "")
		)
		(fill yes
			(thermal_gap 0.5)
			(thermal_bridge_width 0.5)
			(island_removal_mode 0)
		)
		(polygon
			(pts
				(arc
					(start 293.049198 -200.921366)
					(mid 293.064077 -200.957287)
					(end 293.099998 -200.972166)
				)
				(arc
					(start 294.499538 -200.972166)
					(mid 294.535459 -200.957287)
					(end 294.550338 -200.921366)
				)
				(arc
					(start 294.550338 -200.512426)
					(mid 294.535459 -200.476505)
					(end 294.499538 -200.461626)
				)
				(arc
					(start 293.099998 -200.461626)
					(mid 293.064077 -200.476505)
					(end 293.049198 -200.512426)
				)
			)
		)
	)
	(zone
		(layers "In1.Cu" "In2.Cu")
		(hatch none 0.5)
		(connect_pads
			(clearance 0)
		)
		(min_thickness 0.25)
		(keepout
			(tracks not_allowed)
			(vias allowed)
			(pads allowed)
			(copperpour not_allowed)
			(footprints allowed)
		)
		(placement
			(enabled no)
			(sheetname "")
		)
		(fill yes
			(thermal_gap 0.5)
			(thermal_bridge_width 0.5)
			(island_removal_mode 0)
		)
		(polygon
			(pts
				(arc
					(start 432.734466 -236.62132)
					(mid 432.749345 -236.657241)
					(end 432.785266 -236.67212)
				)
				(arc
					(start 434.184806 -236.67212)
					(mid 434.220727 -236.657241)
					(end 434.235606 -236.62132)
				)
				(arc
					(start 434.235606 -236.21238)
					(mid 434.220727 -236.176459)
					(end 434.184806 -236.16158)
				)
				(arc
					(start 432.785266 -236.16158)
					(mid 432.749345 -236.176459)
					(end 432.734466 -236.21238)
				)
			)
		)
	)
	(zone
		(layers "In1.Cu" "In2.Cu")
		(hatch none 0.5)
		(connect_pads
			(clearance 0)
		)
		(min_thickness 0.25)
		(keepout
			(tracks not_allowed)
			(vias allowed)
			(pads allowed)
			(copperpour not_allowed)
			(footprints allowed)
		)
		(placement
			(enabled no)
			(sheetname "")
		)
		(fill yes
			(thermal_gap 0.5)
			(thermal_bridge_width 0.5)
			(island_removal_mode 0)
		)
		(polygon
			(pts
				(arc
					(start 199.881998 -218.77147)
					(mid 199.896877 -218.807391)
					(end 199.932798 -218.82227)
				)
				(arc
					(start 201.332338 -218.82227)
					(mid 201.368259 -218.807391)
					(end 201.383138 -218.77147)
				)
				(arc
					(start 201.383138 -218.36253)
					(mid 201.368259 -218.326609)
					(end 201.332338 -218.31173)
				)
				(arc
					(start 199.932798 -218.31173)
					(mid 199.896877 -218.326609)
					(end 199.881998 -218.36253)
				)
			)
		)
	)
	(zone
		(layers "In1.Cu" "In2.Cu")
		(hatch none 0.5)
		(connect_pads
			(clearance 0)
		)
		(min_thickness 0.25)
		(keepout
			(tracks not_allowed)
			(vias allowed)
			(pads allowed)
			(copperpour not_allowed)
			(footprints allowed)
		)
		(placement
			(enabled no)
			(sheetname "")
		)
		(fill yes
			(thermal_gap 0.5)
			(thermal_bridge_width 0.5)
			(island_removal_mode 0)
		)
		(polygon
			(pts
				(arc
					(start 432.734466 -248.521474)
					(mid 432.749345 -248.557395)
					(end 432.785266 -248.572274)
				)
				(arc
					(start 434.184806 -248.572274)
					(mid 434.220727 -248.557395)
					(end 434.235606 -248.521474)
				)
				(arc
					(start 434.235606 -248.112534)
					(mid 434.220727 -248.076613)
					(end 434.184806 -248.061734)
				)
				(arc
					(start 432.785266 -248.061734)
					(mid 432.749345 -248.076613)
					(end 432.734466 -248.112534)
				)
			)
		)
	)
	(zone
		(layers "In1.Cu" "In2.Cu")
		(hatch none 0.5)
		(connect_pads
			(clearance 0)
		)
		(min_thickness 0.25)
		(keepout
			(tracks not_allowed)
			(vias allowed)
			(pads allowed)
			(copperpour not_allowed)
			(footprints allowed)
		)
		(placement
			(enabled no)
			(sheetname "")
		)
		(fill yes
			(thermal_gap 0.5)
			(thermal_bridge_width 0.5)
			(island_removal_mode 0)
		)
		(polygon
			(pts
				(arc
					(start 300.592998 -251.07138)
					(mid 300.607877 -251.107301)
					(end 300.643798 -251.12218)
				)
				(arc
					(start 302.043338 -251.12218)
					(mid 302.079259 -251.107301)
					(end 302.094138 -251.07138)
				)
				(arc
					(start 302.094138 -250.66244)
					(mid 302.079259 -250.626519)
					(end 302.043338 -250.61164)
				)
				(arc
					(start 300.643798 -250.61164)
					(mid 300.607877 -250.626519)
					(end 300.592998 -250.66244)
				)
			)
		)
	)
	(zone
		(layers "In1.Cu" "In2.Cu")
		(hatch none 0.5)
		(connect_pads
			(clearance 0)
		)
		(min_thickness 0.25)
		(keepout
			(tracks not_allowed)
			(vias allowed)
			(pads allowed)
			(copperpour not_allowed)
			(footprints allowed)
		)
		(placement
			(enabled no)
			(sheetname "")
		)
		(fill yes
			(thermal_gap 0.5)
			(thermal_bridge_width 0.5)
			(island_removal_mode 0)
		)
		(polygon
			(pts
				(arc
					(start 285.505398 -224.72142)
					(mid 285.520277 -224.757341)
					(end 285.556198 -224.77222)
				)
				(arc
					(start 286.955738 -224.77222)
					(mid 286.991659 -224.757341)
					(end 287.006538 -224.72142)
				)
				(arc
					(start 287.006538 -224.31248)
					(mid 286.991659 -224.276559)
					(end 286.955738 -224.26168)
				)
				(arc
					(start 285.556198 -224.26168)
					(mid 285.520277 -224.276559)
					(end 285.505398 -224.31248)
				)
			)
		)
	)
	(zone
		(layers "In1.Cu" "In2.Cu")
		(hatch none 0.5)
		(connect_pads
			(clearance 0)
		)
		(min_thickness 0.25)
		(keepout
			(tracks not_allowed)
			(vias allowed)
			(pads allowed)
			(copperpour not_allowed)
			(footprints allowed)
		)
		(placement
			(enabled no)
			(sheetname "")
		)
		(fill yes
			(thermal_gap 0.5)
			(thermal_bridge_width 0.5)
			(island_removal_mode 0)
		)
		(polygon
			(pts
				(arc
					(start 214.969598 -279.9715)
					(mid 214.984477 -280.007421)
					(end 215.020398 -280.0223)
				)
				(arc
					(start 216.419938 -280.0223)
					(mid 216.455859 -280.007421)
					(end 216.470738 -279.9715)
				)
				(arc
					(start 216.470738 -279.56256)
					(mid 216.455859 -279.526639)
					(end 216.419938 -279.51176)
				)
				(arc
					(start 215.020398 -279.51176)
					(mid 214.984477 -279.526639)
					(end 214.969598 -279.56256)
				)
			)
		)
	)
	(zone
		(layers "In1.Cu" "In2.Cu")
		(hatch none 0.5)
		(connect_pads
			(clearance 0)
		)
		(min_thickness 0.25)
		(keepout
			(tracks not_allowed)
			(vias allowed)
			(pads allowed)
			(copperpour not_allowed)
			(footprints allowed)
		)
		(placement
			(enabled no)
			(sheetname "")
		)
		(fill yes
			(thermal_gap 0.5)
			(thermal_bridge_width 0.5)
			(island_removal_mode 0)
		)
		(polygon
			(pts
				(arc
					(start 165.60673 -244.271292)
					(mid 165.621609 -244.307213)
					(end 165.65753 -244.322092)
				)
				(arc
					(start 167.05707 -244.322092)
					(mid 167.092991 -244.307213)
					(end 167.10787 -244.271292)
				)
				(arc
					(start 167.10787 -243.862352)
					(mid 167.092991 -243.826431)
					(end 167.05707 -243.811552)
				)
				(arc
					(start 165.65753 -243.811552)
					(mid 165.621609 -243.826431)
					(end 165.60673 -243.862352)
				)
			)
		)
	)
	(zone
		(layers "In1.Cu" "In2.Cu")
		(hatch none 0.5)
		(connect_pads
			(clearance 0)
		)
		(min_thickness 0.25)
		(keepout
			(tracks not_allowed)
			(vias allowed)
			(pads allowed)
			(copperpour not_allowed)
			(footprints allowed)
		)
		(placement
			(enabled no)
			(sheetname "")
		)
		(fill yes
			(thermal_gap 0.5)
			(thermal_bridge_width 0.5)
			(island_removal_mode 0)
		)
		(polygon
			(pts
				(arc
					(start 60.19673 -293.571422)
					(mid 60.211609 -293.607343)
					(end 60.24753 -293.622222)
				)
				(arc
					(start 61.64707 -293.622222)
					(mid 61.682991 -293.607343)
					(end 61.69787 -293.571422)
				)
				(arc
					(start 61.69787 -293.162482)
					(mid 61.682991 -293.126561)
					(end 61.64707 -293.111682)
				)
				(arc
					(start 60.24753 -293.111682)
					(mid 60.211609 -293.126561)
					(end 60.19673 -293.162482)
				)
			)
		)
	)
	(zone
		(layers "In1.Cu" "In2.Cu")
		(hatch none 0.5)
		(connect_pads
			(clearance 0)
		)
		(min_thickness 0.25)
		(keepout
			(tracks not_allowed)
			(vias allowed)
			(pads allowed)
			(copperpour not_allowed)
			(footprints allowed)
		)
		(placement
			(enabled no)
			(sheetname "")
		)
		(fill yes
			(thermal_gap 0.5)
			(thermal_bridge_width 0.5)
			(island_removal_mode 0)
		)
		(polygon
			(pts
				(arc
					(start 413.546798 -245.971314)
					(mid 413.561677 -246.007235)
					(end 413.597598 -246.022114)
				)
				(arc
					(start 414.997138 -246.022114)
					(mid 415.033059 -246.007235)
					(end 415.047938 -245.971314)
				)
				(arc
					(start 415.047938 -245.562374)
					(mid 415.033059 -245.526453)
					(end 414.997138 -245.511574)
				)
				(arc
					(start 413.597598 -245.511574)
					(mid 413.561677 -245.526453)
					(end 413.546798 -245.562374)
				)
			)
		)
	)
	(zone
		(layers "In1.Cu" "In2.Cu")
		(hatch none 0.5)
		(connect_pads
			(clearance 0)
		)
		(min_thickness 0.25)
		(keepout
			(tracks not_allowed)
			(vias allowed)
			(pads allowed)
			(copperpour not_allowed)
			(footprints allowed)
		)
		(placement
			(enabled no)
			(sheetname "")
		)
		(fill yes
			(thermal_gap 0.5)
			(thermal_bridge_width 0.5)
			(island_removal_mode 0)
		)
		(polygon
			(pts
				(arc
					(start 443.721998 -301.221394)
					(mid 443.736877 -301.257315)
					(end 443.772798 -301.272194)
				)
				(arc
					(start 445.172338 -301.272194)
					(mid 445.208259 -301.257315)
					(end 445.223138 -301.221394)
				)
				(arc
					(start 445.223138 -300.812454)
					(mid 445.208259 -300.776533)
					(end 445.172338 -300.761654)
				)
				(arc
					(start 443.772798 -300.761654)
					(mid 443.736877 -300.776533)
					(end 443.721998 -300.812454)
				)
			)
		)
	)
	(zone
		(layers "In1.Cu" "In2.Cu")
		(hatch none 0.5)
		(connect_pads
			(clearance 0)
		)
		(min_thickness 0.25)
		(keepout
			(tracks not_allowed)
			(vias allowed)
			(pads allowed)
			(copperpour not_allowed)
			(footprints allowed)
		)
		(placement
			(enabled no)
			(sheetname "")
		)
		(fill yes
			(thermal_gap 0.5)
			(thermal_bridge_width 0.5)
			(island_removal_mode 0)
		)
		(polygon
			(pts
				(arc
					(start 440.278266 -211.121498)
					(mid 440.293145 -211.157419)
					(end 440.329066 -211.172298)
				)
				(arc
					(start 441.728606 -211.172298)
					(mid 441.764527 -211.157419)
					(end 441.779406 -211.121498)
				)
				(arc
					(start 441.779406 -210.712558)
					(mid 441.764527 -210.676637)
					(end 441.728606 -210.661758)
				)
				(arc
					(start 440.329066 -210.661758)
					(mid 440.293145 -210.676637)
					(end 440.278266 -210.712558)
				)
			)
		)
	)
	(zone
		(layers "In1.Cu" "In2.Cu")
		(hatch none 0.5)
		(connect_pads
			(clearance 0)
		)
		(min_thickness 0.25)
		(keepout
			(tracks not_allowed)
			(vias allowed)
			(pads allowed)
			(copperpour not_allowed)
			(footprints allowed)
		)
		(placement
			(enabled no)
			(sheetname "")
		)
		(fill yes
			(thermal_gap 0.5)
			(thermal_bridge_width 0.5)
			(island_removal_mode 0)
		)
		(polygon
			(pts
				(arc
					(start 308.136798 -316.521338)
					(mid 308.151677 -316.557259)
					(end 308.187598 -316.572138)
				)
				(arc
					(start 309.587138 -316.572138)
					(mid 309.623059 -316.557259)
					(end 309.637938 -316.521338)
				)
				(arc
					(start 309.637938 -316.112398)
					(mid 309.623059 -316.076477)
					(end 309.587138 -316.061598)
				)
				(arc
					(start 308.187598 -316.061598)
					(mid 308.151677 -316.076477)
					(end 308.136798 -316.112398)
				)
			)
		)
	)
	(zone
		(layers "In1.Cu" "In2.Cu")
		(hatch none 0.5)
		(connect_pads
			(clearance 0)
		)
		(min_thickness 0.25)
		(keepout
			(tracks not_allowed)
			(vias allowed)
			(pads allowed)
			(copperpour not_allowed)
			(footprints allowed)
		)
		(placement
			(enabled no)
			(sheetname "")
		)
		(fill yes
			(thermal_gap 0.5)
			(thermal_bridge_width 0.5)
			(island_removal_mode 0)
		)
		(polygon
			(pts
				(arc
					(start 52.65293 -247.671336)
					(mid 52.667809 -247.707257)
					(end 52.70373 -247.722136)
				)
				(arc
					(start 54.10327 -247.722136)
					(mid 54.139191 -247.707257)
					(end 54.15407 -247.671336)
				)
				(arc
					(start 54.15407 -247.262396)
					(mid 54.139191 -247.226475)
					(end 54.10327 -247.211596)
				)
				(arc
					(start 52.70373 -247.211596)
					(mid 52.667809 -247.226475)
					(end 52.65293 -247.262396)
				)
			)
		)
	)
	(zone
		(layers "In1.Cu" "In2.Cu")
		(hatch none 0.5)
		(connect_pads
			(clearance 0)
		)
		(min_thickness 0.25)
		(keepout
			(tracks not_allowed)
			(vias allowed)
			(pads allowed)
			(copperpour not_allowed)
			(footprints allowed)
		)
		(placement
			(enabled no)
			(sheetname "")
		)
		(fill yes
			(thermal_gap 0.5)
			(thermal_bridge_width 0.5)
			(island_removal_mode 0)
		)
		(polygon
			(pts
				(arc
					(start 455.365866 -296.971466)
					(mid 455.380745 -297.007387)
					(end 455.416666 -297.022266)
				)
				(arc
					(start 456.816206 -297.022266)
					(mid 456.852127 -297.007387)
					(end 456.867006 -296.971466)
				)
				(arc
					(start 456.867006 -296.562526)
					(mid 456.852127 -296.526605)
					(end 456.816206 -296.511726)
				)
				(arc
					(start 455.416666 -296.511726)
					(mid 455.380745 -296.526605)
					(end 455.365866 -296.562526)
				)
			)
		)
	)
	(zone
		(layers "In1.Cu" "In2.Cu")
		(hatch none 0.5)
		(connect_pads
			(clearance 0)
		)
		(min_thickness 0.25)
		(keepout
			(tracks not_allowed)
			(vias allowed)
			(pads allowed)
			(copperpour not_allowed)
			(footprints allowed)
		)
		(placement
			(enabled no)
			(sheetname "")
		)
		(fill yes
			(thermal_gap 0.5)
			(thermal_bridge_width 0.5)
			(island_removal_mode 0)
		)
		(polygon
			(pts
				(arc
					(start 19.033998 -279.9715)
					(mid 19.048877 -280.007421)
					(end 19.084798 -280.0223)
				)
				(arc
					(start 20.484338 -280.0223)
					(mid 20.520259 -280.007421)
					(end 20.535138 -279.9715)
				)
				(arc
					(start 20.535138 -279.56256)
					(mid 20.520259 -279.526639)
					(end 20.484338 -279.51176)
				)
				(arc
					(start 19.084798 -279.51176)
					(mid 19.048877 -279.526639)
					(end 19.033998 -279.56256)
				)
			)
		)
	)
	(zone
		(layers "In1.Cu" "In2.Cu")
		(hatch none 0.5)
		(connect_pads
			(clearance 0)
		)
		(min_thickness 0.25)
		(keepout
			(tracks not_allowed)
			(vias allowed)
			(pads allowed)
			(copperpour not_allowed)
			(footprints allowed)
		)
		(placement
			(enabled no)
			(sheetname "")
		)
		(fill yes
			(thermal_gap 0.5)
			(thermal_bridge_width 0.5)
			(island_removal_mode 0)
		)
		(polygon
			(pts
				(arc
					(start 425.190666 -233.22153)
					(mid 425.205545 -233.257451)
					(end 425.241466 -233.27233)
				)
				(arc
					(start 426.641006 -233.27233)
					(mid 426.676927 -233.257451)
					(end 426.691806 -233.22153)
				)
				(arc
					(start 426.691806 -232.81259)
					(mid 426.676927 -232.776669)
					(end 426.641006 -232.76179)
				)
				(arc
					(start 425.241466 -232.76179)
					(mid 425.205545 -232.776669)
					(end 425.190666 -232.81259)
				)
			)
		)
	)
	(zone
		(layers "In1.Cu" "In2.Cu")
		(hatch none 0.5)
		(connect_pads
			(clearance 0)
		)
		(min_thickness 0.25)
		(keepout
			(tracks not_allowed)
			(vias allowed)
			(pads allowed)
			(copperpour not_allowed)
			(footprints allowed)
		)
		(placement
			(enabled no)
			(sheetname "")
		)
		(fill yes
			(thermal_gap 0.5)
			(thermal_bridge_width 0.5)
			(island_removal_mode 0)
		)
		(polygon
			(pts
				(arc
					(start 451.265798 -228.971348)
					(mid 451.280677 -229.007269)
					(end 451.316598 -229.022148)
				)
				(arc
					(start 452.716138 -229.022148)
					(mid 452.752059 -229.007269)
					(end 452.766938 -228.971348)
				)
				(arc
					(start 452.766938 -228.562408)
					(mid 452.752059 -228.526487)
					(end 452.716138 -228.511608)
				)
				(arc
					(start 451.316598 -228.511608)
					(mid 451.280677 -228.526487)
					(end 451.265798 -228.562408)
				)
			)
		)
	)
	(zone
		(layers "In1.Cu" "In2.Cu")
		(hatch none 0.5)
		(connect_pads
			(clearance 0)
		)
		(min_thickness 0.25)
		(keepout
			(tracks not_allowed)
			(vias allowed)
			(pads allowed)
			(copperpour not_allowed)
			(footprints allowed)
		)
		(placement
			(enabled no)
			(sheetname "")
		)
		(fill yes
			(thermal_gap 0.5)
			(thermal_bridge_width 0.5)
			(island_removal_mode 0)
		)
		(polygon
			(pts
				(arc
					(start 413.546798 -224.72142)
					(mid 413.561677 -224.757341)
					(end 413.597598 -224.77222)
				)
				(arc
					(start 414.997138 -224.77222)
					(mid 415.033059 -224.757341)
					(end 415.047938 -224.72142)
				)
				(arc
					(start 415.047938 -224.31248)
					(mid 415.033059 -224.276559)
					(end 414.997138 -224.26168)
				)
				(arc
					(start 413.597598 -224.26168)
					(mid 413.561677 -224.276559)
					(end 413.546798 -224.31248)
				)
			)
		)
	)
	(zone
		(layers "In1.Cu" "In2.Cu")
		(hatch none 0.5)
		(connect_pads
			(clearance 0)
		)
		(min_thickness 0.25)
		(keepout
			(tracks not_allowed)
			(vias allowed)
			(pads allowed)
			(copperpour not_allowed)
			(footprints allowed)
		)
		(placement
			(enabled no)
			(sheetname "")
		)
		(fill yes
			(thermal_gap 0.5)
			(thermal_bridge_width 0.5)
			(island_removal_mode 0)
		)
		(polygon
			(pts
				(arc
					(start 462.909666 -237.471458)
					(mid 462.924545 -237.507379)
					(end 462.960466 -237.522258)
				)
				(arc
					(start 464.360006 -237.522258)
					(mid 464.395927 -237.507379)
					(end 464.410806 -237.471458)
				)
				(arc
					(start 464.410806 -237.062518)
					(mid 464.395927 -237.026597)
					(end 464.360006 -237.011718)
				)
				(arc
					(start 462.960466 -237.011718)
					(mid 462.924545 -237.026597)
					(end 462.909666 -237.062518)
				)
			)
		)
	)
	(zone
		(layers "In1.Cu" "In2.Cu")
		(hatch none 0.5)
		(connect_pads
			(clearance 0)
		)
		(min_thickness 0.25)
		(keepout
			(tracks not_allowed)
			(vias allowed)
			(pads allowed)
			(copperpour not_allowed)
			(footprints allowed)
		)
		(placement
			(enabled no)
			(sheetname "")
		)
		(fill yes
			(thermal_gap 0.5)
			(thermal_bridge_width 0.5)
			(island_removal_mode 0)
		)
		(polygon
			(pts
				(arc
					(start 274.517866 -205.171548)
					(mid 274.532745 -205.207469)
					(end 274.568666 -205.222348)
				)
				(arc
					(start 275.968206 -205.222348)
					(mid 276.004127 -205.207469)
					(end 276.019006 -205.171548)
				)
				(arc
					(start 276.019006 -204.762608)
					(mid 276.004127 -204.726687)
					(end 275.968206 -204.711808)
				)
				(arc
					(start 274.568666 -204.711808)
					(mid 274.532745 -204.726687)
					(end 274.517866 -204.762608)
				)
			)
		)
	)
	(zone
		(layers "In1.Cu" "In2.Cu")
		(hatch none 0.5)
		(connect_pads
			(clearance 0)
		)
		(min_thickness 0.25)
		(keepout
			(tracks not_allowed)
			(vias allowed)
			(pads allowed)
			(copperpour not_allowed)
			(footprints allowed)
		)
		(placement
			(enabled no)
			(sheetname "")
		)
		(fill yes
			(thermal_gap 0.5)
			(thermal_bridge_width 0.5)
			(island_removal_mode 0)
		)
		(polygon
			(pts
				(arc
					(start 19.033998 -267.221462)
					(mid 19.048877 -267.257383)
					(end 19.084798 -267.272262)
				)
				(arc
					(start 20.484338 -267.272262)
					(mid 20.520259 -267.257383)
					(end 20.535138 -267.221462)
				)
				(arc
					(start 20.535138 -266.812522)
					(mid 20.520259 -266.776601)
					(end 20.484338 -266.761722)
				)
				(arc
					(start 19.084798 -266.761722)
					(mid 19.048877 -266.776601)
					(end 19.033998 -266.812522)
				)
			)
		)
	)
	(zone
		(layers "In1.Cu" "In2.Cu")
		(hatch none 0.5)
		(connect_pads
			(clearance 0)
		)
		(min_thickness 0.25)
		(keepout
			(tracks not_allowed)
			(vias allowed)
			(pads allowed)
			(copperpour not_allowed)
			(footprints allowed)
		)
		(placement
			(enabled no)
			(sheetname "")
		)
		(fill yes
			(thermal_gap 0.5)
			(thermal_bridge_width 0.5)
			(island_removal_mode 0)
		)
		(polygon
			(pts
				(arc
					(start 14.93393 -226.421442)
					(mid 14.948809 -226.457363)
					(end 14.98473 -226.472242)
				)
				(arc
					(start 16.38427 -226.472242)
					(mid 16.420191 -226.457363)
					(end 16.43507 -226.421442)
				)
				(arc
					(start 16.43507 -226.012502)
					(mid 16.420191 -225.976581)
					(end 16.38427 -225.961702)
				)
				(arc
					(start 14.98473 -225.961702)
					(mid 14.948809 -225.976581)
					(end 14.93393 -226.012502)
				)
			)
		)
	)
	(zone
		(layers "In1.Cu" "In2.Cu")
		(hatch none 0.5)
		(connect_pads
			(clearance 0)
		)
		(min_thickness 0.25)
		(keepout
			(tracks not_allowed)
			(vias allowed)
			(pads allowed)
			(copperpour not_allowed)
			(footprints allowed)
		)
		(placement
			(enabled no)
			(sheetname "")
		)
		(fill yes
			(thermal_gap 0.5)
			(thermal_bridge_width 0.5)
			(island_removal_mode 0)
		)
		(polygon
			(pts
				(arc
					(start 300.592998 -313.121294)
					(mid 300.607877 -313.157215)
					(end 300.643798 -313.172094)
				)
				(arc
					(start 302.043338 -313.172094)
					(mid 302.079259 -313.157215)
					(end 302.094138 -313.121294)
				)
				(arc
					(start 302.094138 -312.712354)
					(mid 302.079259 -312.676433)
					(end 302.043338 -312.661554)
				)
				(arc
					(start 300.643798 -312.661554)
					(mid 300.607877 -312.676433)
					(end 300.592998 -312.712354)
				)
			)
		)
	)
	(zone
		(layers "In1.Cu" "In2.Cu")
		(hatch none 0.5)
		(connect_pads
			(clearance 0)
		)
		(min_thickness 0.25)
		(keepout
			(tracks not_allowed)
			(vias allowed)
			(pads allowed)
			(copperpour not_allowed)
			(footprints allowed)
		)
		(placement
			(enabled no)
			(sheetname "")
		)
		(fill yes
			(thermal_gap 0.5)
			(thermal_bridge_width 0.5)
			(island_removal_mode 0)
		)
		(polygon
			(pts
				(arc
					(start 308.136798 -228.121464)
					(mid 308.151677 -228.157385)
					(end 308.187598 -228.172264)
				)
				(arc
					(start 309.587138 -228.172264)
					(mid 309.623059 -228.157385)
					(end 309.637938 -228.121464)
				)
				(arc
					(start 309.637938 -227.712524)
					(mid 309.623059 -227.676603)
					(end 309.587138 -227.661724)
				)
				(arc
					(start 308.187598 -227.661724)
					(mid 308.151677 -227.676603)
					(end 308.136798 -227.712524)
				)
			)
		)
	)
	(zone
		(layers "In1.Cu" "In2.Cu")
		(hatch none 0.5)
		(connect_pads
			(clearance 0)
		)
		(min_thickness 0.25)
		(keepout
			(tracks not_allowed)
			(vias allowed)
			(pads allowed)
			(copperpour not_allowed)
			(footprints allowed)
		)
		(placement
			(enabled no)
			(sheetname "")
		)
		(fill yes
			(thermal_gap 0.5)
			(thermal_bridge_width 0.5)
			(island_removal_mode 0)
		)
		(polygon
			(pts
				(arc
					(start 425.190666 -306.32146)
					(mid 425.205545 -306.357381)
					(end 425.241466 -306.37226)
				)
				(arc
					(start 426.641006 -306.37226)
					(mid 426.676927 -306.357381)
					(end 426.691806 -306.32146)
				)
				(arc
					(start 426.691806 -305.91252)
					(mid 426.676927 -305.876599)
					(end 426.641006 -305.86172)
				)
				(arc
					(start 425.241466 -305.86172)
					(mid 425.205545 -305.876599)
					(end 425.190666 -305.91252)
				)
			)
		)
	)
	(zone
		(layers "In1.Cu" "In2.Cu")
		(hatch none 0.5)
		(connect_pads
			(clearance 0)
		)
		(min_thickness 0.25)
		(keepout
			(tracks not_allowed)
			(vias allowed)
			(pads allowed)
			(copperpour not_allowed)
			(footprints allowed)
		)
		(placement
			(enabled no)
			(sheetname "")
		)
		(fill yes
			(thermal_gap 0.5)
			(thermal_bridge_width 0.5)
			(island_removal_mode 0)
		)
		(polygon
			(pts
				(arc
					(start 26.577798 -284.221428)
					(mid 26.592677 -284.257349)
					(end 26.628598 -284.272228)
				)
				(arc
					(start 28.028138 -284.272228)
					(mid 28.064059 -284.257349)
					(end 28.078938 -284.221428)
				)
				(arc
					(start 28.078938 -283.812488)
					(mid 28.064059 -283.776567)
					(end 28.028138 -283.761688)
				)
				(arc
					(start 26.628598 -283.761688)
					(mid 26.592677 -283.776567)
					(end 26.577798 -283.812488)
				)
			)
		)
	)
	(zone
		(layers "In1.Cu" "In2.Cu")
		(hatch none 0.5)
		(connect_pads
			(clearance 0)
		)
		(min_thickness 0.25)
		(keepout
			(tracks not_allowed)
			(vias allowed)
			(pads allowed)
			(copperpour not_allowed)
			(footprints allowed)
		)
		(placement
			(enabled no)
			(sheetname "")
		)
		(fill yes
			(thermal_gap 0.5)
			(thermal_bridge_width 0.5)
			(island_removal_mode 0)
		)
		(polygon
			(pts
				(arc
					(start 165.60673 -238.321342)
					(mid 165.621609 -238.357263)
					(end 165.65753 -238.372142)
				)
				(arc
					(start 167.05707 -238.372142)
					(mid 167.092991 -238.357263)
					(end 167.10787 -238.321342)
				)
				(arc
					(start 167.10787 -237.912402)
					(mid 167.092991 -237.876481)
					(end 167.05707 -237.861602)
				)
				(arc
					(start 165.65753 -237.861602)
					(mid 165.621609 -237.876481)
					(end 165.60673 -237.912402)
				)
			)
		)
	)
	(zone
		(layers "In1.Cu" "In2.Cu")
		(hatch none 0.5)
		(connect_pads
			(clearance 0)
		)
		(min_thickness 0.25)
		(keepout
			(tracks not_allowed)
			(vias allowed)
			(pads allowed)
			(copperpour not_allowed)
			(footprints allowed)
		)
		(placement
			(enabled no)
			(sheetname "")
		)
		(fill yes
			(thermal_gap 0.5)
			(thermal_bridge_width 0.5)
			(island_removal_mode 0)
		)
		(polygon
			(pts
				(arc
					(start 425.190666 -208.571338)
					(mid 425.205545 -208.607259)
					(end 425.241466 -208.622138)
				)
				(arc
					(start 426.641006 -208.622138)
					(mid 426.676927 -208.607259)
					(end 426.691806 -208.571338)
				)
				(arc
					(start 426.691806 -208.162398)
					(mid 426.676927 -208.126477)
					(end 426.641006 -208.111598)
				)
				(arc
					(start 425.241466 -208.111598)
					(mid 425.205545 -208.126477)
					(end 425.190666 -208.162398)
				)
			)
		)
	)
	(zone
		(layers "In1.Cu" "In2.Cu")
		(hatch none 0.5)
		(connect_pads
			(clearance 0)
		)
		(min_thickness 0.25)
		(keepout
			(tracks not_allowed)
			(vias allowed)
			(pads allowed)
			(copperpour not_allowed)
			(footprints allowed)
		)
		(placement
			(enabled no)
			(sheetname "")
		)
		(fill yes
			(thermal_gap 0.5)
			(thermal_bridge_width 0.5)
			(island_removal_mode 0)
		)
		(polygon
			(pts
				(arc
					(start 406.002998 -215.371426)
					(mid 406.017877 -215.407347)
					(end 406.053798 -215.422226)
				)
				(arc
					(start 407.453338 -215.422226)
					(mid 407.489259 -215.407347)
					(end 407.504138 -215.371426)
				)
				(arc
					(start 407.504138 -214.962486)
					(mid 407.489259 -214.926565)
					(end 407.453338 -214.911686)
				)
				(arc
					(start 406.053798 -214.911686)
					(mid 406.017877 -214.926565)
					(end 406.002998 -214.962486)
				)
			)
		)
	)
	(zone
		(layers "In1.Cu" "In2.Cu")
		(hatch none 0.5)
		(connect_pads
			(clearance 0)
		)
		(min_thickness 0.25)
		(keepout
			(tracks not_allowed)
			(vias allowed)
			(pads allowed)
			(copperpour not_allowed)
			(footprints allowed)
		)
		(placement
			(enabled no)
			(sheetname "")
		)
		(fill yes
			(thermal_gap 0.5)
			(thermal_bridge_width 0.5)
			(island_removal_mode 0)
		)
		(polygon
			(pts
				(arc
					(start 162.162998 -302.071532)
					(mid 162.177877 -302.107453)
					(end 162.213798 -302.122332)
				)
				(arc
					(start 163.613338 -302.122332)
					(mid 163.649259 -302.107453)
					(end 163.664138 -302.071532)
				)
				(arc
					(start 163.664138 -301.662592)
					(mid 163.649259 -301.626671)
					(end 163.613338 -301.611792)
				)
				(arc
					(start 162.213798 -301.611792)
					(mid 162.177877 -301.626671)
					(end 162.162998 -301.662592)
				)
			)
		)
	)
	(zone
		(layers "In1.Cu" "In2.Cu")
		(hatch none 0.5)
		(connect_pads
			(clearance 0)
		)
		(min_thickness 0.25)
		(keepout
			(tracks not_allowed)
			(vias allowed)
			(pads allowed)
			(copperpour not_allowed)
			(footprints allowed)
		)
		(placement
			(enabled no)
			(sheetname "")
		)
		(fill yes
			(thermal_gap 0.5)
			(thermal_bridge_width 0.5)
			(island_removal_mode 0)
		)
		(polygon
			(pts
				(arc
					(start 428.634398 -296.121328)
					(mid 428.649277 -296.157249)
					(end 428.685198 -296.172128)
				)
				(arc
					(start 430.084738 -296.172128)
					(mid 430.120659 -296.157249)
					(end 430.135538 -296.121328)
				)
				(arc
					(start 430.135538 -295.712388)
					(mid 430.120659 -295.676467)
					(end 430.084738 -295.661588)
				)
				(arc
					(start 428.685198 -295.661588)
					(mid 428.649277 -295.676467)
					(end 428.634398 -295.712388)
				)
			)
		)
	)
	(zone
		(layers "In1.Cu" "In2.Cu")
		(hatch none 0.5)
		(connect_pads
			(clearance 0)
		)
		(min_thickness 0.25)
		(keepout
			(tracks not_allowed)
			(vias allowed)
			(pads allowed)
			(copperpour not_allowed)
			(footprints allowed)
		)
		(placement
			(enabled no)
			(sheetname "")
		)
		(fill yes
			(thermal_gap 0.5)
			(thermal_bridge_width 0.5)
			(island_removal_mode 0)
		)
		(polygon
			(pts
				(arc
					(start 455.365866 -302.921416)
					(mid 455.380745 -302.957337)
					(end 455.416666 -302.972216)
				)
				(arc
					(start 456.816206 -302.972216)
					(mid 456.852127 -302.957337)
					(end 456.867006 -302.921416)
				)
				(arc
					(start 456.867006 -302.512476)
					(mid 456.852127 -302.476555)
					(end 456.816206 -302.461676)
				)
				(arc
					(start 455.416666 -302.461676)
					(mid 455.380745 -302.476555)
					(end 455.365866 -302.512476)
				)
			)
		)
	)
	(zone
		(layers "In1.Cu" "In2.Cu")
		(hatch none 0.5)
		(connect_pads
			(clearance 0)
		)
		(min_thickness 0.25)
		(keepout
			(tracks not_allowed)
			(vias allowed)
			(pads allowed)
			(copperpour not_allowed)
			(footprints allowed)
		)
		(placement
			(enabled no)
			(sheetname "")
		)
		(fill yes
			(thermal_gap 0.5)
			(thermal_bridge_width 0.5)
			(island_removal_mode 0)
		)
		(polygon
			(pts
				(arc
					(start 207.425798 -270.621506)
					(mid 207.440677 -270.657427)
					(end 207.476598 -270.672306)
				)
				(arc
					(start 208.876138 -270.672306)
					(mid 208.912059 -270.657427)
					(end 208.926938 -270.621506)
				)
				(arc
					(start 208.926938 -270.212566)
					(mid 208.912059 -270.176645)
					(end 208.876138 -270.161766)
				)
				(arc
					(start 207.476598 -270.161766)
					(mid 207.440677 -270.176645)
					(end 207.425798 -270.212566)
				)
			)
		)
	)
	(zone
		(layers "In1.Cu" "In2.Cu")
		(hatch none 0.5)
		(connect_pads
			(clearance 0)
		)
		(min_thickness 0.25)
		(keepout
			(tracks not_allowed)
			(vias allowed)
			(pads allowed)
			(copperpour not_allowed)
			(footprints allowed)
		)
		(placement
			(enabled no)
			(sheetname "")
		)
		(fill yes
			(thermal_gap 0.5)
			(thermal_bridge_width 0.5)
			(island_removal_mode 0)
		)
		(polygon
			(pts
				(arc
					(start 270.417798 -235.771436)
					(mid 270.432677 -235.807357)
					(end 270.468598 -235.822236)
				)
				(arc
					(start 271.868138 -235.822236)
					(mid 271.904059 -235.807357)
					(end 271.918938 -235.771436)
				)
				(arc
					(start 271.918938 -235.362496)
					(mid 271.904059 -235.326575)
					(end 271.868138 -235.311696)
				)
				(arc
					(start 270.468598 -235.311696)
					(mid 270.432677 -235.326575)
					(end 270.417798 -235.362496)
				)
			)
		)
	)
	(zone
		(layers "In1.Cu" "In2.Cu")
		(hatch none 0.5)
		(connect_pads
			(clearance 0)
		)
		(min_thickness 0.25)
		(keepout
			(tracks not_allowed)
			(vias allowed)
			(pads allowed)
			(copperpour not_allowed)
			(footprints allowed)
		)
		(placement
			(enabled no)
			(sheetname "")
		)
		(fill yes
			(thermal_gap 0.5)
			(thermal_bridge_width 0.5)
			(island_removal_mode 0)
		)
		(polygon
			(pts
				(arc
					(start 432.734466 -309.721504)
					(mid 432.749345 -309.757425)
					(end 432.785266 -309.772304)
				)
				(arc
					(start 434.184806 -309.772304)
					(mid 434.220727 -309.757425)
					(end 434.235606 -309.721504)
				)
				(arc
					(start 434.235606 -309.312564)
					(mid 434.220727 -309.276643)
					(end 434.184806 -309.261764)
				)
				(arc
					(start 432.785266 -309.261764)
					(mid 432.749345 -309.276643)
					(end 432.734466 -309.312564)
				)
			)
		)
	)
	(zone
		(layers "In1.Cu" "In2.Cu")
		(hatch none 0.5)
		(connect_pads
			(clearance 0)
		)
		(min_thickness 0.25)
		(keepout
			(tracks not_allowed)
			(vias allowed)
			(pads allowed)
			(copperpour not_allowed)
			(footprints allowed)
		)
		(placement
			(enabled no)
			(sheetname "")
		)
		(fill yes
			(thermal_gap 0.5)
			(thermal_bridge_width 0.5)
			(island_removal_mode 0)
		)
		(polygon
			(pts
				(arc
					(start 432.734466 -201.771504)
					(mid 432.749345 -201.807425)
					(end 432.785266 -201.822304)
				)
				(arc
					(start 434.184806 -201.822304)
					(mid 434.220727 -201.807425)
					(end 434.235606 -201.771504)
				)
				(arc
					(start 434.235606 -201.362564)
					(mid 434.220727 -201.326643)
					(end 434.184806 -201.311764)
				)
				(arc
					(start 432.785266 -201.311764)
					(mid 432.749345 -201.326643)
					(end 432.734466 -201.362564)
				)
			)
		)
	)
	(zone
		(layers "In1.Cu" "In2.Cu")
		(hatch none 0.5)
		(connect_pads
			(clearance 0)
		)
		(min_thickness 0.25)
		(keepout
			(tracks not_allowed)
			(vias allowed)
			(pads allowed)
			(copperpour not_allowed)
			(footprints allowed)
		)
		(placement
			(enabled no)
			(sheetname "")
		)
		(fill yes
			(thermal_gap 0.5)
			(thermal_bridge_width 0.5)
			(island_removal_mode 0)
		)
		(polygon
			(pts
				(arc
					(start 37.56533 -211.971382)
					(mid 37.580209 -212.007303)
					(end 37.61613 -212.022182)
				)
				(arc
					(start 39.01567 -212.022182)
					(mid 39.051591 -212.007303)
					(end 39.06647 -211.971382)
				)
				(arc
					(start 39.06647 -211.562442)
					(mid 39.051591 -211.526521)
					(end 39.01567 -211.511642)
				)
				(arc
					(start 37.61613 -211.511642)
					(mid 37.580209 -211.526521)
					(end 37.56533 -211.562442)
				)
			)
		)
	)
	(zone
		(layers "In1.Cu" "In2.Cu")
		(hatch none 0.5)
		(connect_pads
			(clearance 0)
		)
		(min_thickness 0.25)
		(keepout
			(tracks not_allowed)
			(vias allowed)
			(pads allowed)
			(copperpour not_allowed)
			(footprints allowed)
		)
		(placement
			(enabled no)
			(sheetname "")
		)
		(fill yes
			(thermal_gap 0.5)
			(thermal_bridge_width 0.5)
			(island_removal_mode 0)
		)
		(polygon
			(pts
				(arc
					(start 259.430266 -298.671488)
					(mid 259.445145 -298.707409)
					(end 259.481066 -298.722288)
				)
				(arc
					(start 260.880606 -298.722288)
					(mid 260.916527 -298.707409)
					(end 260.931406 -298.671488)
				)
				(arc
					(start 260.931406 -298.262548)
					(mid 260.916527 -298.226627)
					(end 260.880606 -298.211748)
				)
				(arc
					(start 259.481066 -298.211748)
					(mid 259.445145 -298.226627)
					(end 259.430266 -298.262548)
				)
			)
		)
	)
	(zone
		(layers "In1.Cu" "In2.Cu")
		(hatch none 0.5)
		(connect_pads
			(clearance 0)
		)
		(min_thickness 0.25)
		(keepout
			(tracks not_allowed)
			(vias allowed)
			(pads allowed)
			(copperpour not_allowed)
			(footprints allowed)
		)
		(placement
			(enabled no)
			(sheetname "")
		)
		(fill yes
			(thermal_gap 0.5)
			(thermal_bridge_width 0.5)
			(island_removal_mode 0)
		)
		(polygon
			(pts
				(arc
					(start 165.60673 -273.171412)
					(mid 165.621609 -273.207333)
					(end 165.65753 -273.222212)
				)
				(arc
					(start 167.05707 -273.222212)
					(mid 167.092991 -273.207333)
					(end 167.10787 -273.171412)
				)
				(arc
					(start 167.10787 -272.762472)
					(mid 167.092991 -272.726551)
					(end 167.05707 -272.711672)
				)
				(arc
					(start 165.65753 -272.711672)
					(mid 165.621609 -272.726551)
					(end 165.60673 -272.762472)
				)
			)
		)
	)
	(zone
		(layers "In1.Cu" "In2.Cu")
		(hatch none 0.5)
		(connect_pads
			(clearance 0)
		)
		(min_thickness 0.25)
		(keepout
			(tracks not_allowed)
			(vias allowed)
			(pads allowed)
			(copperpour not_allowed)
			(footprints allowed)
		)
		(placement
			(enabled no)
			(sheetname "")
		)
		(fill yes
			(thermal_gap 0.5)
			(thermal_bridge_width 0.5)
			(island_removal_mode 0)
		)
		(polygon
			(pts
				(arc
					(start 410.103066 -212.82152)
					(mid 410.117945 -212.857441)
					(end 410.153866 -212.87232)
				)
				(arc
					(start 411.553406 -212.87232)
					(mid 411.589327 -212.857441)
					(end 411.604206 -212.82152)
				)
				(arc
					(start 411.604206 -212.41258)
					(mid 411.589327 -212.376659)
					(end 411.553406 -212.36178)
				)
				(arc
					(start 410.153866 -212.36178)
					(mid 410.117945 -212.376659)
					(end 410.103066 -212.41258)
				)
			)
		)
	)
	(zone
		(layers "In1.Cu" "In2.Cu")
		(hatch none 0.5)
		(connect_pads
			(clearance 0)
		)
		(min_thickness 0.25)
		(keepout
			(tracks not_allowed)
			(vias allowed)
			(pads allowed)
			(copperpour not_allowed)
			(footprints allowed)
		)
		(placement
			(enabled no)
			(sheetname "")
		)
		(fill yes
			(thermal_gap 0.5)
			(thermal_bridge_width 0.5)
			(island_removal_mode 0)
		)
		(polygon
			(pts
				(arc
					(start 56.752998 -209.421476)
					(mid 56.767877 -209.457397)
					(end 56.803798 -209.472276)
				)
				(arc
					(start 58.203338 -209.472276)
					(mid 58.239259 -209.457397)
					(end 58.254138 -209.421476)
				)
				(arc
					(start 58.254138 -209.012536)
					(mid 58.239259 -208.976615)
					(end 58.203338 -208.961736)
				)
				(arc
					(start 56.803798 -208.961736)
					(mid 56.767877 -208.976615)
					(end 56.752998 -209.012536)
				)
			)
		)
	)
	(zone
		(layers "In1.Cu" "In2.Cu")
		(hatch none 0.5)
		(connect_pads
			(clearance 0)
		)
		(min_thickness 0.25)
		(keepout
			(tracks not_allowed)
			(vias allowed)
			(pads allowed)
			(copperpour not_allowed)
			(footprints allowed)
		)
		(placement
			(enabled no)
			(sheetname "")
		)
		(fill yes
			(thermal_gap 0.5)
			(thermal_bridge_width 0.5)
			(island_removal_mode 0)
		)
		(polygon
			(pts
				(arc
					(start 285.505398 -230.67137)
					(mid 285.520277 -230.707291)
					(end 285.556198 -230.72217)
				)
				(arc
					(start 286.955738 -230.72217)
					(mid 286.991659 -230.707291)
					(end 287.006538 -230.67137)
				)
				(arc
					(start 287.006538 -230.26243)
					(mid 286.991659 -230.226509)
					(end 286.955738 -230.21163)
				)
				(arc
					(start 285.556198 -230.21163)
					(mid 285.520277 -230.226509)
					(end 285.505398 -230.26243)
				)
			)
		)
	)
	(zone
		(layers "In1.Cu" "In2.Cu")
		(hatch none 0.5)
		(connect_pads
			(clearance 0)
		)
		(min_thickness 0.25)
		(keepout
			(tracks not_allowed)
			(vias allowed)
			(pads allowed)
			(copperpour not_allowed)
			(footprints allowed)
		)
		(placement
			(enabled no)
			(sheetname "")
		)
		(fill yes
			(thermal_gap 0.5)
			(thermal_bridge_width 0.5)
			(island_removal_mode 0)
		)
		(polygon
			(pts
				(arc
					(start 274.517866 -279.9715)
					(mid 274.532745 -280.007421)
					(end 274.568666 -280.0223)
				)
				(arc
					(start 275.968206 -280.0223)
					(mid 276.004127 -280.007421)
					(end 276.019006 -279.9715)
				)
				(arc
					(start 276.019006 -279.56256)
					(mid 276.004127 -279.526639)
					(end 275.968206 -279.51176)
				)
				(arc
					(start 274.568666 -279.51176)
					(mid 274.532745 -279.526639)
					(end 274.517866 -279.56256)
				)
			)
		)
	)
	(zone
		(layers "In1.Cu" "In2.Cu")
		(hatch none 0.5)
		(connect_pads
			(clearance 0)
		)
		(min_thickness 0.25)
		(keepout
			(tracks not_allowed)
			(vias allowed)
			(pads allowed)
			(copperpour not_allowed)
			(footprints allowed)
		)
		(placement
			(enabled no)
			(sheetname "")
		)
		(fill yes
			(thermal_gap 0.5)
			(thermal_bridge_width 0.5)
			(island_removal_mode 0)
		)
		(polygon
			(pts
				(arc
					(start 300.592998 -280.821384)
					(mid 300.607877 -280.857305)
					(end 300.643798 -280.872184)
				)
				(arc
					(start 302.043338 -280.872184)
					(mid 302.079259 -280.857305)
					(end 302.094138 -280.821384)
				)
				(arc
					(start 302.094138 -280.412444)
					(mid 302.079259 -280.376523)
					(end 302.043338 -280.361644)
				)
				(arc
					(start 300.643798 -280.361644)
					(mid 300.607877 -280.376523)
					(end 300.592998 -280.412444)
				)
			)
		)
	)
	(zone
		(layers "In1.Cu" "In2.Cu")
		(hatch none 0.5)
		(connect_pads
			(clearance 0)
		)
		(min_thickness 0.25)
		(keepout
			(tracks not_allowed)
			(vias allowed)
			(pads allowed)
			(copperpour not_allowed)
			(footprints allowed)
		)
		(placement
			(enabled no)
			(sheetname "")
		)
		(fill yes
			(thermal_gap 0.5)
			(thermal_bridge_width 0.5)
			(island_removal_mode 0)
		)
		(polygon
			(pts
				(arc
					(start 417.646866 -285.92145)
					(mid 417.661745 -285.957371)
					(end 417.697666 -285.97225)
				)
				(arc
					(start 419.097206 -285.97225)
					(mid 419.133127 -285.957371)
					(end 419.148006 -285.92145)
				)
				(arc
					(start 419.148006 -285.51251)
					(mid 419.133127 -285.476589)
					(end 419.097206 -285.46171)
				)
				(arc
					(start 417.697666 -285.46171)
					(mid 417.661745 -285.476589)
					(end 417.646866 -285.51251)
				)
			)
		)
	)
	(zone
		(layers "In1.Cu" "In2.Cu")
		(hatch none 0.5)
		(connect_pads
			(clearance 0)
		)
		(min_thickness 0.25)
		(keepout
			(tracks not_allowed)
			(vias allowed)
			(pads allowed)
			(copperpour not_allowed)
			(footprints allowed)
		)
		(placement
			(enabled no)
			(sheetname "")
		)
		(fill yes
			(thermal_gap 0.5)
			(thermal_bridge_width 0.5)
			(island_removal_mode 0)
		)
		(polygon
			(pts
				(arc
					(start 282.061666 -274.871434)
					(mid 282.076545 -274.907355)
					(end 282.112466 -274.922234)
				)
				(arc
					(start 283.512006 -274.922234)
					(mid 283.547927 -274.907355)
					(end 283.562806 -274.871434)
				)
				(arc
					(start 283.562806 -274.462494)
					(mid 283.547927 -274.426573)
					(end 283.512006 -274.411694)
				)
				(arc
					(start 282.112466 -274.411694)
					(mid 282.076545 -274.426573)
					(end 282.061666 -274.462494)
				)
			)
		)
	)
	(zone
		(layers "In1.Cu" "In2.Cu")
		(hatch none 0.5)
		(connect_pads
			(clearance 0)
		)
		(min_thickness 0.25)
		(keepout
			(tracks not_allowed)
			(vias allowed)
			(pads allowed)
			(copperpour not_allowed)
			(footprints allowed)
		)
		(placement
			(enabled no)
			(sheetname "")
		)
		(fill yes
			(thermal_gap 0.5)
			(thermal_bridge_width 0.5)
			(island_removal_mode 0)
		)
		(polygon
			(pts
				(arc
					(start 60.19673 -234.071414)
					(mid 60.211609 -234.107335)
					(end 60.24753 -234.122214)
				)
				(arc
					(start 61.64707 -234.122214)
					(mid 61.682991 -234.107335)
					(end 61.69787 -234.071414)
				)
				(arc
					(start 61.69787 -233.662474)
					(mid 61.682991 -233.626553)
					(end 61.64707 -233.611674)
				)
				(arc
					(start 60.24753 -233.611674)
					(mid 60.211609 -233.626553)
					(end 60.19673 -233.662474)
				)
			)
		)
	)
	(zone
		(layers "In1.Cu" "In2.Cu")
		(hatch none 0.5)
		(connect_pads
			(clearance 0)
		)
		(min_thickness 0.25)
		(keepout
			(tracks not_allowed)
			(vias allowed)
			(pads allowed)
			(copperpour not_allowed)
			(footprints allowed)
		)
		(placement
			(enabled no)
			(sheetname "")
		)
		(fill yes
			(thermal_gap 0.5)
			(thermal_bridge_width 0.5)
			(island_removal_mode 0)
		)
		(polygon
			(pts
				(arc
					(start 177.250598 -262.121396)
					(mid 177.265477 -262.157317)
					(end 177.301398 -262.172196)
				)
				(arc
					(start 178.700938 -262.172196)
					(mid 178.736859 -262.157317)
					(end 178.751738 -262.121396)
				)
				(arc
					(start 178.751738 -261.712456)
					(mid 178.736859 -261.676535)
					(end 178.700938 -261.661656)
				)
				(arc
					(start 177.301398 -261.661656)
					(mid 177.265477 -261.676535)
					(end 177.250598 -261.712456)
				)
			)
		)
	)
	(zone
		(layers "In1.Cu" "In2.Cu")
		(hatch none 0.5)
		(connect_pads
			(clearance 0)
		)
		(min_thickness 0.25)
		(keepout
			(tracks not_allowed)
			(vias allowed)
			(pads allowed)
			(copperpour not_allowed)
			(footprints allowed)
		)
		(placement
			(enabled no)
			(sheetname "")
		)
		(fill yes
			(thermal_gap 0.5)
			(thermal_bridge_width 0.5)
			(island_removal_mode 0)
		)
		(polygon
			(pts
				(arc
					(start 259.430266 -260.421374)
					(mid 259.445145 -260.457295)
					(end 259.481066 -260.472174)
				)
				(arc
					(start 260.880606 -260.472174)
					(mid 260.916527 -260.457295)
					(end 260.931406 -260.421374)
				)
				(arc
					(start 260.931406 -260.012434)
					(mid 260.916527 -259.976513)
					(end 260.880606 -259.961634)
				)
				(arc
					(start 259.481066 -259.961634)
					(mid 259.445145 -259.976513)
					(end 259.430266 -260.012434)
				)
			)
		)
	)
	(zone
		(layers "In1.Cu" "In2.Cu")
		(hatch none 0.5)
		(connect_pads
			(clearance 0)
		)
		(min_thickness 0.25)
		(keepout
			(tracks not_allowed)
			(vias allowed)
			(pads allowed)
			(copperpour not_allowed)
			(footprints allowed)
		)
		(placement
			(enabled no)
			(sheetname "")
		)
		(fill yes
			(thermal_gap 0.5)
			(thermal_bridge_width 0.5)
			(island_removal_mode 0)
		)
		(polygon
			(pts
				(arc
					(start 285.505398 -307.171344)
					(mid 285.520277 -307.207265)
					(end 285.556198 -307.222144)
				)
				(arc
					(start 286.955738 -307.222144)
					(mid 286.991659 -307.207265)
					(end 287.006538 -307.171344)
				)
				(arc
					(start 287.006538 -306.762404)
					(mid 286.991659 -306.726483)
					(end 286.955738 -306.711604)
				)
				(arc
					(start 285.556198 -306.711604)
					(mid 285.520277 -306.726483)
					(end 285.505398 -306.762404)
				)
			)
		)
	)
	(zone
		(layers "In1.Cu" "In2.Cu")
		(hatch none 0.5)
		(connect_pads
			(clearance 0)
		)
		(min_thickness 0.25)
		(keepout
			(tracks not_allowed)
			(vias allowed)
			(pads allowed)
			(copperpour not_allowed)
			(footprints allowed)
		)
		(placement
			(enabled no)
			(sheetname "")
		)
		(fill yes
			(thermal_gap 0.5)
			(thermal_bridge_width 0.5)
			(island_removal_mode 0)
		)
		(polygon
			(pts
				(arc
					(start 447.822066 -246.821452)
					(mid 447.836945 -246.857373)
					(end 447.872866 -246.872252)
				)
				(arc
					(start 449.272406 -246.872252)
					(mid 449.308327 -246.857373)
					(end 449.323206 -246.821452)
				)
				(arc
					(start 449.323206 -246.412512)
					(mid 449.308327 -246.376591)
					(end 449.272406 -246.361712)
				)
				(arc
					(start 447.872866 -246.361712)
					(mid 447.836945 -246.376591)
					(end 447.822066 -246.412512)
				)
			)
		)
	)
	(zone
		(layers "In1.Cu" "In2.Cu")
		(hatch none 0.5)
		(connect_pads
			(clearance 0)
		)
		(min_thickness 0.25)
		(keepout
			(tracks not_allowed)
			(vias allowed)
			(pads allowed)
			(copperpour not_allowed)
			(footprints allowed)
		)
		(placement
			(enabled no)
			(sheetname "")
		)
		(fill yes
			(thermal_gap 0.5)
			(thermal_bridge_width 0.5)
			(island_removal_mode 0)
		)
		(polygon
			(pts
				(arc
					(start 421.090598 -226.421442)
					(mid 421.105477 -226.457363)
					(end 421.141398 -226.472242)
				)
				(arc
					(start 422.540938 -226.472242)
					(mid 422.576859 -226.457363)
					(end 422.591738 -226.421442)
				)
				(arc
					(start 422.591738 -226.012502)
					(mid 422.576859 -225.976581)
					(end 422.540938 -225.961702)
				)
				(arc
					(start 421.141398 -225.961702)
					(mid 421.105477 -225.976581)
					(end 421.090598 -226.012502)
				)
			)
		)
	)
	(zone
		(layers "In1.Cu" "In2.Cu")
		(hatch none 0.5)
		(connect_pads
			(clearance 0)
		)
		(min_thickness 0.25)
		(keepout
			(tracks not_allowed)
			(vias allowed)
			(pads allowed)
			(copperpour not_allowed)
			(footprints allowed)
		)
		(placement
			(enabled no)
			(sheetname "")
		)
		(fill yes
			(thermal_gap 0.5)
			(thermal_bridge_width 0.5)
			(island_removal_mode 0)
		)
		(polygon
			(pts
				(arc
					(start 210.86953 -286.771334)
					(mid 210.884409 -286.807255)
					(end 210.92033 -286.822134)
				)
				(arc
					(start 212.31987 -286.822134)
					(mid 212.355791 -286.807255)
					(end 212.37067 -286.771334)
				)
				(arc
					(start 212.37067 -286.362394)
					(mid 212.355791 -286.326473)
					(end 212.31987 -286.311594)
				)
				(arc
					(start 210.92033 -286.311594)
					(mid 210.884409 -286.326473)
					(end 210.86953 -286.362394)
				)
			)
		)
	)
	(zone
		(layers "In1.Cu" "In2.Cu")
		(hatch none 0.5)
		(connect_pads
			(clearance 0)
		)
		(min_thickness 0.25)
		(keepout
			(tracks not_allowed)
			(vias allowed)
			(pads allowed)
			(copperpour not_allowed)
			(footprints allowed)
		)
		(placement
			(enabled no)
			(sheetname "")
		)
		(fill yes
			(thermal_gap 0.5)
			(thermal_bridge_width 0.5)
			(island_removal_mode 0)
		)
		(polygon
			(pts
				(arc
					(start 30.02153 -261.271512)
					(mid 30.036409 -261.307433)
					(end 30.07233 -261.322312)
				)
				(arc
					(start 31.47187 -261.322312)
					(mid 31.507791 -261.307433)
					(end 31.52267 -261.271512)
				)
				(arc
					(start 31.52267 -260.862572)
					(mid 31.507791 -260.826651)
					(end 31.47187 -260.811772)
				)
				(arc
					(start 30.07233 -260.811772)
					(mid 30.036409 -260.826651)
					(end 30.02153 -260.862572)
				)
			)
		)
	)
	(zone
		(layers "In1.Cu" "In2.Cu")
		(hatch none 0.5)
		(connect_pads
			(clearance 0)
		)
		(min_thickness 0.25)
		(keepout
			(tracks not_allowed)
			(vias allowed)
			(pads allowed)
			(copperpour not_allowed)
			(footprints allowed)
		)
		(placement
			(enabled no)
			(sheetname "")
		)
		(fill yes
			(thermal_gap 0.5)
			(thermal_bridge_width 0.5)
			(island_removal_mode 0)
		)
		(polygon
			(pts
				(arc
					(start 297.149266 -295.271444)
					(mid 297.164145 -295.307365)
					(end 297.200066 -295.322244)
				)
				(arc
					(start 298.599606 -295.322244)
					(mid 298.635527 -295.307365)
					(end 298.650406 -295.271444)
				)
				(arc
					(start 298.650406 -294.862504)
					(mid 298.635527 -294.826583)
					(end 298.599606 -294.811704)
				)
				(arc
					(start 297.200066 -294.811704)
					(mid 297.164145 -294.826583)
					(end 297.149266 -294.862504)
				)
			)
		)
	)
	(zone
		(layers "In1.Cu" "In2.Cu")
		(hatch none 0.5)
		(connect_pads
			(clearance 0)
		)
		(min_thickness 0.25)
		(keepout
			(tracks not_allowed)
			(vias allowed)
			(pads allowed)
			(copperpour not_allowed)
			(footprints allowed)
		)
		(placement
			(enabled no)
			(sheetname "")
		)
		(fill yes
			(thermal_gap 0.5)
			(thermal_bridge_width 0.5)
			(island_removal_mode 0)
		)
		(polygon
			(pts
				(arc
					(start 277.961598 -313.121294)
					(mid 277.976477 -313.157215)
					(end 278.012398 -313.172094)
				)
				(arc
					(start 279.411938 -313.172094)
					(mid 279.447859 -313.157215)
					(end 279.462738 -313.121294)
				)
				(arc
					(start 279.462738 -312.712354)
					(mid 279.447859 -312.676433)
					(end 279.411938 -312.661554)
				)
				(arc
					(start 278.012398 -312.661554)
					(mid 277.976477 -312.676433)
					(end 277.961598 -312.712354)
				)
			)
		)
	)
	(zone
		(layers "In1.Cu" "In2.Cu")
		(hatch none 0.5)
		(connect_pads
			(clearance 0)
		)
		(min_thickness 0.25)
		(keepout
			(tracks not_allowed)
			(vias allowed)
			(pads allowed)
			(copperpour not_allowed)
			(footprints allowed)
		)
		(placement
			(enabled no)
			(sheetname "")
		)
		(fill yes
			(thermal_gap 0.5)
			(thermal_bridge_width 0.5)
			(island_removal_mode 0)
		)
		(polygon
			(pts
				(arc
					(start 462.909666 -205.171548)
					(mid 462.924545 -205.207469)
					(end 462.960466 -205.222348)
				)
				(arc
					(start 464.360006 -205.222348)
					(mid 464.395927 -205.207469)
					(end 464.410806 -205.171548)
				)
				(arc
					(start 464.410806 -204.762608)
					(mid 464.395927 -204.726687)
					(end 464.360006 -204.711808)
				)
				(arc
					(start 462.960466 -204.711808)
					(mid 462.924545 -204.726687)
					(end 462.909666 -204.762608)
				)
			)
		)
	)
	(zone
		(layers "In1.Cu" "In2.Cu")
		(hatch none 0.5)
		(connect_pads
			(clearance 0)
		)
		(min_thickness 0.25)
		(keepout
			(tracks not_allowed)
			(vias allowed)
			(pads allowed)
			(copperpour not_allowed)
			(footprints allowed)
		)
		(placement
			(enabled no)
			(sheetname "")
		)
		(fill yes
			(thermal_gap 0.5)
			(thermal_bridge_width 0.5)
			(island_removal_mode 0)
		)
		(polygon
			(pts
				(arc
					(start 64.296798 -211.121498)
					(mid 64.311677 -211.157419)
					(end 64.347598 -211.172298)
				)
				(arc
					(start 65.747138 -211.172298)
					(mid 65.783059 -211.157419)
					(end 65.797938 -211.121498)
				)
				(arc
					(start 65.797938 -210.712558)
					(mid 65.783059 -210.676637)
					(end 65.747138 -210.661758)
				)
				(arc
					(start 64.347598 -210.661758)
					(mid 64.311677 -210.676637)
					(end 64.296798 -210.712558)
				)
			)
		)
	)
	(zone
		(layers "In1.Cu" "In2.Cu")
		(hatch none 0.5)
		(connect_pads
			(clearance 0)
		)
		(min_thickness 0.25)
		(keepout
			(tracks not_allowed)
			(vias allowed)
			(pads allowed)
			(copperpour not_allowed)
			(footprints allowed)
		)
		(placement
			(enabled no)
			(sheetname "")
		)
		(fill yes
			(thermal_gap 0.5)
			(thermal_bridge_width 0.5)
			(island_removal_mode 0)
		)
		(polygon
			(pts
				(arc
					(start 207.425798 -231.521508)
					(mid 207.440677 -231.557429)
					(end 207.476598 -231.572308)
				)
				(arc
					(start 208.876138 -231.572308)
					(mid 208.912059 -231.557429)
					(end 208.926938 -231.521508)
				)
				(arc
					(start 208.926938 -231.112568)
					(mid 208.912059 -231.076647)
					(end 208.876138 -231.061768)
				)
				(arc
					(start 207.476598 -231.061768)
					(mid 207.440677 -231.076647)
					(end 207.425798 -231.112568)
				)
			)
		)
	)
	(zone
		(layers "In1.Cu" "In2.Cu")
		(hatch none 0.5)
		(connect_pads
			(clearance 0)
		)
		(min_thickness 0.25)
		(keepout
			(tracks not_allowed)
			(vias allowed)
			(pads allowed)
			(copperpour not_allowed)
			(footprints allowed)
		)
		(placement
			(enabled no)
			(sheetname "")
		)
		(fill yes
			(thermal_gap 0.5)
			(thermal_bridge_width 0.5)
			(island_removal_mode 0)
		)
		(polygon
			(pts
				(arc
					(start 177.250598 -239.17148)
					(mid 177.265477 -239.207401)
					(end 177.301398 -239.22228)
				)
				(arc
					(start 178.700938 -239.22228)
					(mid 178.736859 -239.207401)
					(end 178.751738 -239.17148)
				)
				(arc
					(start 178.751738 -238.76254)
					(mid 178.736859 -238.726619)
					(end 178.700938 -238.71174)
				)
				(arc
					(start 177.301398 -238.71174)
					(mid 177.265477 -238.726619)
					(end 177.250598 -238.76254)
				)
			)
		)
	)
	(zone
		(layers "In1.Cu" "In2.Cu")
		(hatch none 0.5)
		(connect_pads
			(clearance 0)
		)
		(min_thickness 0.25)
		(keepout
			(tracks not_allowed)
			(vias allowed)
			(pads allowed)
			(copperpour not_allowed)
			(footprints allowed)
		)
		(placement
			(enabled no)
			(sheetname "")
		)
		(fill yes
			(thermal_gap 0.5)
			(thermal_bridge_width 0.5)
			(island_removal_mode 0)
		)
		(polygon
			(pts
				(arc
					(start 432.734466 -289.321494)
					(mid 432.749345 -289.357415)
					(end 432.785266 -289.372294)
				)
				(arc
					(start 434.184806 -289.372294)
					(mid 434.220727 -289.357415)
					(end 434.235606 -289.321494)
				)
				(arc
					(start 434.235606 -288.912554)
					(mid 434.220727 -288.876633)
					(end 434.184806 -288.861754)
				)
				(arc
					(start 432.785266 -288.861754)
					(mid 432.749345 -288.876633)
					(end 432.734466 -288.912554)
				)
			)
		)
	)
	(zone
		(layers "In1.Cu" "In2.Cu")
		(hatch none 0.5)
		(connect_pads
			(clearance 0)
		)
		(min_thickness 0.25)
		(keepout
			(tracks not_allowed)
			(vias allowed)
			(pads allowed)
			(copperpour not_allowed)
			(footprints allowed)
		)
		(placement
			(enabled no)
			(sheetname "")
		)
		(fill yes
			(thermal_gap 0.5)
			(thermal_bridge_width 0.5)
			(island_removal_mode 0)
		)
		(polygon
			(pts
				(arc
					(start 34.121598 -199.221344)
					(mid 34.136477 -199.257265)
					(end 34.172398 -199.272144)
				)
				(arc
					(start 35.571938 -199.272144)
					(mid 35.607859 -199.257265)
					(end 35.622738 -199.221344)
				)
				(arc
					(start 35.622738 -198.812404)
					(mid 35.607859 -198.776483)
					(end 35.571938 -198.761604)
				)
				(arc
					(start 34.172398 -198.761604)
					(mid 34.136477 -198.776483)
					(end 34.121598 -198.812404)
				)
			)
		)
	)
	(zone
		(layers "In1.Cu" "In2.Cu")
		(hatch none 0.5)
		(connect_pads
			(clearance 0)
		)
		(min_thickness 0.25)
		(keepout
			(tracks not_allowed)
			(vias allowed)
			(pads allowed)
			(copperpour not_allowed)
			(footprints allowed)
		)
		(placement
			(enabled no)
			(sheetname "")
		)
		(fill yes
			(thermal_gap 0.5)
			(thermal_bridge_width 0.5)
			(island_removal_mode 0)
		)
		(polygon
			(pts
				(arc
					(start 169.706798 -248.521474)
					(mid 169.721677 -248.557395)
					(end 169.757598 -248.572274)
				)
				(arc
					(start 171.157138 -248.572274)
					(mid 171.193059 -248.557395)
					(end 171.207938 -248.521474)
				)
				(arc
					(start 171.207938 -248.112534)
					(mid 171.193059 -248.076613)
					(end 171.157138 -248.061734)
				)
				(arc
					(start 169.757598 -248.061734)
					(mid 169.721677 -248.076613)
					(end 169.706798 -248.112534)
				)
			)
		)
	)
	(zone
		(layers "In1.Cu" "In2.Cu")
		(hatch none 0.5)
		(connect_pads
			(clearance 0)
		)
		(min_thickness 0.25)
		(keepout
			(tracks not_allowed)
			(vias allowed)
			(pads allowed)
			(copperpour not_allowed)
			(footprints allowed)
		)
		(placement
			(enabled no)
			(sheetname "")
		)
		(fill yes
			(thermal_gap 0.5)
			(thermal_bridge_width 0.5)
			(island_removal_mode 0)
		)
		(polygon
			(pts
				(arc
					(start 413.546798 -234.071414)
					(mid 413.561677 -234.107335)
					(end 413.597598 -234.122214)
				)
				(arc
					(start 414.997138 -234.122214)
					(mid 415.033059 -234.107335)
					(end 415.047938 -234.071414)
				)
				(arc
					(start 415.047938 -233.662474)
					(mid 415.033059 -233.626553)
					(end 414.997138 -233.611674)
				)
				(arc
					(start 413.597598 -233.611674)
					(mid 413.561677 -233.626553)
					(end 413.546798 -233.662474)
				)
			)
		)
	)
	(zone
		(layers "In1.Cu" "In2.Cu")
		(hatch none 0.5)
		(connect_pads
			(clearance 0)
		)
		(min_thickness 0.25)
		(keepout
			(tracks not_allowed)
			(vias allowed)
			(pads allowed)
			(copperpour not_allowed)
			(footprints allowed)
		)
		(placement
			(enabled no)
			(sheetname "")
		)
		(fill yes
			(thermal_gap 0.5)
			(thermal_bridge_width 0.5)
			(island_removal_mode 0)
		)
		(polygon
			(pts
				(arc
					(start 282.061666 -265.52144)
					(mid 282.076545 -265.557361)
					(end 282.112466 -265.57224)
				)
				(arc
					(start 283.512006 -265.57224)
					(mid 283.547927 -265.557361)
					(end 283.562806 -265.52144)
				)
				(arc
					(start 283.562806 -265.1125)
					(mid 283.547927 -265.076579)
					(end 283.512006 -265.0617)
				)
				(arc
					(start 282.112466 -265.0617)
					(mid 282.076545 -265.076579)
					(end 282.061666 -265.1125)
				)
			)
		)
	)
	(zone
		(layers "In1.Cu" "In2.Cu")
		(hatch none 0.5)
		(connect_pads
			(clearance 0)
		)
		(min_thickness 0.25)
		(keepout
			(tracks not_allowed)
			(vias allowed)
			(pads allowed)
			(copperpour not_allowed)
			(footprints allowed)
		)
		(placement
			(enabled no)
			(sheetname "")
		)
		(fill yes
			(thermal_gap 0.5)
			(thermal_bridge_width 0.5)
			(island_removal_mode 0)
		)
		(polygon
			(pts
				(arc
					(start 300.592998 -282.521406)
					(mid 300.607877 -282.557327)
					(end 300.643798 -282.572206)
				)
				(arc
					(start 302.043338 -282.572206)
					(mid 302.079259 -282.557327)
					(end 302.094138 -282.521406)
				)
				(arc
					(start 302.094138 -282.112466)
					(mid 302.079259 -282.076545)
					(end 302.043338 -282.061666)
				)
				(arc
					(start 300.643798 -282.061666)
					(mid 300.607877 -282.076545)
					(end 300.592998 -282.112466)
				)
			)
		)
	)
	(zone
		(layers "In1.Cu" "In2.Cu")
		(hatch none 0.5)
		(connect_pads
			(clearance 0)
		)
		(min_thickness 0.25)
		(keepout
			(tracks not_allowed)
			(vias allowed)
			(pads allowed)
			(copperpour not_allowed)
			(footprints allowed)
		)
		(placement
			(enabled no)
			(sheetname "")
		)
		(fill yes
			(thermal_gap 0.5)
			(thermal_bridge_width 0.5)
			(island_removal_mode 0)
		)
		(polygon
			(pts
				(arc
					(start 26.577798 -197.521322)
					(mid 26.592677 -197.557243)
					(end 26.628598 -197.572122)
				)
				(arc
					(start 28.028138 -197.572122)
					(mid 28.064059 -197.557243)
					(end 28.078938 -197.521322)
				)
				(arc
					(start 28.078938 -197.112382)
					(mid 28.064059 -197.076461)
					(end 28.028138 -197.061582)
				)
				(arc
					(start 26.628598 -197.061582)
					(mid 26.592677 -197.076461)
					(end 26.577798 -197.112382)
				)
			)
		)
	)
	(zone
		(layers "In1.Cu" "In2.Cu")
		(hatch none 0.5)
		(connect_pads
			(clearance 0)
		)
		(min_thickness 0.25)
		(keepout
			(tracks not_allowed)
			(vias allowed)
			(pads allowed)
			(copperpour not_allowed)
			(footprints allowed)
		)
		(placement
			(enabled no)
			(sheetname "")
		)
		(fill yes
			(thermal_gap 0.5)
			(thermal_bridge_width 0.5)
			(island_removal_mode 0)
		)
		(polygon
			(pts
				(arc
					(start 177.250598 -313.971432)
					(mid 177.265477 -314.007353)
					(end 177.301398 -314.022232)
				)
				(arc
					(start 178.700938 -314.022232)
					(mid 178.736859 -314.007353)
					(end 178.751738 -313.971432)
				)
				(arc
					(start 178.751738 -313.562492)
					(mid 178.736859 -313.526571)
					(end 178.700938 -313.511692)
				)
				(arc
					(start 177.301398 -313.511692)
					(mid 177.265477 -313.526571)
					(end 177.250598 -313.562492)
				)
			)
		)
	)
	(zone
		(layers "In1.Cu" "In2.Cu")
		(hatch none 0.5)
		(connect_pads
			(clearance 0)
		)
		(min_thickness 0.25)
		(keepout
			(tracks not_allowed)
			(vias allowed)
			(pads allowed)
			(copperpour not_allowed)
			(footprints allowed)
		)
		(placement
			(enabled no)
			(sheetname "")
		)
		(fill yes
			(thermal_gap 0.5)
			(thermal_bridge_width 0.5)
			(island_removal_mode 0)
		)
		(polygon
			(pts
				(arc
					(start 436.178198 -230.67137)
					(mid 436.193077 -230.707291)
					(end 436.228998 -230.72217)
				)
				(arc
					(start 437.628538 -230.72217)
					(mid 437.664459 -230.707291)
					(end 437.679338 -230.67137)
				)
				(arc
					(start 437.679338 -230.26243)
					(mid 437.664459 -230.226509)
					(end 437.628538 -230.21163)
				)
				(arc
					(start 436.228998 -230.21163)
					(mid 436.193077 -230.226509)
					(end 436.178198 -230.26243)
				)
			)
		)
	)
	(zone
		(layers "In1.Cu" "In2.Cu")
		(hatch none 0.5)
		(connect_pads
			(clearance 0)
		)
		(min_thickness 0.25)
		(keepout
			(tracks not_allowed)
			(vias allowed)
			(pads allowed)
			(copperpour not_allowed)
			(footprints allowed)
		)
		(placement
			(enabled no)
			(sheetname "")
		)
		(fill yes
			(thermal_gap 0.5)
			(thermal_bridge_width 0.5)
			(island_removal_mode 0)
		)
		(polygon
			(pts
				(arc
					(start 432.734466 -296.971466)
					(mid 432.749345 -297.007387)
					(end 432.785266 -297.022266)
				)
				(arc
					(start 434.184806 -297.022266)
					(mid 434.220727 -297.007387)
					(end 434.235606 -296.971466)
				)
				(arc
					(start 434.235606 -296.562526)
					(mid 434.220727 -296.526605)
					(end 434.184806 -296.511726)
				)
				(arc
					(start 432.785266 -296.511726)
					(mid 432.749345 -296.526605)
					(end 432.734466 -296.562526)
				)
			)
		)
	)
	(zone
		(layers "In1.Cu" "In2.Cu")
		(hatch none 0.5)
		(connect_pads
			(clearance 0)
		)
		(min_thickness 0.25)
		(keepout
			(tracks not_allowed)
			(vias allowed)
			(pads allowed)
			(copperpour not_allowed)
			(footprints allowed)
		)
		(placement
			(enabled no)
			(sheetname "")
		)
		(fill yes
			(thermal_gap 0.5)
			(thermal_bridge_width 0.5)
			(island_removal_mode 0)
		)
		(polygon
			(pts
				(arc
					(start 293.049198 -302.921416)
					(mid 293.064077 -302.957337)
					(end 293.099998 -302.972216)
				)
				(arc
					(start 294.499538 -302.972216)
					(mid 294.535459 -302.957337)
					(end 294.550338 -302.921416)
				)
				(arc
					(start 294.550338 -302.512476)
					(mid 294.535459 -302.476555)
					(end 294.499538 -302.461676)
				)
				(arc
					(start 293.099998 -302.461676)
					(mid 293.064077 -302.476555)
					(end 293.049198 -302.512476)
				)
			)
		)
	)
	(zone
		(layers "In1.Cu" "In2.Cu")
		(hatch none 0.5)
		(connect_pads
			(clearance 0)
		)
		(min_thickness 0.25)
		(keepout
			(tracks not_allowed)
			(vias allowed)
			(pads allowed)
			(copperpour not_allowed)
			(footprints allowed)
		)
		(placement
			(enabled no)
			(sheetname "")
		)
		(fill yes
			(thermal_gap 0.5)
			(thermal_bridge_width 0.5)
			(island_removal_mode 0)
		)
		(polygon
			(pts
				(arc
					(start 207.425798 -222.171514)
					(mid 207.440677 -222.207435)
					(end 207.476598 -222.222314)
				)
				(arc
					(start 208.876138 -222.222314)
					(mid 208.912059 -222.207435)
					(end 208.926938 -222.171514)
				)
				(arc
					(start 208.926938 -221.762574)
					(mid 208.912059 -221.726653)
					(end 208.876138 -221.711774)
				)
				(arc
					(start 207.476598 -221.711774)
					(mid 207.440677 -221.726653)
					(end 207.425798 -221.762574)
				)
			)
		)
	)
	(zone
		(layers "In1.Cu" "In2.Cu")
		(hatch none 0.5)
		(connect_pads
			(clearance 0)
		)
		(min_thickness 0.25)
		(keepout
			(tracks not_allowed)
			(vias allowed)
			(pads allowed)
			(copperpour not_allowed)
			(footprints allowed)
		)
		(placement
			(enabled no)
			(sheetname "")
		)
		(fill yes
			(thermal_gap 0.5)
			(thermal_bridge_width 0.5)
			(island_removal_mode 0)
		)
		(polygon
			(pts
				(arc
					(start 297.149266 -315.671454)
					(mid 297.164145 -315.707375)
					(end 297.200066 -315.722254)
				)
				(arc
					(start 298.599606 -315.722254)
					(mid 298.635527 -315.707375)
					(end 298.650406 -315.671454)
				)
				(arc
					(start 298.650406 -315.262514)
					(mid 298.635527 -315.226593)
					(end 298.599606 -315.211714)
				)
				(arc
					(start 297.200066 -315.211714)
					(mid 297.164145 -315.226593)
					(end 297.149266 -315.262514)
				)
			)
		)
	)
	(zone
		(layers "In1.Cu" "In2.Cu")
		(hatch none 0.5)
		(connect_pads
			(clearance 0)
		)
		(min_thickness 0.25)
		(keepout
			(tracks not_allowed)
			(vias allowed)
			(pads allowed)
			(copperpour not_allowed)
			(footprints allowed)
		)
		(placement
			(enabled no)
			(sheetname "")
		)
		(fill yes
			(thermal_gap 0.5)
			(thermal_bridge_width 0.5)
			(island_removal_mode 0)
		)
		(polygon
			(pts
				(arc
					(start 417.646866 -234.921298)
					(mid 417.661745 -234.957219)
					(end 417.697666 -234.972098)
				)
				(arc
					(start 419.097206 -234.972098)
					(mid 419.133127 -234.957219)
					(end 419.148006 -234.921298)
				)
				(arc
					(start 419.148006 -234.512358)
					(mid 419.133127 -234.476437)
					(end 419.097206 -234.461558)
				)
				(arc
					(start 417.697666 -234.461558)
					(mid 417.661745 -234.476437)
					(end 417.646866 -234.512358)
				)
			)
		)
	)
	(zone
		(layers "In1.Cu" "In2.Cu")
		(hatch none 0.5)
		(connect_pads
			(clearance 0)
		)
		(min_thickness 0.25)
		(keepout
			(tracks not_allowed)
			(vias allowed)
			(pads allowed)
			(copperpour not_allowed)
			(footprints allowed)
		)
		(placement
			(enabled no)
			(sheetname "")
		)
		(fill yes
			(thermal_gap 0.5)
			(thermal_bridge_width 0.5)
			(island_removal_mode 0)
		)
		(polygon
			(pts
				(arc
					(start 425.190666 -315.671454)
					(mid 425.205545 -315.707375)
					(end 425.241466 -315.722254)
				)
				(arc
					(start 426.641006 -315.722254)
					(mid 426.676927 -315.707375)
					(end 426.691806 -315.671454)
				)
				(arc
					(start 426.691806 -315.262514)
					(mid 426.676927 -315.226593)
					(end 426.641006 -315.211714)
				)
				(arc
					(start 425.241466 -315.211714)
					(mid 425.205545 -315.226593)
					(end 425.190666 -315.262514)
				)
			)
		)
	)
	(zone
		(layers "In1.Cu" "In2.Cu")
		(hatch none 0.5)
		(connect_pads
			(clearance 0)
		)
		(min_thickness 0.25)
		(keepout
			(tracks not_allowed)
			(vias allowed)
			(pads allowed)
			(copperpour not_allowed)
			(footprints allowed)
		)
		(placement
			(enabled no)
			(sheetname "")
		)
		(fill yes
			(thermal_gap 0.5)
			(thermal_bridge_width 0.5)
			(island_removal_mode 0)
		)
		(polygon
			(pts
				(arc
					(start 406.002998 -282.521406)
					(mid 406.017877 -282.557327)
					(end 406.053798 -282.572206)
				)
				(arc
					(start 407.453338 -282.572206)
					(mid 407.489259 -282.557327)
					(end 407.504138 -282.521406)
				)
				(arc
					(start 407.504138 -282.112466)
					(mid 407.489259 -282.076545)
					(end 407.453338 -282.061666)
				)
				(arc
					(start 406.053798 -282.061666)
					(mid 406.017877 -282.076545)
					(end 406.002998 -282.112466)
				)
			)
		)
	)
	(zone
		(layers "In1.Cu" "In2.Cu")
		(hatch none 0.5)
		(connect_pads
			(clearance 0)
		)
		(min_thickness 0.25)
		(keepout
			(tracks not_allowed)
			(vias allowed)
			(pads allowed)
			(copperpour not_allowed)
			(footprints allowed)
		)
		(placement
			(enabled no)
			(sheetname "")
		)
		(fill yes
			(thermal_gap 0.5)
			(thermal_bridge_width 0.5)
			(island_removal_mode 0)
		)
		(polygon
			(pts
				(arc
					(start 56.752998 -228.121464)
					(mid 56.767877 -228.157385)
					(end 56.803798 -228.172264)
				)
				(arc
					(start 58.203338 -228.172264)
					(mid 58.239259 -228.157385)
					(end 58.254138 -228.121464)
				)
				(arc
					(start 58.254138 -227.712524)
					(mid 58.239259 -227.676603)
					(end 58.203338 -227.661724)
				)
				(arc
					(start 56.803798 -227.661724)
					(mid 56.767877 -227.676603)
					(end 56.752998 -227.712524)
				)
			)
		)
	)
	(zone
		(layers "In1.Cu" "In2.Cu")
		(hatch none 0.5)
		(connect_pads
			(clearance 0)
		)
		(min_thickness 0.25)
		(keepout
			(tracks not_allowed)
			(vias allowed)
			(pads allowed)
			(copperpour not_allowed)
			(footprints allowed)
		)
		(placement
			(enabled no)
			(sheetname "")
		)
		(fill yes
			(thermal_gap 0.5)
			(thermal_bridge_width 0.5)
			(island_removal_mode 0)
		)
		(polygon
			(pts
				(arc
					(start 270.417798 -240.021364)
					(mid 270.432677 -240.057285)
					(end 270.468598 -240.072164)
				)
				(arc
					(start 271.868138 -240.072164)
					(mid 271.904059 -240.057285)
					(end 271.918938 -240.021364)
				)
				(arc
					(start 271.918938 -239.612424)
					(mid 271.904059 -239.576503)
					(end 271.868138 -239.561624)
				)
				(arc
					(start 270.468598 -239.561624)
					(mid 270.432677 -239.576503)
					(end 270.417798 -239.612424)
				)
			)
		)
	)
	(zone
		(layers "In1.Cu" "In2.Cu")
		(hatch none 0.5)
		(connect_pads
			(clearance 0)
		)
		(min_thickness 0.25)
		(keepout
			(tracks not_allowed)
			(vias allowed)
			(pads allowed)
			(copperpour not_allowed)
			(footprints allowed)
		)
		(placement
			(enabled no)
			(sheetname "")
		)
		(fill yes
			(thermal_gap 0.5)
			(thermal_bridge_width 0.5)
			(island_removal_mode 0)
		)
		(polygon
			(pts
				(arc
					(start 169.706798 -250.221496)
					(mid 169.721677 -250.257417)
					(end 169.757598 -250.272296)
				)
				(arc
					(start 171.157138 -250.272296)
					(mid 171.193059 -250.257417)
					(end 171.207938 -250.221496)
				)
				(arc
					(start 171.207938 -249.812556)
					(mid 171.193059 -249.776635)
					(end 171.157138 -249.761756)
				)
				(arc
					(start 169.757598 -249.761756)
					(mid 169.721677 -249.776635)
					(end 169.706798 -249.812556)
				)
			)
		)
	)
	(zone
		(layers "In1.Cu" "In2.Cu")
		(hatch none 0.5)
		(connect_pads
			(clearance 0)
		)
		(min_thickness 0.25)
		(keepout
			(tracks not_allowed)
			(vias allowed)
			(pads allowed)
			(copperpour not_allowed)
			(footprints allowed)
		)
		(placement
			(enabled no)
			(sheetname "")
		)
		(fill yes
			(thermal_gap 0.5)
			(thermal_bridge_width 0.5)
			(island_removal_mode 0)
		)
		(polygon
			(pts
				(arc
					(start 34.121598 -302.921416)
					(mid 34.136477 -302.957337)
					(end 34.172398 -302.972216)
				)
				(arc
					(start 35.571938 -302.972216)
					(mid 35.607859 -302.957337)
					(end 35.622738 -302.921416)
				)
				(arc
					(start 35.622738 -302.512476)
					(mid 35.607859 -302.476555)
					(end 35.571938 -302.461676)
				)
				(arc
					(start 34.172398 -302.461676)
					(mid 34.136477 -302.476555)
					(end 34.121598 -302.512476)
				)
			)
		)
	)
	(zone
		(layers "In1.Cu" "In2.Cu")
		(hatch none 0.5)
		(connect_pads
			(clearance 0)
		)
		(min_thickness 0.25)
		(keepout
			(tracks not_allowed)
			(vias allowed)
			(pads allowed)
			(copperpour not_allowed)
			(footprints allowed)
		)
		(placement
			(enabled no)
			(sheetname "")
		)
		(fill yes
			(thermal_gap 0.5)
			(thermal_bridge_width 0.5)
			(island_removal_mode 0)
		)
		(polygon
			(pts
				(arc
					(start 285.505398 -264.671302)
					(mid 285.520277 -264.707223)
					(end 285.556198 -264.722102)
				)
				(arc
					(start 286.955738 -264.722102)
					(mid 286.991659 -264.707223)
					(end 287.006538 -264.671302)
				)
				(arc
					(start 287.006538 -264.262362)
					(mid 286.991659 -264.226441)
					(end 286.955738 -264.211562)
				)
				(arc
					(start 285.556198 -264.211562)
					(mid 285.520277 -264.226441)
					(end 285.505398 -264.262362)
				)
			)
		)
	)
	(zone
		(layers "In1.Cu" "In2.Cu")
		(hatch none 0.5)
		(connect_pads
			(clearance 0)
		)
		(min_thickness 0.25)
		(keepout
			(tracks not_allowed)
			(vias allowed)
			(pads allowed)
			(copperpour not_allowed)
			(footprints allowed)
		)
		(placement
			(enabled no)
			(sheetname "")
		)
		(fill yes
			(thermal_gap 0.5)
			(thermal_bridge_width 0.5)
			(island_removal_mode 0)
		)
		(polygon
			(pts
				(arc
					(start 436.178198 -235.771436)
					(mid 436.193077 -235.807357)
					(end 436.228998 -235.822236)
				)
				(arc
					(start 437.628538 -235.822236)
					(mid 437.664459 -235.807357)
					(end 437.679338 -235.771436)
				)
				(arc
					(start 437.679338 -235.362496)
					(mid 437.664459 -235.326575)
					(end 437.628538 -235.311696)
				)
				(arc
					(start 436.228998 -235.311696)
					(mid 436.193077 -235.326575)
					(end 436.178198 -235.362496)
				)
			)
		)
	)
	(zone
		(layers "In1.Cu" "In2.Cu")
		(hatch none 0.5)
		(connect_pads
			(clearance 0)
		)
		(min_thickness 0.25)
		(keepout
			(tracks not_allowed)
			(vias allowed)
			(pads allowed)
			(copperpour not_allowed)
			(footprints allowed)
		)
		(placement
			(enabled no)
			(sheetname "")
		)
		(fill yes
			(thermal_gap 0.5)
			(thermal_bridge_width 0.5)
			(island_removal_mode 0)
		)
		(polygon
			(pts
				(arc
					(start 425.190666 -291.021516)
					(mid 425.205545 -291.057437)
					(end 425.241466 -291.072316)
				)
				(arc
					(start 426.641006 -291.072316)
					(mid 426.676927 -291.057437)
					(end 426.691806 -291.021516)
				)
				(arc
					(start 426.691806 -290.612576)
					(mid 426.676927 -290.576655)
					(end 426.641006 -290.561776)
				)
				(arc
					(start 425.241466 -290.561776)
					(mid 425.205545 -290.576655)
					(end 425.190666 -290.612576)
				)
			)
		)
	)
	(zone
		(layers "In1.Cu" "In2.Cu")
		(hatch none 0.5)
		(connect_pads
			(clearance 0)
		)
		(min_thickness 0.25)
		(keepout
			(tracks not_allowed)
			(vias allowed)
			(pads allowed)
			(copperpour not_allowed)
			(footprints allowed)
		)
		(placement
			(enabled no)
			(sheetname "")
		)
		(fill yes
			(thermal_gap 0.5)
			(thermal_bridge_width 0.5)
			(island_removal_mode 0)
		)
		(polygon
			(pts
				(arc
					(start 270.417798 -234.071414)
					(mid 270.432677 -234.107335)
					(end 270.468598 -234.122214)
				)
				(arc
					(start 271.868138 -234.122214)
					(mid 271.904059 -234.107335)
					(end 271.918938 -234.071414)
				)
				(arc
					(start 271.918938 -233.662474)
					(mid 271.904059 -233.626553)
					(end 271.868138 -233.611674)
				)
				(arc
					(start 270.468598 -233.611674)
					(mid 270.432677 -233.626553)
					(end 270.417798 -233.662474)
				)
			)
		)
	)
	(zone
		(layers "In1.Cu" "In2.Cu")
		(hatch none 0.5)
		(connect_pads
			(clearance 0)
		)
		(min_thickness 0.25)
		(keepout
			(tracks not_allowed)
			(vias allowed)
			(pads allowed)
			(copperpour not_allowed)
			(footprints allowed)
		)
		(placement
			(enabled no)
			(sheetname "")
		)
		(fill yes
			(thermal_gap 0.5)
			(thermal_bridge_width 0.5)
			(island_removal_mode 0)
		)
		(polygon
			(pts
				(arc
					(start 293.049198 -223.021398)
					(mid 293.064077 -223.057319)
					(end 293.099998 -223.072198)
				)
				(arc
					(start 294.499538 -223.072198)
					(mid 294.535459 -223.057319)
					(end 294.550338 -223.021398)
				)
				(arc
					(start 294.550338 -222.612458)
					(mid 294.535459 -222.576537)
					(end 294.499538 -222.561658)
				)
				(arc
					(start 293.099998 -222.561658)
					(mid 293.064077 -222.576537)
					(end 293.049198 -222.612458)
				)
			)
		)
	)
	(zone
		(layers "In1.Cu" "In2.Cu")
		(hatch none 0.5)
		(connect_pads
			(clearance 0)
		)
		(min_thickness 0.25)
		(keepout
			(tracks not_allowed)
			(vias allowed)
			(pads allowed)
			(copperpour not_allowed)
			(footprints allowed)
		)
		(placement
			(enabled no)
			(sheetname "")
		)
		(fill yes
			(thermal_gap 0.5)
			(thermal_bridge_width 0.5)
			(island_removal_mode 0)
		)
		(polygon
			(pts
				(arc
					(start 270.417798 -302.921416)
					(mid 270.432677 -302.957337)
					(end 270.468598 -302.972216)
				)
				(arc
					(start 271.868138 -302.972216)
					(mid 271.904059 -302.957337)
					(end 271.918938 -302.921416)
				)
				(arc
					(start 271.918938 -302.512476)
					(mid 271.904059 -302.476555)
					(end 271.868138 -302.461676)
				)
				(arc
					(start 270.468598 -302.461676)
					(mid 270.432677 -302.476555)
					(end 270.417798 -302.512476)
				)
			)
		)
	)
	(zone
		(layers "In1.Cu" "In2.Cu")
		(hatch none 0.5)
		(connect_pads
			(clearance 0)
		)
		(min_thickness 0.25)
		(keepout
			(tracks not_allowed)
			(vias allowed)
			(pads allowed)
			(copperpour not_allowed)
			(footprints allowed)
		)
		(placement
			(enabled no)
			(sheetname "")
		)
		(fill yes
			(thermal_gap 0.5)
			(thermal_bridge_width 0.5)
			(island_removal_mode 0)
		)
		(polygon
			(pts
				(arc
					(start 177.250598 -267.221462)
					(mid 177.265477 -267.257383)
					(end 177.301398 -267.272262)
				)
				(arc
					(start 178.700938 -267.272262)
					(mid 178.736859 -267.257383)
					(end 178.751738 -267.221462)
				)
				(arc
					(start 178.751738 -266.812522)
					(mid 178.736859 -266.776601)
					(end 178.700938 -266.761722)
				)
				(arc
					(start 177.301398 -266.761722)
					(mid 177.265477 -266.776601)
					(end 177.250598 -266.812522)
				)
			)
		)
	)
	(zone
		(layers "In1.Cu" "In2.Cu")
		(hatch none 0.5)
		(connect_pads
			(clearance 0)
		)
		(min_thickness 0.25)
		(keepout
			(tracks not_allowed)
			(vias allowed)
			(pads allowed)
			(copperpour not_allowed)
			(footprints allowed)
		)
		(placement
			(enabled no)
			(sheetname "")
		)
		(fill yes
			(thermal_gap 0.5)
			(thermal_bridge_width 0.5)
			(island_removal_mode 0)
		)
		(polygon
			(pts
				(arc
					(start 436.178198 -280.821384)
					(mid 436.193077 -280.857305)
					(end 436.228998 -280.872184)
				)
				(arc
					(start 437.628538 -280.872184)
					(mid 437.664459 -280.857305)
					(end 437.679338 -280.821384)
				)
				(arc
					(start 437.679338 -280.412444)
					(mid 437.664459 -280.376523)
					(end 437.628538 -280.361644)
				)
				(arc
					(start 436.228998 -280.361644)
					(mid 436.193077 -280.376523)
					(end 436.178198 -280.412444)
				)
			)
		)
	)
	(zone
		(layers "In1.Cu" "In2.Cu")
		(hatch none 0.5)
		(connect_pads
			(clearance 0)
		)
		(min_thickness 0.25)
		(keepout
			(tracks not_allowed)
			(vias allowed)
			(pads allowed)
			(copperpour not_allowed)
			(footprints allowed)
		)
		(placement
			(enabled no)
			(sheetname "")
		)
		(fill yes
			(thermal_gap 0.5)
			(thermal_bridge_width 0.5)
			(island_removal_mode 0)
		)
		(polygon
			(pts
				(arc
					(start 406.002998 -290.171378)
					(mid 406.017877 -290.207299)
					(end 406.053798 -290.222178)
				)
				(arc
					(start 407.453338 -290.222178)
					(mid 407.489259 -290.207299)
					(end 407.504138 -290.171378)
				)
				(arc
					(start 407.504138 -289.762438)
					(mid 407.489259 -289.726517)
					(end 407.453338 -289.711638)
				)
				(arc
					(start 406.053798 -289.711638)
					(mid 406.017877 -289.726517)
					(end 406.002998 -289.762438)
				)
			)
		)
	)
	(zone
		(layers "In1.Cu" "In2.Cu")
		(hatch none 0.5)
		(connect_pads
			(clearance 0)
		)
		(min_thickness 0.25)
		(keepout
			(tracks not_allowed)
			(vias allowed)
			(pads allowed)
			(copperpour not_allowed)
			(footprints allowed)
		)
		(placement
			(enabled no)
			(sheetname "")
		)
		(fill yes
			(thermal_gap 0.5)
			(thermal_bridge_width 0.5)
			(island_removal_mode 0)
		)
		(polygon
			(pts
				(arc
					(start 312.236866 -234.921298)
					(mid 312.251745 -234.957219)
					(end 312.287666 -234.972098)
				)
				(arc
					(start 313.687206 -234.972098)
					(mid 313.723127 -234.957219)
					(end 313.738006 -234.921298)
				)
				(arc
					(start 313.738006 -234.512358)
					(mid 313.723127 -234.476437)
					(end 313.687206 -234.461558)
				)
				(arc
					(start 312.287666 -234.461558)
					(mid 312.251745 -234.476437)
					(end 312.236866 -234.512358)
				)
			)
		)
	)
	(zone
		(layers "In1.Cu" "In2.Cu")
		(hatch none 0.5)
		(connect_pads
			(clearance 0)
		)
		(min_thickness 0.25)
		(keepout
			(tracks not_allowed)
			(vias allowed)
			(pads allowed)
			(copperpour not_allowed)
			(footprints allowed)
		)
		(placement
			(enabled no)
			(sheetname "")
		)
		(fill yes
			(thermal_gap 0.5)
			(thermal_bridge_width 0.5)
			(island_removal_mode 0)
		)
		(polygon
			(pts
				(arc
					(start 308.136798 -286.771334)
					(mid 308.151677 -286.807255)
					(end 308.187598 -286.822134)
				)
				(arc
					(start 309.587138 -286.822134)
					(mid 309.623059 -286.807255)
					(end 309.637938 -286.771334)
				)
				(arc
					(start 309.637938 -286.362394)
					(mid 309.623059 -286.326473)
					(end 309.587138 -286.311594)
				)
				(arc
					(start 308.187598 -286.311594)
					(mid 308.151677 -286.326473)
					(end 308.136798 -286.362394)
				)
			)
		)
	)
	(zone
		(layers "In1.Cu" "In2.Cu")
		(hatch none 0.5)
		(connect_pads
			(clearance 0)
		)
		(min_thickness 0.25)
		(keepout
			(tracks not_allowed)
			(vias allowed)
			(pads allowed)
			(copperpour not_allowed)
			(footprints allowed)
		)
		(placement
			(enabled no)
			(sheetname "")
		)
		(fill yes
			(thermal_gap 0.5)
			(thermal_bridge_width 0.5)
			(island_removal_mode 0)
		)
		(polygon
			(pts
				(arc
					(start 184.794398 -292.721538)
					(mid 184.809277 -292.757459)
					(end 184.845198 -292.772338)
				)
				(arc
					(start 186.244738 -292.772338)
					(mid 186.280659 -292.757459)
					(end 186.295538 -292.721538)
				)
				(arc
					(start 186.295538 -292.312598)
					(mid 186.280659 -292.276677)
					(end 186.244738 -292.261798)
				)
				(arc
					(start 184.845198 -292.261798)
					(mid 184.809277 -292.276677)
					(end 184.794398 -292.312598)
				)
			)
		)
	)
	(zone
		(layers "In1.Cu" "In2.Cu")
		(hatch none 0.5)
		(connect_pads
			(clearance 0)
		)
		(min_thickness 0.25)
		(keepout
			(tracks not_allowed)
			(vias allowed)
			(pads allowed)
			(copperpour not_allowed)
			(footprints allowed)
		)
		(placement
			(enabled no)
			(sheetname "")
		)
		(fill yes
			(thermal_gap 0.5)
			(thermal_bridge_width 0.5)
			(island_removal_mode 0)
		)
		(polygon
			(pts
				(arc
					(start 462.909666 -302.921416)
					(mid 462.924545 -302.957337)
					(end 462.960466 -302.972216)
				)
				(arc
					(start 464.360006 -302.972216)
					(mid 464.395927 -302.957337)
					(end 464.410806 -302.921416)
				)
				(arc
					(start 464.410806 -302.512476)
					(mid 464.395927 -302.476555)
					(end 464.360006 -302.461676)
				)
				(arc
					(start 462.960466 -302.461676)
					(mid 462.924545 -302.476555)
					(end 462.909666 -302.512476)
				)
			)
		)
	)
	(zone
		(layers "In1.Cu" "In2.Cu")
		(hatch none 0.5)
		(connect_pads
			(clearance 0)
		)
		(min_thickness 0.25)
		(keepout
			(tracks not_allowed)
			(vias allowed)
			(pads allowed)
			(copperpour not_allowed)
			(footprints allowed)
		)
		(placement
			(enabled no)
			(sheetname "")
		)
		(fill yes
			(thermal_gap 0.5)
			(thermal_bridge_width 0.5)
			(island_removal_mode 0)
		)
		(polygon
			(pts
				(arc
					(start 14.93393 -290.171378)
					(mid 14.948809 -290.207299)
					(end 14.98473 -290.222178)
				)
				(arc
					(start 16.38427 -290.222178)
					(mid 16.420191 -290.207299)
					(end 16.43507 -290.171378)
				)
				(arc
					(start 16.43507 -289.762438)
					(mid 16.420191 -289.726517)
					(end 16.38427 -289.711638)
				)
				(arc
					(start 14.98473 -289.711638)
					(mid 14.948809 -289.726517)
					(end 14.93393 -289.762438)
				)
			)
		)
	)
	(zone
		(layers "In1.Cu" "In2.Cu")
		(hatch none 0.5)
		(connect_pads
			(clearance 0)
		)
		(min_thickness 0.25)
		(keepout
			(tracks not_allowed)
			(vias allowed)
			(pads allowed)
			(copperpour not_allowed)
			(footprints allowed)
		)
		(placement
			(enabled no)
			(sheetname "")
		)
		(fill yes
			(thermal_gap 0.5)
			(thermal_bridge_width 0.5)
			(island_removal_mode 0)
		)
		(polygon
			(pts
				(arc
					(start 451.265798 -313.121294)
					(mid 451.280677 -313.157215)
					(end 451.316598 -313.172094)
				)
				(arc
					(start 452.716138 -313.172094)
					(mid 452.752059 -313.157215)
					(end 452.766938 -313.121294)
				)
				(arc
					(start 452.766938 -312.712354)
					(mid 452.752059 -312.676433)
					(end 452.716138 -312.661554)
				)
				(arc
					(start 451.316598 -312.661554)
					(mid 451.280677 -312.676433)
					(end 451.265798 -312.712354)
				)
			)
		)
	)
	(zone
		(layers "In1.Cu" "In2.Cu")
		(hatch none 0.5)
		(connect_pads
			(clearance 0)
		)
		(min_thickness 0.25)
		(keepout
			(tracks not_allowed)
			(vias allowed)
			(pads allowed)
			(copperpour not_allowed)
			(footprints allowed)
		)
		(placement
			(enabled no)
			(sheetname "")
		)
		(fill yes
			(thermal_gap 0.5)
			(thermal_bridge_width 0.5)
			(island_removal_mode 0)
		)
		(polygon
			(pts
				(arc
					(start 259.430266 -295.271444)
					(mid 259.445145 -295.307365)
					(end 259.481066 -295.322244)
				)
				(arc
					(start 260.880606 -295.322244)
					(mid 260.916527 -295.307365)
					(end 260.931406 -295.271444)
				)
				(arc
					(start 260.931406 -294.862504)
					(mid 260.916527 -294.826583)
					(end 260.880606 -294.811704)
				)
				(arc
					(start 259.481066 -294.811704)
					(mid 259.445145 -294.826583)
					(end 259.430266 -294.862504)
				)
			)
		)
	)
	(zone
		(layers "In1.Cu" "In2.Cu")
		(hatch none 0.5)
		(connect_pads
			(clearance 0)
		)
		(min_thickness 0.25)
		(keepout
			(tracks not_allowed)
			(vias allowed)
			(pads allowed)
			(copperpour not_allowed)
			(footprints allowed)
		)
		(placement
			(enabled no)
			(sheetname "")
		)
		(fill yes
			(thermal_gap 0.5)
			(thermal_bridge_width 0.5)
			(island_removal_mode 0)
		)
		(polygon
			(pts
				(arc
					(start 52.65293 -237.471458)
					(mid 52.667809 -237.507379)
					(end 52.70373 -237.522258)
				)
				(arc
					(start 54.10327 -237.522258)
					(mid 54.139191 -237.507379)
					(end 54.15407 -237.471458)
				)
				(arc
					(start 54.15407 -237.062518)
					(mid 54.139191 -237.026597)
					(end 54.10327 -237.011718)
				)
				(arc
					(start 52.70373 -237.011718)
					(mid 52.667809 -237.026597)
					(end 52.65293 -237.062518)
				)
			)
		)
	)
	(zone
		(layers "In1.Cu" "In2.Cu")
		(hatch none 0.5)
		(connect_pads
			(clearance 0)
		)
		(min_thickness 0.25)
		(keepout
			(tracks not_allowed)
			(vias allowed)
			(pads allowed)
			(copperpour not_allowed)
			(footprints allowed)
		)
		(placement
			(enabled no)
			(sheetname "")
		)
		(fill yes
			(thermal_gap 0.5)
			(thermal_bridge_width 0.5)
			(island_removal_mode 0)
		)
		(polygon
			(pts
				(arc
					(start 56.752998 -309.721504)
					(mid 56.767877 -309.757425)
					(end 56.803798 -309.772304)
				)
				(arc
					(start 58.203338 -309.772304)
					(mid 58.239259 -309.757425)
					(end 58.254138 -309.721504)
				)
				(arc
					(start 58.254138 -309.312564)
					(mid 58.239259 -309.276643)
					(end 58.203338 -309.261764)
				)
				(arc
					(start 56.803798 -309.261764)
					(mid 56.767877 -309.276643)
					(end 56.752998 -309.312564)
				)
			)
		)
	)
	(zone
		(layers "In1.Cu" "In2.Cu")
		(hatch none 0.5)
		(connect_pads
			(clearance 0)
		)
		(min_thickness 0.25)
		(keepout
			(tracks not_allowed)
			(vias allowed)
			(pads allowed)
			(copperpour not_allowed)
			(footprints allowed)
		)
		(placement
			(enabled no)
			(sheetname "")
		)
		(fill yes
			(thermal_gap 0.5)
			(thermal_bridge_width 0.5)
			(island_removal_mode 0)
		)
		(polygon
			(pts
				(arc
					(start 308.136798 -301.221394)
					(mid 308.151677 -301.257315)
					(end 308.187598 -301.272194)
				)
				(arc
					(start 309.587138 -301.272194)
					(mid 309.623059 -301.257315)
					(end 309.637938 -301.221394)
				)
				(arc
					(start 309.637938 -300.812454)
					(mid 309.623059 -300.776533)
					(end 309.587138 -300.761654)
				)
				(arc
					(start 308.187598 -300.761654)
					(mid 308.151677 -300.776533)
					(end 308.136798 -300.812454)
				)
			)
		)
	)
	(zone
		(layers "In1.Cu" "In2.Cu")
		(hatch none 0.5)
		(connect_pads
			(clearance 0)
		)
		(min_thickness 0.25)
		(keepout
			(tracks not_allowed)
			(vias allowed)
			(pads allowed)
			(copperpour not_allowed)
			(footprints allowed)
		)
		(placement
			(enabled no)
			(sheetname "")
		)
		(fill yes
			(thermal_gap 0.5)
			(thermal_bridge_width 0.5)
			(island_removal_mode 0)
		)
		(polygon
			(pts
				(arc
					(start 188.23813 -275.721318)
					(mid 188.253009 -275.757239)
					(end 188.28893 -275.772118)
				)
				(arc
					(start 189.68847 -275.772118)
					(mid 189.724391 -275.757239)
					(end 189.73927 -275.721318)
				)
				(arc
					(start 189.73927 -275.312378)
					(mid 189.724391 -275.276457)
					(end 189.68847 -275.261578)
				)
				(arc
					(start 188.28893 -275.261578)
					(mid 188.253009 -275.276457)
					(end 188.23813 -275.312378)
				)
			)
		)
	)
	(zone
		(layers "In1.Cu" "In2.Cu")
		(hatch none 0.5)
		(connect_pads
			(clearance 0)
		)
		(min_thickness 0.25)
		(keepout
			(tracks not_allowed)
			(vias allowed)
			(pads allowed)
			(copperpour not_allowed)
			(footprints allowed)
		)
		(placement
			(enabled no)
			(sheetname "")
		)
		(fill yes
			(thermal_gap 0.5)
			(thermal_bridge_width 0.5)
			(island_removal_mode 0)
		)
		(polygon
			(pts
				(arc
					(start 451.265798 -206.021432)
					(mid 451.280677 -206.057353)
					(end 451.316598 -206.072232)
				)
				(arc
					(start 452.716138 -206.072232)
					(mid 452.752059 -206.057353)
					(end 452.766938 -206.021432)
				)
				(arc
					(start 452.766938 -205.612492)
					(mid 452.752059 -205.576571)
					(end 452.716138 -205.561692)
				)
				(arc
					(start 451.316598 -205.561692)
					(mid 451.280677 -205.576571)
					(end 451.265798 -205.612492)
				)
			)
		)
	)
	(zone
		(layers "In1.Cu" "In2.Cu")
		(hatch none 0.5)
		(connect_pads
			(clearance 0)
		)
		(min_thickness 0.25)
		(keepout
			(tracks not_allowed)
			(vias allowed)
			(pads allowed)
			(copperpour not_allowed)
			(footprints allowed)
		)
		(placement
			(enabled no)
			(sheetname "")
		)
		(fill yes
			(thermal_gap 0.5)
			(thermal_bridge_width 0.5)
			(island_removal_mode 0)
		)
		(polygon
			(pts
				(arc
					(start 262.873998 -228.121464)
					(mid 262.888877 -228.157385)
					(end 262.924798 -228.172264)
				)
				(arc
					(start 264.324338 -228.172264)
					(mid 264.360259 -228.157385)
					(end 264.375138 -228.121464)
				)
				(arc
					(start 264.375138 -227.712524)
					(mid 264.360259 -227.676603)
					(end 264.324338 -227.661724)
				)
				(arc
					(start 262.924798 -227.661724)
					(mid 262.888877 -227.676603)
					(end 262.873998 -227.712524)
				)
			)
		)
	)
	(zone
		(layers "In1.Cu" "In2.Cu")
		(hatch none 0.5)
		(connect_pads
			(clearance 0)
		)
		(min_thickness 0.25)
		(keepout
			(tracks not_allowed)
			(vias allowed)
			(pads allowed)
			(copperpour not_allowed)
			(footprints allowed)
		)
		(placement
			(enabled no)
			(sheetname "")
		)
		(fill yes
			(thermal_gap 0.5)
			(thermal_bridge_width 0.5)
			(island_removal_mode 0)
		)
		(polygon
			(pts
				(arc
					(start 214.969598 -223.871536)
					(mid 214.984477 -223.907457)
					(end 215.020398 -223.922336)
				)
				(arc
					(start 216.419938 -223.922336)
					(mid 216.455859 -223.907457)
					(end 216.470738 -223.871536)
				)
				(arc
					(start 216.470738 -223.462596)
					(mid 216.455859 -223.426675)
					(end 216.419938 -223.411796)
				)
				(arc
					(start 215.020398 -223.411796)
					(mid 214.984477 -223.426675)
					(end 214.969598 -223.462596)
				)
			)
		)
	)
	(zone
		(layers "In1.Cu" "In2.Cu")
		(hatch none 0.5)
		(connect_pads
			(clearance 0)
		)
		(min_thickness 0.25)
		(keepout
			(tracks not_allowed)
			(vias allowed)
			(pads allowed)
			(copperpour not_allowed)
			(footprints allowed)
		)
		(placement
			(enabled no)
			(sheetname "")
		)
		(fill yes
			(thermal_gap 0.5)
			(thermal_bridge_width 0.5)
			(island_removal_mode 0)
		)
		(polygon
			(pts
				(arc
					(start 45.10913 -301.221394)
					(mid 45.124009 -301.257315)
					(end 45.15993 -301.272194)
				)
				(arc
					(start 46.55947 -301.272194)
					(mid 46.595391 -301.257315)
					(end 46.61027 -301.221394)
				)
				(arc
					(start 46.61027 -300.812454)
					(mid 46.595391 -300.776533)
					(end 46.55947 -300.761654)
				)
				(arc
					(start 45.15993 -300.761654)
					(mid 45.124009 -300.776533)
					(end 45.10913 -300.812454)
				)
			)
		)
	)
	(zone
		(layers "In1.Cu" "In2.Cu")
		(hatch none 0.5)
		(connect_pads
			(clearance 0)
		)
		(min_thickness 0.25)
		(keepout
			(tracks not_allowed)
			(vias allowed)
			(pads allowed)
			(copperpour not_allowed)
			(footprints allowed)
		)
		(placement
			(enabled no)
			(sheetname "")
		)
		(fill yes
			(thermal_gap 0.5)
			(thermal_bridge_width 0.5)
			(island_removal_mode 0)
		)
		(polygon
			(pts
				(arc
					(start 425.190666 -201.771504)
					(mid 425.205545 -201.807425)
					(end 425.241466 -201.822304)
				)
				(arc
					(start 426.641006 -201.822304)
					(mid 426.676927 -201.807425)
					(end 426.691806 -201.771504)
				)
				(arc
					(start 426.691806 -201.362564)
					(mid 426.676927 -201.326643)
					(end 426.641006 -201.311764)
				)
				(arc
					(start 425.241466 -201.311764)
					(mid 425.205545 -201.326643)
					(end 425.190666 -201.362564)
				)
			)
		)
	)
	(zone
		(layers "In1.Cu" "In2.Cu")
		(hatch none 0.5)
		(connect_pads
			(clearance 0)
		)
		(min_thickness 0.25)
		(keepout
			(tracks not_allowed)
			(vias allowed)
			(pads allowed)
			(copperpour not_allowed)
			(footprints allowed)
		)
		(placement
			(enabled no)
			(sheetname "")
		)
		(fill yes
			(thermal_gap 0.5)
			(thermal_bridge_width 0.5)
			(island_removal_mode 0)
		)
		(polygon
			(pts
				(arc
					(start 432.734466 -234.921298)
					(mid 432.749345 -234.957219)
					(end 432.785266 -234.972098)
				)
				(arc
					(start 434.184806 -234.972098)
					(mid 434.220727 -234.957219)
					(end 434.235606 -234.921298)
				)
				(arc
					(start 434.235606 -234.512358)
					(mid 434.220727 -234.476437)
					(end 434.184806 -234.461558)
				)
				(arc
					(start 432.785266 -234.461558)
					(mid 432.749345 -234.476437)
					(end 432.734466 -234.512358)
				)
			)
		)
	)
	(zone
		(layers "In1.Cu" "In2.Cu")
		(hatch none 0.5)
		(connect_pads
			(clearance 0)
		)
		(min_thickness 0.25)
		(keepout
			(tracks not_allowed)
			(vias allowed)
			(pads allowed)
			(copperpour not_allowed)
			(footprints allowed)
		)
		(placement
			(enabled no)
			(sheetname "")
		)
		(fill yes
			(thermal_gap 0.5)
			(thermal_bridge_width 0.5)
			(island_removal_mode 0)
		)
		(polygon
			(pts
				(arc
					(start 11.490198 -246.821452)
					(mid 11.505077 -246.857373)
					(end 11.540998 -246.872252)
				)
				(arc
					(start 12.940538 -246.872252)
					(mid 12.976459 -246.857373)
					(end 12.991338 -246.821452)
				)
				(arc
					(start 12.991338 -246.412512)
					(mid 12.976459 -246.376591)
					(end 12.940538 -246.361712)
				)
				(arc
					(start 11.540998 -246.361712)
					(mid 11.505077 -246.376591)
					(end 11.490198 -246.412512)
				)
			)
		)
	)
	(zone
		(layers "In1.Cu" "In2.Cu")
		(hatch none 0.5)
		(connect_pads
			(clearance 0)
		)
		(min_thickness 0.25)
		(keepout
			(tracks not_allowed)
			(vias allowed)
			(pads allowed)
			(copperpour not_allowed)
			(footprints allowed)
		)
		(placement
			(enabled no)
			(sheetname "")
		)
		(fill yes
			(thermal_gap 0.5)
			(thermal_bridge_width 0.5)
			(island_removal_mode 0)
		)
		(polygon
			(pts
				(arc
					(start 64.296798 -200.071482)
					(mid 64.311677 -200.107403)
					(end 64.347598 -200.122282)
				)
				(arc
					(start 65.747138 -200.122282)
					(mid 65.783059 -200.107403)
					(end 65.797938 -200.071482)
				)
				(arc
					(start 65.797938 -199.662542)
					(mid 65.783059 -199.626621)
					(end 65.747138 -199.611742)
				)
				(arc
					(start 64.347598 -199.611742)
					(mid 64.311677 -199.626621)
					(end 64.296798 -199.662542)
				)
			)
		)
	)
	(zone
		(layers "In1.Cu" "In2.Cu")
		(hatch none 0.5)
		(connect_pads
			(clearance 0)
		)
		(min_thickness 0.25)
		(keepout
			(tracks not_allowed)
			(vias allowed)
			(pads allowed)
			(copperpour not_allowed)
			(footprints allowed)
		)
		(placement
			(enabled no)
			(sheetname "")
		)
		(fill yes
			(thermal_gap 0.5)
			(thermal_bridge_width 0.5)
			(island_removal_mode 0)
		)
		(polygon
			(pts
				(arc
					(start 199.881998 -234.921298)
					(mid 199.896877 -234.957219)
					(end 199.932798 -234.972098)
				)
				(arc
					(start 201.332338 -234.972098)
					(mid 201.368259 -234.957219)
					(end 201.383138 -234.921298)
				)
				(arc
					(start 201.383138 -234.512358)
					(mid 201.368259 -234.476437)
					(end 201.332338 -234.461558)
				)
				(arc
					(start 199.932798 -234.461558)
					(mid 199.896877 -234.476437)
					(end 199.881998 -234.512358)
				)
			)
		)
	)
	(zone
		(layers "In1.Cu" "In2.Cu")
		(hatch none 0.5)
		(connect_pads
			(clearance 0)
		)
		(min_thickness 0.25)
		(keepout
			(tracks not_allowed)
			(vias allowed)
			(pads allowed)
			(copperpour not_allowed)
			(footprints allowed)
		)
		(placement
			(enabled no)
			(sheetname "")
		)
		(fill yes
			(thermal_gap 0.5)
			(thermal_bridge_width 0.5)
			(island_removal_mode 0)
		)
		(polygon
			(pts
				(arc
					(start 52.65293 -240.021364)
					(mid 52.667809 -240.057285)
					(end 52.70373 -240.072164)
				)
				(arc
					(start 54.10327 -240.072164)
					(mid 54.139191 -240.057285)
					(end 54.15407 -240.021364)
				)
				(arc
					(start 54.15407 -239.612424)
					(mid 54.139191 -239.576503)
					(end 54.10327 -239.561624)
				)
				(arc
					(start 52.70373 -239.561624)
					(mid 52.667809 -239.576503)
					(end 52.65293 -239.612424)
				)
			)
		)
	)
	(zone
		(layers "In1.Cu" "In2.Cu")
		(hatch none 0.5)
		(connect_pads
			(clearance 0)
		)
		(min_thickness 0.25)
		(keepout
			(tracks not_allowed)
			(vias allowed)
			(pads allowed)
			(copperpour not_allowed)
			(footprints allowed)
		)
		(placement
			(enabled no)
			(sheetname "")
		)
		(fill yes
			(thermal_gap 0.5)
			(thermal_bridge_width 0.5)
			(island_removal_mode 0)
		)
		(polygon
			(pts
				(arc
					(start 19.033998 -308.021482)
					(mid 19.048877 -308.057403)
					(end 19.084798 -308.072282)
				)
				(arc
					(start 20.484338 -308.072282)
					(mid 20.520259 -308.057403)
					(end 20.535138 -308.021482)
				)
				(arc
					(start 20.535138 -307.612542)
					(mid 20.520259 -307.576621)
					(end 20.484338 -307.561742)
				)
				(arc
					(start 19.084798 -307.561742)
					(mid 19.048877 -307.576621)
					(end 19.033998 -307.612542)
				)
			)
		)
	)
	(zone
		(layers "In1.Cu" "In2.Cu")
		(hatch none 0.5)
		(connect_pads
			(clearance 0)
		)
		(min_thickness 0.25)
		(keepout
			(tracks not_allowed)
			(vias allowed)
			(pads allowed)
			(copperpour not_allowed)
			(footprints allowed)
		)
		(placement
			(enabled no)
			(sheetname "")
		)
		(fill yes
			(thermal_gap 0.5)
			(thermal_bridge_width 0.5)
			(island_removal_mode 0)
		)
		(polygon
			(pts
				(arc
					(start 458.809598 -312.27141)
					(mid 458.824477 -312.307331)
					(end 458.860398 -312.32221)
				)
				(arc
					(start 460.259938 -312.32221)
					(mid 460.295859 -312.307331)
					(end 460.310738 -312.27141)
				)
				(arc
					(start 460.310738 -311.86247)
					(mid 460.295859 -311.826549)
					(end 460.259938 -311.81167)
				)
				(arc
					(start 458.860398 -311.81167)
					(mid 458.824477 -311.826549)
					(end 458.809598 -311.86247)
				)
			)
		)
	)
	(zone
		(layers "In1.Cu" "In2.Cu")
		(hatch none 0.5)
		(connect_pads
			(clearance 0)
		)
		(min_thickness 0.25)
		(keepout
			(tracks not_allowed)
			(vias allowed)
			(pads allowed)
			(copperpour not_allowed)
			(footprints allowed)
		)
		(placement
			(enabled no)
			(sheetname "")
		)
		(fill yes
			(thermal_gap 0.5)
			(thermal_bridge_width 0.5)
			(island_removal_mode 0)
		)
		(polygon
			(pts
				(arc
					(start 255.330198 -235.771436)
					(mid 255.345077 -235.807357)
					(end 255.380998 -235.822236)
				)
				(arc
					(start 256.780538 -235.822236)
					(mid 256.816459 -235.807357)
					(end 256.831338 -235.771436)
				)
				(arc
					(start 256.831338 -235.362496)
					(mid 256.816459 -235.326575)
					(end 256.780538 -235.311696)
				)
				(arc
					(start 255.380998 -235.311696)
					(mid 255.345077 -235.326575)
					(end 255.330198 -235.362496)
				)
			)
		)
	)
	(zone
		(layers "In1.Cu" "In2.Cu")
		(hatch none 0.5)
		(connect_pads
			(clearance 0)
		)
		(min_thickness 0.25)
		(keepout
			(tracks not_allowed)
			(vias allowed)
			(pads allowed)
			(copperpour not_allowed)
			(footprints allowed)
		)
		(placement
			(enabled no)
			(sheetname "")
		)
		(fill yes
			(thermal_gap 0.5)
			(thermal_bridge_width 0.5)
			(island_removal_mode 0)
		)
		(polygon
			(pts
				(arc
					(start 277.961598 -310.571388)
					(mid 277.976477 -310.607309)
					(end 278.012398 -310.622188)
				)
				(arc
					(start 279.411938 -310.622188)
					(mid 279.447859 -310.607309)
					(end 279.462738 -310.571388)
				)
				(arc
					(start 279.462738 -310.162448)
					(mid 279.447859 -310.126527)
					(end 279.411938 -310.111648)
				)
				(arc
					(start 278.012398 -310.111648)
					(mid 277.976477 -310.126527)
					(end 277.961598 -310.162448)
				)
			)
		)
	)
	(zone
		(layers "In1.Cu" "In2.Cu")
		(hatch none 0.5)
		(connect_pads
			(clearance 0)
		)
		(min_thickness 0.25)
		(keepout
			(tracks not_allowed)
			(vias allowed)
			(pads allowed)
			(copperpour not_allowed)
			(footprints allowed)
		)
		(placement
			(enabled no)
			(sheetname "")
		)
		(fill yes
			(thermal_gap 0.5)
			(thermal_bridge_width 0.5)
			(island_removal_mode 0)
		)
		(polygon
			(pts
				(arc
					(start 162.162998 -228.121464)
					(mid 162.177877 -228.157385)
					(end 162.213798 -228.172264)
				)
				(arc
					(start 163.613338 -228.172264)
					(mid 163.649259 -228.157385)
					(end 163.664138 -228.121464)
				)
				(arc
					(start 163.664138 -227.712524)
					(mid 163.649259 -227.676603)
					(end 163.613338 -227.661724)
				)
				(arc
					(start 162.213798 -227.661724)
					(mid 162.177877 -227.676603)
					(end 162.162998 -227.712524)
				)
			)
		)
	)
	(zone
		(layers "In1.Cu" "In2.Cu")
		(hatch none 0.5)
		(connect_pads
			(clearance 0)
		)
		(min_thickness 0.25)
		(keepout
			(tracks not_allowed)
			(vias allowed)
			(pads allowed)
			(copperpour not_allowed)
			(footprints allowed)
		)
		(placement
			(enabled no)
			(sheetname "")
		)
		(fill yes
			(thermal_gap 0.5)
			(thermal_bridge_width 0.5)
			(island_removal_mode 0)
		)
		(polygon
			(pts
				(arc
					(start 304.693066 -199.221344)
					(mid 304.707945 -199.257265)
					(end 304.743866 -199.272144)
				)
				(arc
					(start 306.143406 -199.272144)
					(mid 306.179327 -199.257265)
					(end 306.194206 -199.221344)
				)
				(arc
					(start 306.194206 -198.812404)
					(mid 306.179327 -198.776483)
					(end 306.143406 -198.761604)
				)
				(arc
					(start 304.743866 -198.761604)
					(mid 304.707945 -198.776483)
					(end 304.693066 -198.812404)
				)
			)
		)
	)
	(zone
		(layers "In1.Cu" "In2.Cu")
		(hatch none 0.5)
		(connect_pads
			(clearance 0)
		)
		(min_thickness 0.25)
		(keepout
			(tracks not_allowed)
			(vias allowed)
			(pads allowed)
			(copperpour not_allowed)
			(footprints allowed)
		)
		(placement
			(enabled no)
			(sheetname "")
		)
		(fill yes
			(thermal_gap 0.5)
			(thermal_bridge_width 0.5)
			(island_removal_mode 0)
		)
		(polygon
			(pts
				(arc
					(start 413.546798 -215.371426)
					(mid 413.561677 -215.407347)
					(end 413.597598 -215.422226)
				)
				(arc
					(start 414.997138 -215.422226)
					(mid 415.033059 -215.407347)
					(end 415.047938 -215.371426)
				)
				(arc
					(start 415.047938 -214.962486)
					(mid 415.033059 -214.926565)
					(end 414.997138 -214.911686)
				)
				(arc
					(start 413.597598 -214.911686)
					(mid 413.561677 -214.926565)
					(end 413.546798 -214.962486)
				)
			)
		)
	)
	(zone
		(layers "In1.Cu" "In2.Cu")
		(hatch none 0.5)
		(connect_pads
			(clearance 0)
		)
		(min_thickness 0.25)
		(keepout
			(tracks not_allowed)
			(vias allowed)
			(pads allowed)
			(copperpour not_allowed)
			(footprints allowed)
		)
		(placement
			(enabled no)
			(sheetname "")
		)
		(fill yes
			(thermal_gap 0.5)
			(thermal_bridge_width 0.5)
			(island_removal_mode 0)
		)
		(polygon
			(pts
				(arc
					(start 266.974066 -270.621506)
					(mid 266.988945 -270.657427)
					(end 267.024866 -270.672306)
				)
				(arc
					(start 268.424406 -270.672306)
					(mid 268.460327 -270.657427)
					(end 268.475206 -270.621506)
				)
				(arc
					(start 268.475206 -270.212566)
					(mid 268.460327 -270.176645)
					(end 268.424406 -270.161766)
				)
				(arc
					(start 267.024866 -270.161766)
					(mid 266.988945 -270.176645)
					(end 266.974066 -270.212566)
				)
			)
		)
	)
	(zone
		(layers "In1.Cu" "In2.Cu")
		(hatch none 0.5)
		(connect_pads
			(clearance 0)
		)
		(min_thickness 0.25)
		(keepout
			(tracks not_allowed)
			(vias allowed)
			(pads allowed)
			(copperpour not_allowed)
			(footprints allowed)
		)
		(placement
			(enabled no)
			(sheetname "")
		)
		(fill yes
			(thermal_gap 0.5)
			(thermal_bridge_width 0.5)
			(island_removal_mode 0)
		)
		(polygon
			(pts
				(arc
					(start 304.693066 -272.321528)
					(mid 304.707945 -272.357449)
					(end 304.743866 -272.372328)
				)
				(arc
					(start 306.143406 -272.372328)
					(mid 306.179327 -272.357449)
					(end 306.194206 -272.321528)
				)
				(arc
					(start 306.194206 -271.912588)
					(mid 306.179327 -271.876667)
					(end 306.143406 -271.861788)
				)
				(arc
					(start 304.743866 -271.861788)
					(mid 304.707945 -271.876667)
					(end 304.693066 -271.912588)
				)
			)
		)
	)
	(zone
		(layers "In1.Cu" "In2.Cu")
		(hatch none 0.5)
		(connect_pads
			(clearance 0)
		)
		(min_thickness 0.25)
		(keepout
			(tracks not_allowed)
			(vias allowed)
			(pads allowed)
			(copperpour not_allowed)
			(footprints allowed)
		)
		(placement
			(enabled no)
			(sheetname "")
		)
		(fill yes
			(thermal_gap 0.5)
			(thermal_bridge_width 0.5)
			(island_removal_mode 0)
		)
		(polygon
			(pts
				(arc
					(start 41.665398 -240.871502)
					(mid 41.680277 -240.907423)
					(end 41.716198 -240.922302)
				)
				(arc
					(start 43.115738 -240.922302)
					(mid 43.151659 -240.907423)
					(end 43.166538 -240.871502)
				)
				(arc
					(start 43.166538 -240.462562)
					(mid 43.151659 -240.426641)
					(end 43.115738 -240.411762)
				)
				(arc
					(start 41.716198 -240.411762)
					(mid 41.680277 -240.426641)
					(end 41.665398 -240.462562)
				)
			)
		)
	)
	(zone
		(layers "In1.Cu" "In2.Cu")
		(hatch none 0.5)
		(connect_pads
			(clearance 0)
		)
		(min_thickness 0.25)
		(keepout
			(tracks not_allowed)
			(vias allowed)
			(pads allowed)
			(copperpour not_allowed)
			(footprints allowed)
		)
		(placement
			(enabled no)
			(sheetname "")
		)
		(fill yes
			(thermal_gap 0.5)
			(thermal_bridge_width 0.5)
			(island_removal_mode 0)
		)
		(polygon
			(pts
				(arc
					(start 26.577798 -234.921298)
					(mid 26.592677 -234.957219)
					(end 26.628598 -234.972098)
				)
				(arc
					(start 28.028138 -234.972098)
					(mid 28.064059 -234.957219)
					(end 28.078938 -234.921298)
				)
				(arc
					(start 28.078938 -234.512358)
					(mid 28.064059 -234.476437)
					(end 28.028138 -234.461558)
				)
				(arc
					(start 26.628598 -234.461558)
					(mid 26.592677 -234.476437)
					(end 26.577798 -234.512358)
				)
			)
		)
	)
	(zone
		(layers "In1.Cu" "In2.Cu")
		(hatch none 0.5)
		(connect_pads
			(clearance 0)
		)
		(min_thickness 0.25)
		(keepout
			(tracks not_allowed)
			(vias allowed)
			(pads allowed)
			(copperpour not_allowed)
			(footprints allowed)
		)
		(placement
			(enabled no)
			(sheetname "")
		)
		(fill yes
			(thermal_gap 0.5)
			(thermal_bridge_width 0.5)
			(island_removal_mode 0)
		)
		(polygon
			(pts
				(arc
					(start 428.634398 -301.221394)
					(mid 428.649277 -301.257315)
					(end 428.685198 -301.272194)
				)
				(arc
					(start 430.084738 -301.272194)
					(mid 430.120659 -301.257315)
					(end 430.135538 -301.221394)
				)
				(arc
					(start 430.135538 -300.812454)
					(mid 430.120659 -300.776533)
					(end 430.084738 -300.761654)
				)
				(arc
					(start 428.685198 -300.761654)
					(mid 428.649277 -300.776533)
					(end 428.634398 -300.812454)
				)
			)
		)
	)
	(zone
		(layers "In1.Cu" "In2.Cu")
		(hatch none 0.5)
		(connect_pads
			(clearance 0)
		)
		(min_thickness 0.25)
		(keepout
			(tracks not_allowed)
			(vias allowed)
			(pads allowed)
			(copperpour not_allowed)
			(footprints allowed)
		)
		(placement
			(enabled no)
			(sheetname "")
		)
		(fill yes
			(thermal_gap 0.5)
			(thermal_bridge_width 0.5)
			(island_removal_mode 0)
		)
		(polygon
			(pts
				(arc
					(start 410.103066 -239.17148)
					(mid 410.117945 -239.207401)
					(end 410.153866 -239.22228)
				)
				(arc
					(start 411.553406 -239.22228)
					(mid 411.589327 -239.207401)
					(end 411.604206 -239.17148)
				)
				(arc
					(start 411.604206 -238.76254)
					(mid 411.589327 -238.726619)
					(end 411.553406 -238.71174)
				)
				(arc
					(start 410.153866 -238.71174)
					(mid 410.117945 -238.726619)
					(end 410.103066 -238.76254)
				)
			)
		)
	)
	(zone
		(layers "In1.Cu" "In2.Cu")
		(hatch none 0.5)
		(connect_pads
			(clearance 0)
		)
		(min_thickness 0.25)
		(keepout
			(tracks not_allowed)
			(vias allowed)
			(pads allowed)
			(copperpour not_allowed)
			(footprints allowed)
		)
		(placement
			(enabled no)
			(sheetname "")
		)
		(fill yes
			(thermal_gap 0.5)
			(thermal_bridge_width 0.5)
			(island_removal_mode 0)
		)
		(polygon
			(pts
				(arc
					(start 417.646866 -227.271326)
					(mid 417.661745 -227.307247)
					(end 417.697666 -227.322126)
				)
				(arc
					(start 419.097206 -227.322126)
					(mid 419.133127 -227.307247)
					(end 419.148006 -227.271326)
				)
				(arc
					(start 419.148006 -226.862386)
					(mid 419.133127 -226.826465)
					(end 419.097206 -226.811586)
				)
				(arc
					(start 417.697666 -226.811586)
					(mid 417.661745 -226.826465)
					(end 417.646866 -226.862386)
				)
			)
		)
	)
	(zone
		(layers "In1.Cu" "In2.Cu")
		(hatch none 0.5)
		(connect_pads
			(clearance 0)
		)
		(min_thickness 0.25)
		(keepout
			(tracks not_allowed)
			(vias allowed)
			(pads allowed)
			(copperpour not_allowed)
			(footprints allowed)
		)
		(placement
			(enabled no)
			(sheetname "")
		)
		(fill yes
			(thermal_gap 0.5)
			(thermal_bridge_width 0.5)
			(island_removal_mode 0)
		)
		(polygon
			(pts
				(arc
					(start 207.425798 -233.22153)
					(mid 207.440677 -233.257451)
					(end 207.476598 -233.27233)
				)
				(arc
					(start 208.876138 -233.27233)
					(mid 208.912059 -233.257451)
					(end 208.926938 -233.22153)
				)
				(arc
					(start 208.926938 -232.81259)
					(mid 208.912059 -232.776669)
					(end 208.876138 -232.76179)
				)
				(arc
					(start 207.476598 -232.76179)
					(mid 207.440677 -232.776669)
					(end 207.425798 -232.81259)
				)
			)
		)
	)
	(zone
		(layers "In1.Cu" "In2.Cu")
		(hatch none 0.5)
		(connect_pads
			(clearance 0)
		)
		(min_thickness 0.25)
		(keepout
			(tracks not_allowed)
			(vias allowed)
			(pads allowed)
			(copperpour not_allowed)
			(footprints allowed)
		)
		(placement
			(enabled no)
			(sheetname "")
		)
		(fill yes
			(thermal_gap 0.5)
			(thermal_bridge_width 0.5)
			(island_removal_mode 0)
		)
		(polygon
			(pts
				(arc
					(start 282.061666 -302.071532)
					(mid 282.076545 -302.107453)
					(end 282.112466 -302.122332)
				)
				(arc
					(start 283.512006 -302.122332)
					(mid 283.547927 -302.107453)
					(end 283.562806 -302.071532)
				)
				(arc
					(start 283.562806 -301.662592)
					(mid 283.547927 -301.626671)
					(end 283.512006 -301.611792)
				)
				(arc
					(start 282.112466 -301.611792)
					(mid 282.076545 -301.626671)
					(end 282.061666 -301.662592)
				)
			)
		)
	)
	(zone
		(layers "In1.Cu" "In2.Cu")
		(hatch none 0.5)
		(connect_pads
			(clearance 0)
		)
		(min_thickness 0.25)
		(keepout
			(tracks not_allowed)
			(vias allowed)
			(pads allowed)
			(copperpour not_allowed)
			(footprints allowed)
		)
		(placement
			(enabled no)
			(sheetname "")
		)
		(fill yes
			(thermal_gap 0.5)
			(thermal_bridge_width 0.5)
			(island_removal_mode 0)
		)
		(polygon
			(pts
				(arc
					(start 7.39013 -210.27136)
					(mid 7.405009 -210.307281)
					(end 7.44093 -210.32216)
				)
				(arc
					(start 8.84047 -210.32216)
					(mid 8.876391 -210.307281)
					(end 8.89127 -210.27136)
				)
				(arc
					(start 8.89127 -209.86242)
					(mid 8.876391 -209.826499)
					(end 8.84047 -209.81162)
				)
				(arc
					(start 7.44093 -209.81162)
					(mid 7.405009 -209.826499)
					(end 7.39013 -209.86242)
				)
			)
		)
	)
	(zone
		(layers "In1.Cu" "In2.Cu")
		(hatch none 0.5)
		(connect_pads
			(clearance 0)
		)
		(min_thickness 0.25)
		(keepout
			(tracks not_allowed)
			(vias allowed)
			(pads allowed)
			(copperpour not_allowed)
			(footprints allowed)
		)
		(placement
			(enabled no)
			(sheetname "")
		)
		(fill yes
			(thermal_gap 0.5)
			(thermal_bridge_width 0.5)
			(island_removal_mode 0)
		)
		(polygon
			(pts
				(arc
					(start 22.47773 -266.371324)
					(mid 22.492609 -266.407245)
					(end 22.52853 -266.422124)
				)
				(arc
					(start 23.92807 -266.422124)
					(mid 23.963991 -266.407245)
					(end 23.97887 -266.371324)
				)
				(arc
					(start 23.97887 -265.962384)
					(mid 23.963991 -265.926463)
					(end 23.92807 -265.911584)
				)
				(arc
					(start 22.52853 -265.911584)
					(mid 22.492609 -265.926463)
					(end 22.47773 -265.962384)
				)
			)
		)
	)
	(zone
		(layers "In1.Cu" "In2.Cu")
		(hatch none 0.5)
		(connect_pads
			(clearance 0)
		)
		(min_thickness 0.25)
		(keepout
			(tracks not_allowed)
			(vias allowed)
			(pads allowed)
			(copperpour not_allowed)
			(footprints allowed)
		)
		(placement
			(enabled no)
			(sheetname "")
		)
		(fill yes
			(thermal_gap 0.5)
			(thermal_bridge_width 0.5)
			(island_removal_mode 0)
		)
		(polygon
			(pts
				(arc
					(start 455.365866 -231.521508)
					(mid 455.380745 -231.557429)
					(end 455.416666 -231.572308)
				)
				(arc
					(start 456.816206 -231.572308)
					(mid 456.852127 -231.557429)
					(end 456.867006 -231.521508)
				)
				(arc
					(start 456.867006 -231.112568)
					(mid 456.852127 -231.076647)
					(end 456.816206 -231.061768)
				)
				(arc
					(start 455.416666 -231.061768)
					(mid 455.380745 -231.076647)
					(end 455.365866 -231.112568)
				)
			)
		)
	)
	(zone
		(layers "In1.Cu" "In2.Cu")
		(hatch none 0.5)
		(connect_pads
			(clearance 0)
		)
		(min_thickness 0.25)
		(keepout
			(tracks not_allowed)
			(vias allowed)
			(pads allowed)
			(copperpour not_allowed)
			(footprints allowed)
		)
		(placement
			(enabled no)
			(sheetname "")
		)
		(fill yes
			(thermal_gap 0.5)
			(thermal_bridge_width 0.5)
			(island_removal_mode 0)
		)
		(polygon
			(pts
				(arc
					(start 282.061666 -197.521322)
					(mid 282.076545 -197.557243)
					(end 282.112466 -197.572122)
				)
				(arc
					(start 283.512006 -197.572122)
					(mid 283.547927 -197.557243)
					(end 283.562806 -197.521322)
				)
				(arc
					(start 283.562806 -197.112382)
					(mid 283.547927 -197.076461)
					(end 283.512006 -197.061582)
				)
				(arc
					(start 282.112466 -197.061582)
					(mid 282.076545 -197.076461)
					(end 282.061666 -197.112382)
				)
			)
		)
	)
	(zone
		(layers "In1.Cu" "In2.Cu")
		(hatch none 0.5)
		(connect_pads
			(clearance 0)
		)
		(min_thickness 0.25)
		(keepout
			(tracks not_allowed)
			(vias allowed)
			(pads allowed)
			(copperpour not_allowed)
			(footprints allowed)
		)
		(placement
			(enabled no)
			(sheetname "")
		)
		(fill yes
			(thermal_gap 0.5)
			(thermal_bridge_width 0.5)
			(island_removal_mode 0)
		)
		(polygon
			(pts
				(arc
					(start 214.969598 -302.071532)
					(mid 214.984477 -302.107453)
					(end 215.020398 -302.122332)
				)
				(arc
					(start 216.419938 -302.122332)
					(mid 216.455859 -302.107453)
					(end 216.470738 -302.071532)
				)
				(arc
					(start 216.470738 -301.662592)
					(mid 216.455859 -301.626671)
					(end 216.419938 -301.611792)
				)
				(arc
					(start 215.020398 -301.611792)
					(mid 214.984477 -301.626671)
					(end 214.969598 -301.662592)
				)
			)
		)
	)
	(zone
		(layers "In1.Cu" "In2.Cu")
		(hatch none 0.5)
		(connect_pads
			(clearance 0)
		)
		(min_thickness 0.25)
		(keepout
			(tracks not_allowed)
			(vias allowed)
			(pads allowed)
			(copperpour not_allowed)
			(footprints allowed)
		)
		(placement
			(enabled no)
			(sheetname "")
		)
		(fill yes
			(thermal_gap 0.5)
			(thermal_bridge_width 0.5)
			(island_removal_mode 0)
		)
		(polygon
			(pts
				(arc
					(start 259.430266 -279.9715)
					(mid 259.445145 -280.007421)
					(end 259.481066 -280.0223)
				)
				(arc
					(start 260.880606 -280.0223)
					(mid 260.916527 -280.007421)
					(end 260.931406 -279.9715)
				)
				(arc
					(start 260.931406 -279.56256)
					(mid 260.916527 -279.526639)
					(end 260.880606 -279.51176)
				)
				(arc
					(start 259.481066 -279.51176)
					(mid 259.445145 -279.526639)
					(end 259.430266 -279.56256)
				)
			)
		)
	)
	(zone
		(layers "In1.Cu" "In2.Cu")
		(hatch none 0.5)
		(connect_pads
			(clearance 0)
		)
		(min_thickness 0.25)
		(keepout
			(tracks not_allowed)
			(vias allowed)
			(pads allowed)
			(copperpour not_allowed)
			(footprints allowed)
		)
		(placement
			(enabled no)
			(sheetname "")
		)
		(fill yes
			(thermal_gap 0.5)
			(thermal_bridge_width 0.5)
			(island_removal_mode 0)
		)
		(polygon
			(pts
				(arc
					(start 308.136798 -275.721318)
					(mid 308.151677 -275.757239)
					(end 308.187598 -275.772118)
				)
				(arc
					(start 309.587138 -275.772118)
					(mid 309.623059 -275.757239)
					(end 309.637938 -275.721318)
				)
				(arc
					(start 309.637938 -275.312378)
					(mid 309.623059 -275.276457)
					(end 309.587138 -275.261578)
				)
				(arc
					(start 308.187598 -275.261578)
					(mid 308.151677 -275.276457)
					(end 308.136798 -275.312378)
				)
			)
		)
	)
	(zone
		(layers "In1.Cu" "In2.Cu")
		(hatch none 0.5)
		(connect_pads
			(clearance 0)
		)
		(min_thickness 0.25)
		(keepout
			(tracks not_allowed)
			(vias allowed)
			(pads allowed)
			(copperpour not_allowed)
			(footprints allowed)
		)
		(placement
			(enabled no)
			(sheetname "")
		)
		(fill yes
			(thermal_gap 0.5)
			(thermal_bridge_width 0.5)
			(island_removal_mode 0)
		)
		(polygon
			(pts
				(arc
					(start 195.78193 -303.7713)
					(mid 195.796809 -303.807221)
					(end 195.83273 -303.8221)
				)
				(arc
					(start 197.23227 -303.8221)
					(mid 197.268191 -303.807221)
					(end 197.28307 -303.7713)
				)
				(arc
					(start 197.28307 -303.36236)
					(mid 197.268191 -303.326439)
					(end 197.23227 -303.31156)
				)
				(arc
					(start 195.83273 -303.31156)
					(mid 195.796809 -303.326439)
					(end 195.78193 -303.36236)
				)
			)
		)
	)
	(zone
		(layers "In1.Cu" "In2.Cu")
		(hatch none 0.5)
		(connect_pads
			(clearance 0)
		)
		(min_thickness 0.25)
		(keepout
			(tracks not_allowed)
			(vias allowed)
			(pads allowed)
			(copperpour not_allowed)
			(footprints allowed)
		)
		(placement
			(enabled no)
			(sheetname "")
		)
		(fill yes
			(thermal_gap 0.5)
			(thermal_bridge_width 0.5)
			(island_removal_mode 0)
		)
		(polygon
			(pts
				(arc
					(start 436.178198 -314.821316)
					(mid 436.193077 -314.857237)
					(end 436.228998 -314.872116)
				)
				(arc
					(start 437.628538 -314.872116)
					(mid 437.664459 -314.857237)
					(end 437.679338 -314.821316)
				)
				(arc
					(start 437.679338 -314.412376)
					(mid 437.664459 -314.376455)
					(end 437.628538 -314.361576)
				)
				(arc
					(start 436.228998 -314.361576)
					(mid 436.193077 -314.376455)
					(end 436.178198 -314.412376)
				)
			)
		)
	)
	(zone
		(layers "In1.Cu" "In2.Cu")
		(hatch none 0.5)
		(connect_pads
			(clearance 0)
		)
		(min_thickness 0.25)
		(keepout
			(tracks not_allowed)
			(vias allowed)
			(pads allowed)
			(copperpour not_allowed)
			(footprints allowed)
		)
		(placement
			(enabled no)
			(sheetname "")
		)
		(fill yes
			(thermal_gap 0.5)
			(thermal_bridge_width 0.5)
			(island_removal_mode 0)
		)
		(polygon
			(pts
				(arc
					(start 207.425798 -292.721538)
					(mid 207.440677 -292.757459)
					(end 207.476598 -292.772338)
				)
				(arc
					(start 208.876138 -292.772338)
					(mid 208.912059 -292.757459)
					(end 208.926938 -292.721538)
				)
				(arc
					(start 208.926938 -292.312598)
					(mid 208.912059 -292.276677)
					(end 208.876138 -292.261798)
				)
				(arc
					(start 207.476598 -292.261798)
					(mid 207.440677 -292.276677)
					(end 207.425798 -292.312598)
				)
			)
		)
	)
	(zone
		(layers "In1.Cu" "In2.Cu")
		(hatch none 0.5)
		(connect_pads
			(clearance 0)
		)
		(min_thickness 0.25)
		(keepout
			(tracks not_allowed)
			(vias allowed)
			(pads allowed)
			(copperpour not_allowed)
			(footprints allowed)
		)
		(placement
			(enabled no)
			(sheetname "")
		)
		(fill yes
			(thermal_gap 0.5)
			(thermal_bridge_width 0.5)
			(island_removal_mode 0)
		)
		(polygon
			(pts
				(arc
					(start 259.430266 -259.57149)
					(mid 259.445145 -259.607411)
					(end 259.481066 -259.62229)
				)
				(arc
					(start 260.880606 -259.62229)
					(mid 260.916527 -259.607411)
					(end 260.931406 -259.57149)
				)
				(arc
					(start 260.931406 -259.16255)
					(mid 260.916527 -259.126629)
					(end 260.880606 -259.11175)
				)
				(arc
					(start 259.481066 -259.11175)
					(mid 259.445145 -259.126629)
					(end 259.430266 -259.16255)
				)
			)
		)
	)
	(zone
		(layers "In1.Cu" "In2.Cu")
		(hatch none 0.5)
		(connect_pads
			(clearance 0)
		)
		(min_thickness 0.25)
		(keepout
			(tracks not_allowed)
			(vias allowed)
			(pads allowed)
			(copperpour not_allowed)
			(footprints allowed)
		)
		(placement
			(enabled no)
			(sheetname "")
		)
		(fill yes
			(thermal_gap 0.5)
			(thermal_bridge_width 0.5)
			(island_removal_mode 0)
		)
		(polygon
			(pts
				(arc
					(start 312.236866 -216.22131)
					(mid 312.251745 -216.257231)
					(end 312.287666 -216.27211)
				)
				(arc
					(start 313.687206 -216.27211)
					(mid 313.723127 -216.257231)
					(end 313.738006 -216.22131)
				)
				(arc
					(start 313.738006 -215.81237)
					(mid 313.723127 -215.776449)
					(end 313.687206 -215.76157)
				)
				(arc
					(start 312.287666 -215.76157)
					(mid 312.251745 -215.776449)
					(end 312.236866 -215.81237)
				)
			)
		)
	)
	(zone
		(layers "In1.Cu" "In2.Cu")
		(hatch none 0.5)
		(connect_pads
			(clearance 0)
		)
		(min_thickness 0.25)
		(keepout
			(tracks not_allowed)
			(vias allowed)
			(pads allowed)
			(copperpour not_allowed)
			(footprints allowed)
		)
		(placement
			(enabled no)
			(sheetname "")
		)
		(fill yes
			(thermal_gap 0.5)
			(thermal_bridge_width 0.5)
			(island_removal_mode 0)
		)
		(polygon
			(pts
				(arc
					(start 169.706798 -228.121464)
					(mid 169.721677 -228.157385)
					(end 169.757598 -228.172264)
				)
				(arc
					(start 171.157138 -228.172264)
					(mid 171.193059 -228.157385)
					(end 171.207938 -228.121464)
				)
				(arc
					(start 171.207938 -227.712524)
					(mid 171.193059 -227.676603)
					(end 171.157138 -227.661724)
				)
				(arc
					(start 169.757598 -227.661724)
					(mid 169.721677 -227.676603)
					(end 169.706798 -227.712524)
				)
			)
		)
	)
	(zone
		(layers "In1.Cu" "In2.Cu")
		(hatch none 0.5)
		(connect_pads
			(clearance 0)
		)
		(min_thickness 0.25)
		(keepout
			(tracks not_allowed)
			(vias allowed)
			(pads allowed)
			(copperpour not_allowed)
			(footprints allowed)
		)
		(placement
			(enabled no)
			(sheetname "")
		)
		(fill yes
			(thermal_gap 0.5)
			(thermal_bridge_width 0.5)
			(island_removal_mode 0)
		)
		(polygon
			(pts
				(arc
					(start 203.32573 -228.121464)
					(mid 203.340609 -228.157385)
					(end 203.37653 -228.172264)
				)
				(arc
					(start 204.77607 -228.172264)
					(mid 204.811991 -228.157385)
					(end 204.82687 -228.121464)
				)
				(arc
					(start 204.82687 -227.712524)
					(mid 204.811991 -227.676603)
					(end 204.77607 -227.661724)
				)
				(arc
					(start 203.37653 -227.661724)
					(mid 203.340609 -227.676603)
					(end 203.32573 -227.712524)
				)
			)
		)
	)
	(zone
		(layers "In1.Cu" "In2.Cu")
		(hatch none 0.5)
		(connect_pads
			(clearance 0)
		)
		(min_thickness 0.25)
		(keepout
			(tracks not_allowed)
			(vias allowed)
			(pads allowed)
			(copperpour not_allowed)
			(footprints allowed)
		)
		(placement
			(enabled no)
			(sheetname "")
		)
		(fill yes
			(thermal_gap 0.5)
			(thermal_bridge_width 0.5)
			(island_removal_mode 0)
		)
		(polygon
			(pts
				(arc
					(start 30.02153 -264.671302)
					(mid 30.036409 -264.707223)
					(end 30.07233 -264.722102)
				)
				(arc
					(start 31.47187 -264.722102)
					(mid 31.507791 -264.707223)
					(end 31.52267 -264.671302)
				)
				(arc
					(start 31.52267 -264.262362)
					(mid 31.507791 -264.226441)
					(end 31.47187 -264.211562)
				)
				(arc
					(start 30.07233 -264.211562)
					(mid 30.036409 -264.226441)
					(end 30.02153 -264.262362)
				)
			)
		)
	)
	(zone
		(layers "In1.Cu" "In2.Cu")
		(hatch none 0.5)
		(connect_pads
			(clearance 0)
		)
		(min_thickness 0.25)
		(keepout
			(tracks not_allowed)
			(vias allowed)
			(pads allowed)
			(copperpour not_allowed)
			(footprints allowed)
		)
		(placement
			(enabled no)
			(sheetname "")
		)
		(fill yes
			(thermal_gap 0.5)
			(thermal_bridge_width 0.5)
			(island_removal_mode 0)
		)
		(polygon
			(pts
				(arc
					(start 413.546798 -305.471322)
					(mid 413.561677 -305.507243)
					(end 413.597598 -305.522122)
				)
				(arc
					(start 414.997138 -305.522122)
					(mid 415.033059 -305.507243)
					(end 415.047938 -305.471322)
				)
				(arc
					(start 415.047938 -305.062382)
					(mid 415.033059 -305.026461)
					(end 414.997138 -305.011582)
				)
				(arc
					(start 413.597598 -305.011582)
					(mid 413.561677 -305.026461)
					(end 413.546798 -305.062382)
				)
			)
		)
	)
	(zone
		(layers "In1.Cu" "In2.Cu")
		(hatch none 0.5)
		(connect_pads
			(clearance 0)
		)
		(min_thickness 0.25)
		(keepout
			(tracks not_allowed)
			(vias allowed)
			(pads allowed)
			(copperpour not_allowed)
			(footprints allowed)
		)
		(placement
			(enabled no)
			(sheetname "")
		)
		(fill yes
			(thermal_gap 0.5)
			(thermal_bridge_width 0.5)
			(island_removal_mode 0)
		)
		(polygon
			(pts
				(arc
					(start 451.265798 -241.721386)
					(mid 451.280677 -241.757307)
					(end 451.316598 -241.772186)
				)
				(arc
					(start 452.716138 -241.772186)
					(mid 452.752059 -241.757307)
					(end 452.766938 -241.721386)
				)
				(arc
					(start 452.766938 -241.312446)
					(mid 452.752059 -241.276525)
					(end 452.716138 -241.261646)
				)
				(arc
					(start 451.316598 -241.261646)
					(mid 451.280677 -241.276525)
					(end 451.265798 -241.312446)
				)
			)
		)
	)
	(zone
		(layers "In1.Cu" "In2.Cu")
		(hatch none 0.5)
		(connect_pads
			(clearance 0)
		)
		(min_thickness 0.25)
		(keepout
			(tracks not_allowed)
			(vias allowed)
			(pads allowed)
			(copperpour not_allowed)
			(footprints allowed)
		)
		(placement
			(enabled no)
			(sheetname "")
		)
		(fill yes
			(thermal_gap 0.5)
			(thermal_bridge_width 0.5)
			(island_removal_mode 0)
		)
		(polygon
			(pts
				(arc
					(start 162.162998 -212.82152)
					(mid 162.177877 -212.857441)
					(end 162.213798 -212.87232)
				)
				(arc
					(start 163.613338 -212.87232)
					(mid 163.649259 -212.857441)
					(end 163.664138 -212.82152)
				)
				(arc
					(start 163.664138 -212.41258)
					(mid 163.649259 -212.376659)
					(end 163.613338 -212.36178)
				)
				(arc
					(start 162.213798 -212.36178)
					(mid 162.177877 -212.376659)
					(end 162.162998 -212.41258)
				)
			)
		)
	)
	(zone
		(layers "In1.Cu" "In2.Cu")
		(hatch none 0.5)
		(connect_pads
			(clearance 0)
		)
		(min_thickness 0.25)
		(keepout
			(tracks not_allowed)
			(vias allowed)
			(pads allowed)
			(copperpour not_allowed)
			(footprints allowed)
		)
		(placement
			(enabled no)
			(sheetname "")
		)
		(fill yes
			(thermal_gap 0.5)
			(thermal_bridge_width 0.5)
			(island_removal_mode 0)
		)
		(polygon
			(pts
				(arc
					(start 34.121598 -272.321528)
					(mid 34.136477 -272.357449)
					(end 34.172398 -272.372328)
				)
				(arc
					(start 35.571938 -272.372328)
					(mid 35.607859 -272.357449)
					(end 35.622738 -272.321528)
				)
				(arc
					(start 35.622738 -271.912588)
					(mid 35.607859 -271.876667)
					(end 35.571938 -271.861788)
				)
				(arc
					(start 34.172398 -271.861788)
					(mid 34.136477 -271.876667)
					(end 34.121598 -271.912588)
				)
			)
		)
	)
	(zone
		(layers "In1.Cu" "In2.Cu")
		(hatch none 0.5)
		(connect_pads
			(clearance 0)
		)
		(min_thickness 0.25)
		(keepout
			(tracks not_allowed)
			(vias allowed)
			(pads allowed)
			(copperpour not_allowed)
			(footprints allowed)
		)
		(placement
			(enabled no)
			(sheetname "")
		)
		(fill yes
			(thermal_gap 0.5)
			(thermal_bridge_width 0.5)
			(island_removal_mode 0)
		)
		(polygon
			(pts
				(arc
					(start 11.490198 -227.271326)
					(mid 11.505077 -227.307247)
					(end 11.540998 -227.322126)
				)
				(arc
					(start 12.940538 -227.322126)
					(mid 12.976459 -227.307247)
					(end 12.991338 -227.271326)
				)
				(arc
					(start 12.991338 -226.862386)
					(mid 12.976459 -226.826465)
					(end 12.940538 -226.811586)
				)
				(arc
					(start 11.540998 -226.811586)
					(mid 11.505077 -226.826465)
					(end 11.490198 -226.862386)
				)
			)
		)
	)
	(zone
		(layers "In1.Cu" "In2.Cu")
		(hatch none 0.5)
		(connect_pads
			(clearance 0)
		)
		(min_thickness 0.25)
		(keepout
			(tracks not_allowed)
			(vias allowed)
			(pads allowed)
			(copperpour not_allowed)
			(footprints allowed)
		)
		(placement
			(enabled no)
			(sheetname "")
		)
		(fill yes
			(thermal_gap 0.5)
			(thermal_bridge_width 0.5)
			(island_removal_mode 0)
		)
		(polygon
			(pts
				(arc
					(start 440.278266 -284.221428)
					(mid 440.293145 -284.257349)
					(end 440.329066 -284.272228)
				)
				(arc
					(start 441.728606 -284.272228)
					(mid 441.764527 -284.257349)
					(end 441.779406 -284.221428)
				)
				(arc
					(start 441.779406 -283.812488)
					(mid 441.764527 -283.776567)
					(end 441.728606 -283.761688)
				)
				(arc
					(start 440.329066 -283.761688)
					(mid 440.293145 -283.776567)
					(end 440.278266 -283.812488)
				)
			)
		)
	)
	(zone
		(layers "In1.Cu" "In2.Cu")
		(hatch none 0.5)
		(connect_pads
			(clearance 0)
		)
		(min_thickness 0.25)
		(keepout
			(tracks not_allowed)
			(vias allowed)
			(pads allowed)
			(copperpour not_allowed)
			(footprints allowed)
		)
		(placement
			(enabled no)
			(sheetname "")
		)
		(fill yes
			(thermal_gap 0.5)
			(thermal_bridge_width 0.5)
			(island_removal_mode 0)
		)
		(polygon
			(pts
				(arc
					(start 49.209198 -201.771504)
					(mid 49.224077 -201.807425)
					(end 49.259998 -201.822304)
				)
				(arc
					(start 50.659538 -201.822304)
					(mid 50.695459 -201.807425)
					(end 50.710338 -201.771504)
				)
				(arc
					(start 50.710338 -201.362564)
					(mid 50.695459 -201.326643)
					(end 50.659538 -201.311764)
				)
				(arc
					(start 49.259998 -201.311764)
					(mid 49.224077 -201.326643)
					(end 49.209198 -201.362564)
				)
			)
		)
	)
	(zone
		(layers "In1.Cu" "In2.Cu")
		(hatch none 0.5)
		(connect_pads
			(clearance 0)
		)
		(min_thickness 0.25)
		(keepout
			(tracks not_allowed)
			(vias allowed)
			(pads allowed)
			(copperpour not_allowed)
			(footprints allowed)
		)
		(placement
			(enabled no)
			(sheetname "")
		)
		(fill yes
			(thermal_gap 0.5)
			(thermal_bridge_width 0.5)
			(island_removal_mode 0)
		)
		(polygon
			(pts
				(arc
					(start 41.665398 -295.271444)
					(mid 41.680277 -295.307365)
					(end 41.716198 -295.322244)
				)
				(arc
					(start 43.115738 -295.322244)
					(mid 43.151659 -295.307365)
					(end 43.166538 -295.271444)
				)
				(arc
					(start 43.166538 -294.862504)
					(mid 43.151659 -294.826583)
					(end 43.115738 -294.811704)
				)
				(arc
					(start 41.716198 -294.811704)
					(mid 41.680277 -294.826583)
					(end 41.665398 -294.862504)
				)
			)
		)
	)
	(zone
		(layers "In1.Cu" "In2.Cu")
		(hatch none 0.5)
		(connect_pads
			(clearance 0)
		)
		(min_thickness 0.25)
		(keepout
			(tracks not_allowed)
			(vias allowed)
			(pads allowed)
			(copperpour not_allowed)
			(footprints allowed)
		)
		(placement
			(enabled no)
			(sheetname "")
		)
		(fill yes
			(thermal_gap 0.5)
			(thermal_bridge_width 0.5)
			(island_removal_mode 0)
		)
		(polygon
			(pts
				(arc
					(start 22.47773 -285.071312)
					(mid 22.492609 -285.107233)
					(end 22.52853 -285.122112)
				)
				(arc
					(start 23.92807 -285.122112)
					(mid 23.963991 -285.107233)
					(end 23.97887 -285.071312)
				)
				(arc
					(start 23.97887 -284.662372)
					(mid 23.963991 -284.626451)
					(end 23.92807 -284.611572)
				)
				(arc
					(start 22.52853 -284.611572)
					(mid 22.492609 -284.626451)
					(end 22.47773 -284.662372)
				)
			)
		)
	)
	(zone
		(layers "In1.Cu" "In2.Cu")
		(hatch none 0.5)
		(connect_pads
			(clearance 0)
		)
		(min_thickness 0.25)
		(keepout
			(tracks not_allowed)
			(vias allowed)
			(pads allowed)
			(copperpour not_allowed)
			(footprints allowed)
		)
		(placement
			(enabled no)
			(sheetname "")
		)
		(fill yes
			(thermal_gap 0.5)
			(thermal_bridge_width 0.5)
			(island_removal_mode 0)
		)
		(polygon
			(pts
				(arc
					(start 22.47773 -284.221428)
					(mid 22.492609 -284.257349)
					(end 22.52853 -284.272228)
				)
				(arc
					(start 23.92807 -284.272228)
					(mid 23.963991 -284.257349)
					(end 23.97887 -284.221428)
				)
				(arc
					(start 23.97887 -283.812488)
					(mid 23.963991 -283.776567)
					(end 23.92807 -283.761688)
				)
				(arc
					(start 22.52853 -283.761688)
					(mid 22.492609 -283.776567)
					(end 22.47773 -283.812488)
				)
			)
		)
	)
	(zone
		(layers "In1.Cu" "In2.Cu")
		(hatch none 0.5)
		(connect_pads
			(clearance 0)
		)
		(min_thickness 0.25)
		(keepout
			(tracks not_allowed)
			(vias allowed)
			(pads allowed)
			(copperpour not_allowed)
			(footprints allowed)
		)
		(placement
			(enabled no)
			(sheetname "")
		)
		(fill yes
			(thermal_gap 0.5)
			(thermal_bridge_width 0.5)
			(island_removal_mode 0)
		)
		(polygon
			(pts
				(arc
					(start 158.06293 -198.37146)
					(mid 158.077809 -198.407381)
					(end 158.11373 -198.42226)
				)
				(arc
					(start 159.51327 -198.42226)
					(mid 159.549191 -198.407381)
					(end 159.56407 -198.37146)
				)
				(arc
					(start 159.56407 -197.96252)
					(mid 159.549191 -197.926599)
					(end 159.51327 -197.91172)
				)
				(arc
					(start 158.11373 -197.91172)
					(mid 158.077809 -197.926599)
					(end 158.06293 -197.96252)
				)
			)
		)
	)
	(zone
		(layers "In1.Cu" "In2.Cu")
		(hatch none 0.5)
		(connect_pads
			(clearance 0)
		)
		(min_thickness 0.25)
		(keepout
			(tracks not_allowed)
			(vias allowed)
			(pads allowed)
			(copperpour not_allowed)
			(footprints allowed)
		)
		(placement
			(enabled no)
			(sheetname "")
		)
		(fill yes
			(thermal_gap 0.5)
			(thermal_bridge_width 0.5)
			(island_removal_mode 0)
		)
		(polygon
			(pts
				(arc
					(start 440.278266 -239.17148)
					(mid 440.293145 -239.207401)
					(end 440.329066 -239.22228)
				)
				(arc
					(start 441.728606 -239.22228)
					(mid 441.764527 -239.207401)
					(end 441.779406 -239.17148)
				)
				(arc
					(start 441.779406 -238.76254)
					(mid 441.764527 -238.726619)
					(end 441.728606 -238.71174)
				)
				(arc
					(start 440.329066 -238.71174)
					(mid 440.293145 -238.726619)
					(end 440.278266 -238.76254)
				)
			)
		)
	)
	(zone
		(layers "In1.Cu" "In2.Cu")
		(hatch none 0.5)
		(connect_pads
			(clearance 0)
		)
		(min_thickness 0.25)
		(keepout
			(tracks not_allowed)
			(vias allowed)
			(pads allowed)
			(copperpour not_allowed)
			(footprints allowed)
		)
		(placement
			(enabled no)
			(sheetname "")
		)
		(fill yes
			(thermal_gap 0.5)
			(thermal_bridge_width 0.5)
			(island_removal_mode 0)
		)
		(polygon
			(pts
				(arc
					(start 45.10913 -235.771436)
					(mid 45.124009 -235.807357)
					(end 45.15993 -235.822236)
				)
				(arc
					(start 46.55947 -235.822236)
					(mid 46.595391 -235.807357)
					(end 46.61027 -235.771436)
				)
				(arc
					(start 46.61027 -235.362496)
					(mid 46.595391 -235.326575)
					(end 46.55947 -235.311696)
				)
				(arc
					(start 45.15993 -235.311696)
					(mid 45.124009 -235.326575)
					(end 45.10913 -235.362496)
				)
			)
		)
	)
	(zone
		(layers "In1.Cu" "In2.Cu")
		(hatch none 0.5)
		(connect_pads
			(clearance 0)
		)
		(min_thickness 0.25)
		(keepout
			(tracks not_allowed)
			(vias allowed)
			(pads allowed)
			(copperpour not_allowed)
			(footprints allowed)
		)
		(placement
			(enabled no)
			(sheetname "")
		)
		(fill yes
			(thermal_gap 0.5)
			(thermal_bridge_width 0.5)
			(island_removal_mode 0)
		)
		(polygon
			(pts
				(arc
					(start 30.02153 -290.171378)
					(mid 30.036409 -290.207299)
					(end 30.07233 -290.222178)
				)
				(arc
					(start 31.47187 -290.222178)
					(mid 31.507791 -290.207299)
					(end 31.52267 -290.171378)
				)
				(arc
					(start 31.52267 -289.762438)
					(mid 31.507791 -289.726517)
					(end 31.47187 -289.711638)
				)
				(arc
					(start 30.07233 -289.711638)
					(mid 30.036409 -289.726517)
					(end 30.02153 -289.762438)
				)
			)
		)
	)
	(zone
		(layers "In1.Cu" "In2.Cu")
		(hatch none 0.5)
		(connect_pads
			(clearance 0)
		)
		(min_thickness 0.25)
		(keepout
			(tracks not_allowed)
			(vias allowed)
			(pads allowed)
			(copperpour not_allowed)
			(footprints allowed)
		)
		(placement
			(enabled no)
			(sheetname "")
		)
		(fill yes
			(thermal_gap 0.5)
			(thermal_bridge_width 0.5)
			(island_removal_mode 0)
		)
		(polygon
			(pts
				(arc
					(start 458.809598 -275.721318)
					(mid 458.824477 -275.757239)
					(end 458.860398 -275.772118)
				)
				(arc
					(start 460.259938 -275.772118)
					(mid 460.295859 -275.757239)
					(end 460.310738 -275.721318)
				)
				(arc
					(start 460.310738 -275.312378)
					(mid 460.295859 -275.276457)
					(end 460.259938 -275.261578)
				)
				(arc
					(start 458.860398 -275.261578)
					(mid 458.824477 -275.276457)
					(end 458.809598 -275.312378)
				)
			)
		)
	)
	(zone
		(layers "In1.Cu" "In2.Cu")
		(hatch none 0.5)
		(connect_pads
			(clearance 0)
		)
		(min_thickness 0.25)
		(keepout
			(tracks not_allowed)
			(vias allowed)
			(pads allowed)
			(copperpour not_allowed)
			(footprints allowed)
		)
		(placement
			(enabled no)
			(sheetname "")
		)
		(fill yes
			(thermal_gap 0.5)
			(thermal_bridge_width 0.5)
			(island_removal_mode 0)
		)
		(polygon
			(pts
				(arc
					(start 421.090598 -223.021398)
					(mid 421.105477 -223.057319)
					(end 421.141398 -223.072198)
				)
				(arc
					(start 422.540938 -223.072198)
					(mid 422.576859 -223.057319)
					(end 422.591738 -223.021398)
				)
				(arc
					(start 422.591738 -222.612458)
					(mid 422.576859 -222.576537)
					(end 422.540938 -222.561658)
				)
				(arc
					(start 421.141398 -222.561658)
					(mid 421.105477 -222.576537)
					(end 421.090598 -222.612458)
				)
			)
		)
	)
	(zone
		(layers "In1.Cu" "In2.Cu")
		(hatch none 0.5)
		(connect_pads
			(clearance 0)
		)
		(min_thickness 0.25)
		(keepout
			(tracks not_allowed)
			(vias allowed)
			(pads allowed)
			(copperpour not_allowed)
			(footprints allowed)
		)
		(placement
			(enabled no)
			(sheetname "")
		)
		(fill yes
			(thermal_gap 0.5)
			(thermal_bridge_width 0.5)
			(island_removal_mode 0)
		)
		(polygon
			(pts
				(arc
					(start 255.330198 -285.071312)
					(mid 255.345077 -285.107233)
					(end 255.380998 -285.122112)
				)
				(arc
					(start 256.780538 -285.122112)
					(mid 256.816459 -285.107233)
					(end 256.831338 -285.071312)
				)
				(arc
					(start 256.831338 -284.662372)
					(mid 256.816459 -284.626451)
					(end 256.780538 -284.611572)
				)
				(arc
					(start 255.380998 -284.611572)
					(mid 255.345077 -284.626451)
					(end 255.330198 -284.662372)
				)
			)
		)
	)
	(zone
		(layers "In1.Cu" "In2.Cu")
		(hatch none 0.5)
		(connect_pads
			(clearance 0)
		)
		(min_thickness 0.25)
		(keepout
			(tracks not_allowed)
			(vias allowed)
			(pads allowed)
			(copperpour not_allowed)
			(footprints allowed)
		)
		(placement
			(enabled no)
			(sheetname "")
		)
		(fill yes
			(thermal_gap 0.5)
			(thermal_bridge_width 0.5)
			(island_removal_mode 0)
		)
		(polygon
			(pts
				(arc
					(start 285.505398 -240.021364)
					(mid 285.520277 -240.057285)
					(end 285.556198 -240.072164)
				)
				(arc
					(start 286.955738 -240.072164)
					(mid 286.991659 -240.057285)
					(end 287.006538 -240.021364)
				)
				(arc
					(start 287.006538 -239.612424)
					(mid 286.991659 -239.576503)
					(end 286.955738 -239.561624)
				)
				(arc
					(start 285.556198 -239.561624)
					(mid 285.520277 -239.576503)
					(end 285.505398 -239.612424)
				)
			)
		)
	)
	(zone
		(layers "In1.Cu" "In2.Cu")
		(hatch none 0.5)
		(connect_pads
			(clearance 0)
		)
		(min_thickness 0.25)
		(keepout
			(tracks not_allowed)
			(vias allowed)
			(pads allowed)
			(copperpour not_allowed)
			(footprints allowed)
		)
		(placement
			(enabled no)
			(sheetname "")
		)
		(fill yes
			(thermal_gap 0.5)
			(thermal_bridge_width 0.5)
			(island_removal_mode 0)
		)
		(polygon
			(pts
				(arc
					(start 184.794398 -268.921484)
					(mid 184.809277 -268.957405)
					(end 184.845198 -268.972284)
				)
				(arc
					(start 186.244738 -268.972284)
					(mid 186.280659 -268.957405)
					(end 186.295538 -268.921484)
				)
				(arc
					(start 186.295538 -268.512544)
					(mid 186.280659 -268.476623)
					(end 186.244738 -268.461744)
				)
				(arc
					(start 184.845198 -268.461744)
					(mid 184.809277 -268.476623)
					(end 184.794398 -268.512544)
				)
			)
		)
	)
	(zone
		(layers "In1.Cu" "In2.Cu")
		(hatch none 0.5)
		(connect_pads
			(clearance 0)
		)
		(min_thickness 0.25)
		(keepout
			(tracks not_allowed)
			(vias allowed)
			(pads allowed)
			(copperpour not_allowed)
			(footprints allowed)
		)
		(placement
			(enabled no)
			(sheetname "")
		)
		(fill yes
			(thermal_gap 0.5)
			(thermal_bridge_width 0.5)
			(island_removal_mode 0)
		)
		(polygon
			(pts
				(arc
					(start 203.32573 -277.42134)
					(mid 203.340609 -277.457261)
					(end 203.37653 -277.47214)
				)
				(arc
					(start 204.77607 -277.47214)
					(mid 204.811991 -277.457261)
					(end 204.82687 -277.42134)
				)
				(arc
					(start 204.82687 -277.0124)
					(mid 204.811991 -276.976479)
					(end 204.77607 -276.9616)
				)
				(arc
					(start 203.37653 -276.9616)
					(mid 203.340609 -276.976479)
					(end 203.32573 -277.0124)
				)
			)
		)
	)
	(zone
		(layers "In1.Cu" "In2.Cu")
		(hatch none 0.5)
		(connect_pads
			(clearance 0)
		)
		(min_thickness 0.25)
		(keepout
			(tracks not_allowed)
			(vias allowed)
			(pads allowed)
			(copperpour not_allowed)
			(footprints allowed)
		)
		(placement
			(enabled no)
			(sheetname "")
		)
		(fill yes
			(thermal_gap 0.5)
			(thermal_bridge_width 0.5)
			(island_removal_mode 0)
		)
		(polygon
			(pts
				(arc
					(start 428.634398 -244.271292)
					(mid 428.649277 -244.307213)
					(end 428.685198 -244.322092)
				)
				(arc
					(start 430.084738 -244.322092)
					(mid 430.120659 -244.307213)
					(end 430.135538 -244.271292)
				)
				(arc
					(start 430.135538 -243.862352)
					(mid 430.120659 -243.826431)
					(end 430.084738 -243.811552)
				)
				(arc
					(start 428.685198 -243.811552)
					(mid 428.649277 -243.826431)
					(end 428.634398 -243.862352)
				)
			)
		)
	)
	(zone
		(layers "In1.Cu" "In2.Cu")
		(hatch none 0.5)
		(connect_pads
			(clearance 0)
		)
		(min_thickness 0.25)
		(keepout
			(tracks not_allowed)
			(vias allowed)
			(pads allowed)
			(copperpour not_allowed)
			(footprints allowed)
		)
		(placement
			(enabled no)
			(sheetname "")
		)
		(fill yes
			(thermal_gap 0.5)
			(thermal_bridge_width 0.5)
			(island_removal_mode 0)
		)
		(polygon
			(pts
				(arc
					(start 14.93393 -274.871434)
					(mid 14.948809 -274.907355)
					(end 14.98473 -274.922234)
				)
				(arc
					(start 16.38427 -274.922234)
					(mid 16.420191 -274.907355)
					(end 16.43507 -274.871434)
				)
				(arc
					(start 16.43507 -274.462494)
					(mid 16.420191 -274.426573)
					(end 16.38427 -274.411694)
				)
				(arc
					(start 14.98473 -274.411694)
					(mid 14.948809 -274.426573)
					(end 14.93393 -274.462494)
				)
			)
		)
	)
	(zone
		(layers "In1.Cu" "In2.Cu")
		(hatch none 0.5)
		(connect_pads
			(clearance 0)
		)
		(min_thickness 0.25)
		(keepout
			(tracks not_allowed)
			(vias allowed)
			(pads allowed)
			(copperpour not_allowed)
			(footprints allowed)
		)
		(placement
			(enabled no)
			(sheetname "")
		)
		(fill yes
			(thermal_gap 0.5)
			(thermal_bridge_width 0.5)
			(island_removal_mode 0)
		)
		(polygon
			(pts
				(arc
					(start 451.265798 -226.421442)
					(mid 451.280677 -226.457363)
					(end 451.316598 -226.472242)
				)
				(arc
					(start 452.716138 -226.472242)
					(mid 452.752059 -226.457363)
					(end 452.766938 -226.421442)
				)
				(arc
					(start 452.766938 -226.012502)
					(mid 452.752059 -225.976581)
					(end 452.716138 -225.961702)
				)
				(arc
					(start 451.316598 -225.961702)
					(mid 451.280677 -225.976581)
					(end 451.265798 -226.012502)
				)
			)
		)
	)
	(zone
		(layers "In1.Cu" "In2.Cu")
		(hatch none 0.5)
		(connect_pads
			(clearance 0)
		)
		(min_thickness 0.25)
		(keepout
			(tracks not_allowed)
			(vias allowed)
			(pads allowed)
			(copperpour not_allowed)
			(footprints allowed)
		)
		(placement
			(enabled no)
			(sheetname "")
		)
		(fill yes
			(thermal_gap 0.5)
			(thermal_bridge_width 0.5)
			(island_removal_mode 0)
		)
		(polygon
			(pts
				(arc
					(start 7.39013 -285.071312)
					(mid 7.405009 -285.107233)
					(end 7.44093 -285.122112)
				)
				(arc
					(start 8.84047 -285.122112)
					(mid 8.876391 -285.107233)
					(end 8.89127 -285.071312)
				)
				(arc
					(start 8.89127 -284.662372)
					(mid 8.876391 -284.626451)
					(end 8.84047 -284.611572)
				)
				(arc
					(start 7.44093 -284.611572)
					(mid 7.405009 -284.626451)
					(end 7.39013 -284.662372)
				)
			)
		)
	)
	(zone
		(layers "In1.Cu" "In2.Cu")
		(hatch none 0.5)
		(connect_pads
			(clearance 0)
		)
		(min_thickness 0.25)
		(keepout
			(tracks not_allowed)
			(vias allowed)
			(pads allowed)
			(copperpour not_allowed)
			(footprints allowed)
		)
		(placement
			(enabled no)
			(sheetname "")
		)
		(fill yes
			(thermal_gap 0.5)
			(thermal_bridge_width 0.5)
			(island_removal_mode 0)
		)
		(polygon
			(pts
				(arc
					(start 188.23813 -266.371324)
					(mid 188.253009 -266.407245)
					(end 188.28893 -266.422124)
				)
				(arc
					(start 189.68847 -266.422124)
					(mid 189.724391 -266.407245)
					(end 189.73927 -266.371324)
				)
				(arc
					(start 189.73927 -265.962384)
					(mid 189.724391 -265.926463)
					(end 189.68847 -265.911584)
				)
				(arc
					(start 188.28893 -265.911584)
					(mid 188.253009 -265.926463)
					(end 188.23813 -265.962384)
				)
			)
		)
	)
	(zone
		(layers "In1.Cu" "In2.Cu")
		(hatch none 0.5)
		(connect_pads
			(clearance 0)
		)
		(min_thickness 0.25)
		(keepout
			(tracks not_allowed)
			(vias allowed)
			(pads allowed)
			(copperpour not_allowed)
			(footprints allowed)
		)
		(placement
			(enabled no)
			(sheetname "")
		)
		(fill yes
			(thermal_gap 0.5)
			(thermal_bridge_width 0.5)
			(island_removal_mode 0)
		)
		(polygon
			(pts
				(arc
					(start 56.752998 -199.221344)
					(mid 56.767877 -199.257265)
					(end 56.803798 -199.272144)
				)
				(arc
					(start 58.203338 -199.272144)
					(mid 58.239259 -199.257265)
					(end 58.254138 -199.221344)
				)
				(arc
					(start 58.254138 -198.812404)
					(mid 58.239259 -198.776483)
					(end 58.203338 -198.761604)
				)
				(arc
					(start 56.803798 -198.761604)
					(mid 56.767877 -198.776483)
					(end 56.752998 -198.812404)
				)
			)
		)
	)
	(zone
		(layers "In1.Cu" "In2.Cu")
		(hatch none 0.5)
		(connect_pads
			(clearance 0)
		)
		(min_thickness 0.25)
		(keepout
			(tracks not_allowed)
			(vias allowed)
			(pads allowed)
			(copperpour not_allowed)
			(footprints allowed)
		)
		(placement
			(enabled no)
			(sheetname "")
		)
		(fill yes
			(thermal_gap 0.5)
			(thermal_bridge_width 0.5)
			(island_removal_mode 0)
		)
		(polygon
			(pts
				(arc
					(start 458.809598 -301.221394)
					(mid 458.824477 -301.257315)
					(end 458.860398 -301.272194)
				)
				(arc
					(start 460.259938 -301.272194)
					(mid 460.295859 -301.257315)
					(end 460.310738 -301.221394)
				)
				(arc
					(start 460.310738 -300.812454)
					(mid 460.295859 -300.776533)
					(end 460.259938 -300.761654)
				)
				(arc
					(start 458.860398 -300.761654)
					(mid 458.824477 -300.776533)
					(end 458.809598 -300.812454)
				)
			)
		)
	)
	(zone
		(layers "In1.Cu" "In2.Cu")
		(hatch none 0.5)
		(connect_pads
			(clearance 0)
		)
		(min_thickness 0.25)
		(keepout
			(tracks not_allowed)
			(vias allowed)
			(pads allowed)
			(copperpour not_allowed)
			(footprints allowed)
		)
		(placement
			(enabled no)
			(sheetname "")
		)
		(fill yes
			(thermal_gap 0.5)
			(thermal_bridge_width 0.5)
			(island_removal_mode 0)
		)
		(polygon
			(pts
				(arc
					(start 304.693066 -209.421476)
					(mid 304.707945 -209.457397)
					(end 304.743866 -209.472276)
				)
				(arc
					(start 306.143406 -209.472276)
					(mid 306.179327 -209.457397)
					(end 306.194206 -209.421476)
				)
				(arc
					(start 306.194206 -209.012536)
					(mid 306.179327 -208.976615)
					(end 306.143406 -208.961736)
				)
				(arc
					(start 304.743866 -208.961736)
					(mid 304.707945 -208.976615)
					(end 304.693066 -209.012536)
				)
			)
		)
	)
	(zone
		(layers "In1.Cu" "In2.Cu")
		(hatch none 0.5)
		(connect_pads
			(clearance 0)
		)
		(min_thickness 0.25)
		(keepout
			(tracks not_allowed)
			(vias allowed)
			(pads allowed)
			(copperpour not_allowed)
			(footprints allowed)
		)
		(placement
			(enabled no)
			(sheetname "")
		)
		(fill yes
			(thermal_gap 0.5)
			(thermal_bridge_width 0.5)
			(island_removal_mode 0)
		)
		(polygon
			(pts
				(arc
					(start 410.103066 -263.821418)
					(mid 410.117945 -263.857339)
					(end 410.153866 -263.872218)
				)
				(arc
					(start 411.553406 -263.872218)
					(mid 411.589327 -263.857339)
					(end 411.604206 -263.821418)
				)
				(arc
					(start 411.604206 -263.412478)
					(mid 411.589327 -263.376557)
					(end 411.553406 -263.361678)
				)
				(arc
					(start 410.153866 -263.361678)
					(mid 410.117945 -263.376557)
					(end 410.103066 -263.412478)
				)
			)
		)
	)
	(zone
		(layers "In1.Cu" "In2.Cu")
		(hatch none 0.5)
		(connect_pads
			(clearance 0)
		)
		(min_thickness 0.25)
		(keepout
			(tracks not_allowed)
			(vias allowed)
			(pads allowed)
			(copperpour not_allowed)
			(footprints allowed)
		)
		(placement
			(enabled no)
			(sheetname "")
		)
		(fill yes
			(thermal_gap 0.5)
			(thermal_bridge_width 0.5)
			(island_removal_mode 0)
		)
		(polygon
			(pts
				(arc
					(start 203.32573 -237.471458)
					(mid 203.340609 -237.507379)
					(end 203.37653 -237.522258)
				)
				(arc
					(start 204.77607 -237.522258)
					(mid 204.811991 -237.507379)
					(end 204.82687 -237.471458)
				)
				(arc
					(start 204.82687 -237.062518)
					(mid 204.811991 -237.026597)
					(end 204.77607 -237.011718)
				)
				(arc
					(start 203.37653 -237.011718)
					(mid 203.340609 -237.026597)
					(end 203.32573 -237.062518)
				)
			)
		)
	)
	(zone
		(layers "In1.Cu" "In2.Cu")
		(hatch none 0.5)
		(connect_pads
			(clearance 0)
		)
		(min_thickness 0.25)
		(keepout
			(tracks not_allowed)
			(vias allowed)
			(pads allowed)
			(copperpour not_allowed)
			(footprints allowed)
		)
		(placement
			(enabled no)
			(sheetname "")
		)
		(fill yes
			(thermal_gap 0.5)
			(thermal_bridge_width 0.5)
			(island_removal_mode 0)
		)
		(polygon
			(pts
				(arc
					(start 458.809598 -279.121362)
					(mid 458.824477 -279.157283)
					(end 458.860398 -279.172162)
				)
				(arc
					(start 460.259938 -279.172162)
					(mid 460.295859 -279.157283)
					(end 460.310738 -279.121362)
				)
				(arc
					(start 460.310738 -278.712422)
					(mid 460.295859 -278.676501)
					(end 460.259938 -278.661622)
				)
				(arc
					(start 458.860398 -278.661622)
					(mid 458.824477 -278.676501)
					(end 458.809598 -278.712422)
				)
			)
		)
	)
	(zone
		(layers "In1.Cu" "In2.Cu")
		(hatch none 0.5)
		(connect_pads
			(clearance 0)
		)
		(min_thickness 0.25)
		(keepout
			(tracks not_allowed)
			(vias allowed)
			(pads allowed)
			(copperpour not_allowed)
			(footprints allowed)
		)
		(placement
			(enabled no)
			(sheetname "")
		)
		(fill yes
			(thermal_gap 0.5)
			(thermal_bridge_width 0.5)
			(island_removal_mode 0)
		)
		(polygon
			(pts
				(arc
					(start 425.190666 -248.521474)
					(mid 425.205545 -248.557395)
					(end 425.241466 -248.572274)
				)
				(arc
					(start 426.641006 -248.572274)
					(mid 426.676927 -248.557395)
					(end 426.691806 -248.521474)
				)
				(arc
					(start 426.691806 -248.112534)
					(mid 426.676927 -248.076613)
					(end 426.641006 -248.061734)
				)
				(arc
					(start 425.241466 -248.061734)
					(mid 425.205545 -248.076613)
					(end 425.190666 -248.112534)
				)
			)
		)
	)
	(zone
		(layers "In1.Cu" "In2.Cu")
		(hatch none 0.5)
		(connect_pads
			(clearance 0)
		)
		(min_thickness 0.25)
		(keepout
			(tracks not_allowed)
			(vias allowed)
			(pads allowed)
			(copperpour not_allowed)
			(footprints allowed)
		)
		(placement
			(enabled no)
			(sheetname "")
		)
		(fill yes
			(thermal_gap 0.5)
			(thermal_bridge_width 0.5)
			(island_removal_mode 0)
		)
		(polygon
			(pts
				(arc
					(start 447.822066 -216.22131)
					(mid 447.836945 -216.257231)
					(end 447.872866 -216.27211)
				)
				(arc
					(start 449.272406 -216.27211)
					(mid 449.308327 -216.257231)
					(end 449.323206 -216.22131)
				)
				(arc
					(start 449.323206 -215.81237)
					(mid 449.308327 -215.776449)
					(end 449.272406 -215.76157)
				)
				(arc
					(start 447.872866 -215.76157)
					(mid 447.836945 -215.776449)
					(end 447.822066 -215.81237)
				)
			)
		)
	)
	(zone
		(layers "In1.Cu" "In2.Cu")
		(hatch none 0.5)
		(connect_pads
			(clearance 0)
		)
		(min_thickness 0.25)
		(keepout
			(tracks not_allowed)
			(vias allowed)
			(pads allowed)
			(copperpour not_allowed)
			(footprints allowed)
		)
		(placement
			(enabled no)
			(sheetname "")
		)
		(fill yes
			(thermal_gap 0.5)
			(thermal_bridge_width 0.5)
			(island_removal_mode 0)
		)
		(polygon
			(pts
				(arc
					(start 293.049198 -240.021364)
					(mid 293.064077 -240.057285)
					(end 293.099998 -240.072164)
				)
				(arc
					(start 294.499538 -240.072164)
					(mid 294.535459 -240.057285)
					(end 294.550338 -240.021364)
				)
				(arc
					(start 294.550338 -239.612424)
					(mid 294.535459 -239.576503)
					(end 294.499538 -239.561624)
				)
				(arc
					(start 293.099998 -239.561624)
					(mid 293.064077 -239.576503)
					(end 293.049198 -239.612424)
				)
			)
		)
	)
	(zone
		(layers "In1.Cu" "In2.Cu")
		(hatch none 0.5)
		(connect_pads
			(clearance 0)
		)
		(min_thickness 0.25)
		(keepout
			(tracks not_allowed)
			(vias allowed)
			(pads allowed)
			(copperpour not_allowed)
			(footprints allowed)
		)
		(placement
			(enabled no)
			(sheetname "")
		)
		(fill yes
			(thermal_gap 0.5)
			(thermal_bridge_width 0.5)
			(island_removal_mode 0)
		)
		(polygon
			(pts
				(arc
					(start 45.10913 -262.971534)
					(mid 45.124009 -263.007455)
					(end 45.15993 -263.022334)
				)
				(arc
					(start 46.55947 -263.022334)
					(mid 46.595391 -263.007455)
					(end 46.61027 -262.971534)
				)
				(arc
					(start 46.61027 -262.562594)
					(mid 46.595391 -262.526673)
					(end 46.55947 -262.511794)
				)
				(arc
					(start 45.15993 -262.511794)
					(mid 45.124009 -262.526673)
					(end 45.10913 -262.562594)
				)
			)
		)
	)
	(zone
		(layers "In1.Cu" "In2.Cu")
		(hatch none 0.5)
		(connect_pads
			(clearance 0)
		)
		(min_thickness 0.25)
		(keepout
			(tracks not_allowed)
			(vias allowed)
			(pads allowed)
			(copperpour not_allowed)
			(footprints allowed)
		)
		(placement
			(enabled no)
			(sheetname "")
		)
		(fill yes
			(thermal_gap 0.5)
			(thermal_bridge_width 0.5)
			(island_removal_mode 0)
		)
		(polygon
			(pts
				(arc
					(start 436.178198 -237.471458)
					(mid 436.193077 -237.507379)
					(end 436.228998 -237.522258)
				)
				(arc
					(start 437.628538 -237.522258)
					(mid 437.664459 -237.507379)
					(end 437.679338 -237.471458)
				)
				(arc
					(start 437.679338 -237.062518)
					(mid 437.664459 -237.026597)
					(end 437.628538 -237.011718)
				)
				(arc
					(start 436.228998 -237.011718)
					(mid 436.193077 -237.026597)
					(end 436.178198 -237.062518)
				)
			)
		)
	)
	(zone
		(layers "In1.Cu" "In2.Cu")
		(hatch none 0.5)
		(connect_pads
			(clearance 0)
		)
		(min_thickness 0.25)
		(keepout
			(tracks not_allowed)
			(vias allowed)
			(pads allowed)
			(copperpour not_allowed)
			(footprints allowed)
		)
		(placement
			(enabled no)
			(sheetname "")
		)
		(fill yes
			(thermal_gap 0.5)
			(thermal_bridge_width 0.5)
			(island_removal_mode 0)
		)
		(polygon
			(pts
				(arc
					(start 432.734466 -223.871536)
					(mid 432.749345 -223.907457)
					(end 432.785266 -223.922336)
				)
				(arc
					(start 434.184806 -223.922336)
					(mid 434.220727 -223.907457)
					(end 434.235606 -223.871536)
				)
				(arc
					(start 434.235606 -223.462596)
					(mid 434.220727 -223.426675)
					(end 434.184806 -223.411796)
				)
				(arc
					(start 432.785266 -223.411796)
					(mid 432.749345 -223.426675)
					(end 432.734466 -223.462596)
				)
			)
		)
	)
	(zone
		(layers "In1.Cu" "In2.Cu")
		(hatch none 0.5)
		(connect_pads
			(clearance 0)
		)
		(min_thickness 0.25)
		(keepout
			(tracks not_allowed)
			(vias allowed)
			(pads allowed)
			(copperpour not_allowed)
			(footprints allowed)
		)
		(placement
			(enabled no)
			(sheetname "")
		)
		(fill yes
			(thermal_gap 0.5)
			(thermal_bridge_width 0.5)
			(island_removal_mode 0)
		)
		(polygon
			(pts
				(arc
					(start 447.822066 -313.971432)
					(mid 447.836945 -314.007353)
					(end 447.872866 -314.022232)
				)
				(arc
					(start 449.272406 -314.022232)
					(mid 449.308327 -314.007353)
					(end 449.323206 -313.971432)
				)
				(arc
					(start 449.323206 -313.562492)
					(mid 449.308327 -313.526571)
					(end 449.272406 -313.511692)
				)
				(arc
					(start 447.872866 -313.511692)
					(mid 447.836945 -313.526571)
					(end 447.822066 -313.562492)
				)
			)
		)
	)
	(zone
		(layers "In1.Cu" "In2.Cu")
		(hatch none 0.5)
		(connect_pads
			(clearance 0)
		)
		(min_thickness 0.25)
		(keepout
			(tracks not_allowed)
			(vias allowed)
			(pads allowed)
			(copperpour not_allowed)
			(footprints allowed)
		)
		(placement
			(enabled no)
			(sheetname "")
		)
		(fill yes
			(thermal_gap 0.5)
			(thermal_bridge_width 0.5)
			(island_removal_mode 0)
		)
		(polygon
			(pts
				(arc
					(start 308.136798 -312.27141)
					(mid 308.151677 -312.307331)
					(end 308.187598 -312.32221)
				)
				(arc
					(start 309.587138 -312.32221)
					(mid 309.623059 -312.307331)
					(end 309.637938 -312.27141)
				)
				(arc
					(start 309.637938 -311.86247)
					(mid 309.623059 -311.826549)
					(end 309.587138 -311.81167)
				)
				(arc
					(start 308.187598 -311.81167)
					(mid 308.151677 -311.826549)
					(end 308.136798 -311.86247)
				)
			)
		)
	)
	(zone
		(layers "In1.Cu" "In2.Cu")
		(hatch none 0.5)
		(connect_pads
			(clearance 0)
		)
		(min_thickness 0.25)
		(keepout
			(tracks not_allowed)
			(vias allowed)
			(pads allowed)
			(copperpour not_allowed)
			(footprints allowed)
		)
		(placement
			(enabled no)
			(sheetname "")
		)
		(fill yes
			(thermal_gap 0.5)
			(thermal_bridge_width 0.5)
			(island_removal_mode 0)
		)
		(polygon
			(pts
				(arc
					(start 30.02153 -245.971314)
					(mid 30.036409 -246.007235)
					(end 30.07233 -246.022114)
				)
				(arc
					(start 31.47187 -246.022114)
					(mid 31.507791 -246.007235)
					(end 31.52267 -245.971314)
				)
				(arc
					(start 31.52267 -245.562374)
					(mid 31.507791 -245.526453)
					(end 31.47187 -245.511574)
				)
				(arc
					(start 30.07233 -245.511574)
					(mid 30.036409 -245.526453)
					(end 30.02153 -245.562374)
				)
			)
		)
	)
	(zone
		(layers "In1.Cu" "In2.Cu")
		(hatch none 0.5)
		(connect_pads
			(clearance 0)
		)
		(min_thickness 0.25)
		(keepout
			(tracks not_allowed)
			(vias allowed)
			(pads allowed)
			(copperpour not_allowed)
			(footprints allowed)
		)
		(placement
			(enabled no)
			(sheetname "")
		)
		(fill yes
			(thermal_gap 0.5)
			(thermal_bridge_width 0.5)
			(island_removal_mode 0)
		)
		(polygon
			(pts
				(arc
					(start 64.296798 -233.22153)
					(mid 64.311677 -233.257451)
					(end 64.347598 -233.27233)
				)
				(arc
					(start 65.747138 -233.27233)
					(mid 65.783059 -233.257451)
					(end 65.797938 -233.22153)
				)
				(arc
					(start 65.797938 -232.81259)
					(mid 65.783059 -232.776669)
					(end 65.747138 -232.76179)
				)
				(arc
					(start 64.347598 -232.76179)
					(mid 64.311677 -232.776669)
					(end 64.296798 -232.81259)
				)
			)
		)
	)
	(zone
		(layers "In1.Cu" "In2.Cu")
		(hatch none 0.5)
		(connect_pads
			(clearance 0)
		)
		(min_thickness 0.25)
		(keepout
			(tracks not_allowed)
			(vias allowed)
			(pads allowed)
			(copperpour not_allowed)
			(footprints allowed)
		)
		(placement
			(enabled no)
			(sheetname "")
		)
		(fill yes
			(thermal_gap 0.5)
			(thermal_bridge_width 0.5)
			(island_removal_mode 0)
		)
		(polygon
			(pts
				(arc
					(start 274.517866 -251.921518)
					(mid 274.532745 -251.957439)
					(end 274.568666 -251.972318)
				)
				(arc
					(start 275.968206 -251.972318)
					(mid 276.004127 -251.957439)
					(end 276.019006 -251.921518)
				)
				(arc
					(start 276.019006 -251.512578)
					(mid 276.004127 -251.476657)
					(end 275.968206 -251.461778)
				)
				(arc
					(start 274.568666 -251.461778)
					(mid 274.532745 -251.476657)
					(end 274.517866 -251.512578)
				)
			)
		)
	)
	(zone
		(layers "In1.Cu" "In2.Cu")
		(hatch none 0.5)
		(connect_pads
			(clearance 0)
		)
		(min_thickness 0.25)
		(keepout
			(tracks not_allowed)
			(vias allowed)
			(pads allowed)
			(copperpour not_allowed)
			(footprints allowed)
		)
		(placement
			(enabled no)
			(sheetname "")
		)
		(fill yes
			(thermal_gap 0.5)
			(thermal_bridge_width 0.5)
			(island_removal_mode 0)
		)
		(polygon
			(pts
				(arc
					(start 165.60673 -297.82135)
					(mid 165.621609 -297.857271)
					(end 165.65753 -297.87215)
				)
				(arc
					(start 167.05707 -297.87215)
					(mid 167.092991 -297.857271)
					(end 167.10787 -297.82135)
				)
				(arc
					(start 167.10787 -297.41241)
					(mid 167.092991 -297.376489)
					(end 167.05707 -297.36161)
				)
				(arc
					(start 165.65753 -297.36161)
					(mid 165.621609 -297.376489)
					(end 165.60673 -297.41241)
				)
			)
		)
	)
	(zone
		(layers "In1.Cu" "In2.Cu")
		(hatch none 0.5)
		(connect_pads
			(clearance 0)
		)
		(min_thickness 0.25)
		(keepout
			(tracks not_allowed)
			(vias allowed)
			(pads allowed)
			(copperpour not_allowed)
			(footprints allowed)
		)
		(placement
			(enabled no)
			(sheetname "")
		)
		(fill yes
			(thermal_gap 0.5)
			(thermal_bridge_width 0.5)
			(island_removal_mode 0)
		)
		(polygon
			(pts
				(arc
					(start 173.15053 -264.671302)
					(mid 173.165409 -264.707223)
					(end 173.20133 -264.722102)
				)
				(arc
					(start 174.60087 -264.722102)
					(mid 174.636791 -264.707223)
					(end 174.65167 -264.671302)
				)
				(arc
					(start 174.65167 -264.262362)
					(mid 174.636791 -264.226441)
					(end 174.60087 -264.211562)
				)
				(arc
					(start 173.20133 -264.211562)
					(mid 173.165409 -264.226441)
					(end 173.15053 -264.262362)
				)
			)
		)
	)
	(zone
		(layers "In1.Cu" "In2.Cu")
		(hatch none 0.5)
		(connect_pads
			(clearance 0)
		)
		(min_thickness 0.25)
		(keepout
			(tracks not_allowed)
			(vias allowed)
			(pads allowed)
			(copperpour not_allowed)
			(footprints allowed)
		)
		(placement
			(enabled no)
			(sheetname "")
		)
		(fill yes
			(thermal_gap 0.5)
			(thermal_bridge_width 0.5)
			(island_removal_mode 0)
		)
		(polygon
			(pts
				(arc
					(start 14.93393 -211.971382)
					(mid 14.948809 -212.007303)
					(end 14.98473 -212.022182)
				)
				(arc
					(start 16.38427 -212.022182)
					(mid 16.420191 -212.007303)
					(end 16.43507 -211.971382)
				)
				(arc
					(start 16.43507 -211.562442)
					(mid 16.420191 -211.526521)
					(end 16.38427 -211.511642)
				)
				(arc
					(start 14.98473 -211.511642)
					(mid 14.948809 -211.526521)
					(end 14.93393 -211.562442)
				)
			)
		)
	)
	(zone
		(layers "In1.Cu" "In2.Cu")
		(hatch none 0.5)
		(connect_pads
			(clearance 0)
		)
		(min_thickness 0.25)
		(keepout
			(tracks not_allowed)
			(vias allowed)
			(pads allowed)
			(copperpour not_allowed)
			(footprints allowed)
		)
		(placement
			(enabled no)
			(sheetname "")
		)
		(fill yes
			(thermal_gap 0.5)
			(thermal_bridge_width 0.5)
			(island_removal_mode 0)
		)
		(polygon
			(pts
				(arc
					(start 177.250598 -270.621506)
					(mid 177.265477 -270.657427)
					(end 177.301398 -270.672306)
				)
				(arc
					(start 178.700938 -270.672306)
					(mid 178.736859 -270.657427)
					(end 178.751738 -270.621506)
				)
				(arc
					(start 178.751738 -270.212566)
					(mid 178.736859 -270.176645)
					(end 178.700938 -270.161766)
				)
				(arc
					(start 177.301398 -270.161766)
					(mid 177.265477 -270.176645)
					(end 177.250598 -270.212566)
				)
			)
		)
	)
	(zone
		(layers "In1.Cu" "In2.Cu")
		(hatch none 0.5)
		(connect_pads
			(clearance 0)
		)
		(min_thickness 0.25)
		(keepout
			(tracks not_allowed)
			(vias allowed)
			(pads allowed)
			(copperpour not_allowed)
			(footprints allowed)
		)
		(placement
			(enabled no)
			(sheetname "")
		)
		(fill yes
			(thermal_gap 0.5)
			(thermal_bridge_width 0.5)
			(island_removal_mode 0)
		)
		(polygon
			(pts
				(arc
					(start 293.049198 -296.121328)
					(mid 293.064077 -296.157249)
					(end 293.099998 -296.172128)
				)
				(arc
					(start 294.499538 -296.172128)
					(mid 294.535459 -296.157249)
					(end 294.550338 -296.121328)
				)
				(arc
					(start 294.550338 -295.712388)
					(mid 294.535459 -295.676467)
					(end 294.499538 -295.661588)
				)
				(arc
					(start 293.099998 -295.661588)
					(mid 293.064077 -295.676467)
					(end 293.049198 -295.712388)
				)
			)
		)
	)
	(zone
		(layers "In1.Cu" "In2.Cu")
		(hatch none 0.5)
		(connect_pads
			(clearance 0)
		)
		(min_thickness 0.25)
		(keepout
			(tracks not_allowed)
			(vias allowed)
			(pads allowed)
			(copperpour not_allowed)
			(footprints allowed)
		)
		(placement
			(enabled no)
			(sheetname "")
		)
		(fill yes
			(thermal_gap 0.5)
			(thermal_bridge_width 0.5)
			(island_removal_mode 0)
		)
		(polygon
			(pts
				(arc
					(start 207.425798 -212.82152)
					(mid 207.440677 -212.857441)
					(end 207.476598 -212.87232)
				)
				(arc
					(start 208.876138 -212.87232)
					(mid 208.912059 -212.857441)
					(end 208.926938 -212.82152)
				)
				(arc
					(start 208.926938 -212.41258)
					(mid 208.912059 -212.376659)
					(end 208.876138 -212.36178)
				)
				(arc
					(start 207.476598 -212.36178)
					(mid 207.440677 -212.376659)
					(end 207.425798 -212.41258)
				)
			)
		)
	)
	(zone
		(layers "In1.Cu" "In2.Cu")
		(hatch none 0.5)
		(connect_pads
			(clearance 0)
		)
		(min_thickness 0.25)
		(keepout
			(tracks not_allowed)
			(vias allowed)
			(pads allowed)
			(copperpour not_allowed)
			(footprints allowed)
		)
		(placement
			(enabled no)
			(sheetname "")
		)
		(fill yes
			(thermal_gap 0.5)
			(thermal_bridge_width 0.5)
			(island_removal_mode 0)
		)
		(polygon
			(pts
				(arc
					(start 210.86953 -280.821384)
					(mid 210.884409 -280.857305)
					(end 210.92033 -280.872184)
				)
				(arc
					(start 212.31987 -280.872184)
					(mid 212.355791 -280.857305)
					(end 212.37067 -280.821384)
				)
				(arc
					(start 212.37067 -280.412444)
					(mid 212.355791 -280.376523)
					(end 212.31987 -280.361644)
				)
				(arc
					(start 210.92033 -280.361644)
					(mid 210.884409 -280.376523)
					(end 210.86953 -280.412444)
				)
			)
		)
	)
	(zone
		(layers "In1.Cu" "In2.Cu")
		(hatch none 0.5)
		(connect_pads
			(clearance 0)
		)
		(min_thickness 0.25)
		(keepout
			(tracks not_allowed)
			(vias allowed)
			(pads allowed)
			(copperpour not_allowed)
			(footprints allowed)
		)
		(placement
			(enabled no)
			(sheetname "")
		)
		(fill yes
			(thermal_gap 0.5)
			(thermal_bridge_width 0.5)
			(island_removal_mode 0)
		)
		(polygon
			(pts
				(arc
					(start 192.338198 -278.271478)
					(mid 192.353077 -278.307399)
					(end 192.388998 -278.322278)
				)
				(arc
					(start 193.788538 -278.322278)
					(mid 193.824459 -278.307399)
					(end 193.839338 -278.271478)
				)
				(arc
					(start 193.839338 -277.862538)
					(mid 193.824459 -277.826617)
					(end 193.788538 -277.811738)
				)
				(arc
					(start 192.388998 -277.811738)
					(mid 192.353077 -277.826617)
					(end 192.338198 -277.862538)
				)
			)
		)
	)
	(zone
		(layers "In1.Cu" "In2.Cu")
		(hatch none 0.5)
		(connect_pads
			(clearance 0)
		)
		(min_thickness 0.25)
		(keepout
			(tracks not_allowed)
			(vias allowed)
			(pads allowed)
			(copperpour not_allowed)
			(footprints allowed)
		)
		(placement
			(enabled no)
			(sheetname "")
		)
		(fill yes
			(thermal_gap 0.5)
			(thermal_bridge_width 0.5)
			(island_removal_mode 0)
		)
		(polygon
			(pts
				(arc
					(start 308.136798 -277.42134)
					(mid 308.151677 -277.457261)
					(end 308.187598 -277.47214)
				)
				(arc
					(start 309.587138 -277.47214)
					(mid 309.623059 -277.457261)
					(end 309.637938 -277.42134)
				)
				(arc
					(start 309.637938 -277.0124)
					(mid 309.623059 -276.976479)
					(end 309.587138 -276.9616)
				)
				(arc
					(start 308.187598 -276.9616)
					(mid 308.151677 -276.976479)
					(end 308.136798 -277.0124)
				)
			)
		)
	)
	(zone
		(layers "In1.Cu" "In2.Cu")
		(hatch none 0.5)
		(connect_pads
			(clearance 0)
		)
		(min_thickness 0.25)
		(keepout
			(tracks not_allowed)
			(vias allowed)
			(pads allowed)
			(copperpour not_allowed)
			(footprints allowed)
		)
		(placement
			(enabled no)
			(sheetname "")
		)
		(fill yes
			(thermal_gap 0.5)
			(thermal_bridge_width 0.5)
			(island_removal_mode 0)
		)
		(polygon
			(pts
				(arc
					(start 162.162998 -276.571456)
					(mid 162.177877 -276.607377)
					(end 162.213798 -276.622256)
				)
				(arc
					(start 163.613338 -276.622256)
					(mid 163.649259 -276.607377)
					(end 163.664138 -276.571456)
				)
				(arc
					(start 163.664138 -276.162516)
					(mid 163.649259 -276.126595)
					(end 163.613338 -276.111716)
				)
				(arc
					(start 162.213798 -276.111716)
					(mid 162.177877 -276.126595)
					(end 162.162998 -276.162516)
				)
			)
		)
	)
	(zone
		(layers "In1.Cu" "In2.Cu")
		(hatch none 0.5)
		(connect_pads
			(clearance 0)
		)
		(min_thickness 0.25)
		(keepout
			(tracks not_allowed)
			(vias allowed)
			(pads allowed)
			(copperpour not_allowed)
			(footprints allowed)
		)
		(placement
			(enabled no)
			(sheetname "")
		)
		(fill yes
			(thermal_gap 0.5)
			(thermal_bridge_width 0.5)
			(island_removal_mode 0)
		)
		(polygon
			(pts
				(arc
					(start 428.634398 -297.82135)
					(mid 428.649277 -297.857271)
					(end 428.685198 -297.87215)
				)
				(arc
					(start 430.084738 -297.87215)
					(mid 430.120659 -297.857271)
					(end 430.135538 -297.82135)
				)
				(arc
					(start 430.135538 -297.41241)
					(mid 430.120659 -297.376489)
					(end 430.084738 -297.36161)
				)
				(arc
					(start 428.685198 -297.36161)
					(mid 428.649277 -297.376489)
					(end 428.634398 -297.41241)
				)
			)
		)
	)
	(zone
		(layers "In1.Cu" "In2.Cu")
		(hatch none 0.5)
		(connect_pads
			(clearance 0)
		)
		(min_thickness 0.25)
		(keepout
			(tracks not_allowed)
			(vias allowed)
			(pads allowed)
			(copperpour not_allowed)
			(footprints allowed)
		)
		(placement
			(enabled no)
			(sheetname "")
		)
		(fill yes
			(thermal_gap 0.5)
			(thermal_bridge_width 0.5)
			(island_removal_mode 0)
		)
		(polygon
			(pts
				(arc
					(start 173.15053 -249.371358)
					(mid 173.165409 -249.407279)
					(end 173.20133 -249.422158)
				)
				(arc
					(start 174.60087 -249.422158)
					(mid 174.636791 -249.407279)
					(end 174.65167 -249.371358)
				)
				(arc
					(start 174.65167 -248.962418)
					(mid 174.636791 -248.926497)
					(end 174.60087 -248.911618)
				)
				(arc
					(start 173.20133 -248.911618)
					(mid 173.165409 -248.926497)
					(end 173.15053 -248.962418)
				)
			)
		)
	)
	(zone
		(layers "In1.Cu" "In2.Cu")
		(hatch none 0.5)
		(connect_pads
			(clearance 0)
		)
		(min_thickness 0.25)
		(keepout
			(tracks not_allowed)
			(vias allowed)
			(pads allowed)
			(copperpour not_allowed)
			(footprints allowed)
		)
		(placement
			(enabled no)
			(sheetname "")
		)
		(fill yes
			(thermal_gap 0.5)
			(thermal_bridge_width 0.5)
			(island_removal_mode 0)
		)
		(polygon
			(pts
				(arc
					(start 26.577798 -298.671488)
					(mid 26.592677 -298.707409)
					(end 26.628598 -298.722288)
				)
				(arc
					(start 28.028138 -298.722288)
					(mid 28.064059 -298.707409)
					(end 28.078938 -298.671488)
				)
				(arc
					(start 28.078938 -298.262548)
					(mid 28.064059 -298.226627)
					(end 28.028138 -298.211748)
				)
				(arc
					(start 26.628598 -298.211748)
					(mid 26.592677 -298.226627)
					(end 26.577798 -298.262548)
				)
			)
		)
	)
	(zone
		(layers "In1.Cu" "In2.Cu")
		(hatch none 0.5)
		(connect_pads
			(clearance 0)
		)
		(min_thickness 0.25)
		(keepout
			(tracks not_allowed)
			(vias allowed)
			(pads allowed)
			(copperpour not_allowed)
			(footprints allowed)
		)
		(placement
			(enabled no)
			(sheetname "")
		)
		(fill yes
			(thermal_gap 0.5)
			(thermal_bridge_width 0.5)
			(island_removal_mode 0)
		)
		(polygon
			(pts
				(arc
					(start 458.809598 -280.821384)
					(mid 458.824477 -280.857305)
					(end 458.860398 -280.872184)
				)
				(arc
					(start 460.259938 -280.872184)
					(mid 460.295859 -280.857305)
					(end 460.310738 -280.821384)
				)
				(arc
					(start 460.310738 -280.412444)
					(mid 460.295859 -280.376523)
					(end 460.259938 -280.361644)
				)
				(arc
					(start 458.860398 -280.361644)
					(mid 458.824477 -280.376523)
					(end 458.809598 -280.412444)
				)
			)
		)
	)
	(zone
		(layers "In1.Cu" "In2.Cu")
		(hatch none 0.5)
		(connect_pads
			(clearance 0)
		)
		(min_thickness 0.25)
		(keepout
			(tracks not_allowed)
			(vias allowed)
			(pads allowed)
			(copperpour not_allowed)
			(footprints allowed)
		)
		(placement
			(enabled no)
			(sheetname "")
		)
		(fill yes
			(thermal_gap 0.5)
			(thermal_bridge_width 0.5)
			(island_removal_mode 0)
		)
		(polygon
			(pts
				(arc
					(start 451.265798 -237.471458)
					(mid 451.280677 -237.507379)
					(end 451.316598 -237.522258)
				)
				(arc
					(start 452.716138 -237.522258)
					(mid 452.752059 -237.507379)
					(end 452.766938 -237.471458)
				)
				(arc
					(start 452.766938 -237.062518)
					(mid 452.752059 -237.026597)
					(end 452.716138 -237.011718)
				)
				(arc
					(start 451.316598 -237.011718)
					(mid 451.280677 -237.026597)
					(end 451.265798 -237.062518)
				)
			)
		)
	)
	(zone
		(layers "In1.Cu" "In2.Cu")
		(hatch none 0.5)
		(connect_pads
			(clearance 0)
		)
		(min_thickness 0.25)
		(keepout
			(tracks not_allowed)
			(vias allowed)
			(pads allowed)
			(copperpour not_allowed)
			(footprints allowed)
		)
		(placement
			(enabled no)
			(sheetname "")
		)
		(fill yes
			(thermal_gap 0.5)
			(thermal_bridge_width 0.5)
			(island_removal_mode 0)
		)
		(polygon
			(pts
				(arc
					(start 64.296798 -222.171514)
					(mid 64.311677 -222.207435)
					(end 64.347598 -222.222314)
				)
				(arc
					(start 65.747138 -222.222314)
					(mid 65.783059 -222.207435)
					(end 65.797938 -222.171514)
				)
				(arc
					(start 65.797938 -221.762574)
					(mid 65.783059 -221.726653)
					(end 65.747138 -221.711774)
				)
				(arc
					(start 64.347598 -221.711774)
					(mid 64.311677 -221.726653)
					(end 64.296798 -221.762574)
				)
			)
		)
	)
	(zone
		(layers "In1.Cu" "In2.Cu")
		(hatch none 0.5)
		(connect_pads
			(clearance 0)
		)
		(min_thickness 0.25)
		(keepout
			(tracks not_allowed)
			(vias allowed)
			(pads allowed)
			(copperpour not_allowed)
			(footprints allowed)
		)
		(placement
			(enabled no)
			(sheetname "")
		)
		(fill yes
			(thermal_gap 0.5)
			(thermal_bridge_width 0.5)
			(island_removal_mode 0)
		)
		(polygon
			(pts
				(arc
					(start 199.881998 -274.871434)
					(mid 199.896877 -274.907355)
					(end 199.932798 -274.922234)
				)
				(arc
					(start 201.332338 -274.922234)
					(mid 201.368259 -274.907355)
					(end 201.383138 -274.871434)
				)
				(arc
					(start 201.383138 -274.462494)
					(mid 201.368259 -274.426573)
					(end 201.332338 -274.411694)
				)
				(arc
					(start 199.932798 -274.411694)
					(mid 199.896877 -274.426573)
					(end 199.881998 -274.462494)
				)
			)
		)
	)
	(zone
		(layers "In1.Cu" "In2.Cu")
		(hatch none 0.5)
		(connect_pads
			(clearance 0)
		)
		(min_thickness 0.25)
		(keepout
			(tracks not_allowed)
			(vias allowed)
			(pads allowed)
			(copperpour not_allowed)
			(footprints allowed)
		)
		(placement
			(enabled no)
			(sheetname "")
		)
		(fill yes
			(thermal_gap 0.5)
			(thermal_bridge_width 0.5)
			(island_removal_mode 0)
		)
		(polygon
			(pts
				(arc
					(start 270.417798 -206.021432)
					(mid 270.432677 -206.057353)
					(end 270.468598 -206.072232)
				)
				(arc
					(start 271.868138 -206.072232)
					(mid 271.904059 -206.057353)
					(end 271.918938 -206.021432)
				)
				(arc
					(start 271.918938 -205.612492)
					(mid 271.904059 -205.576571)
					(end 271.868138 -205.561692)
				)
				(arc
					(start 270.468598 -205.561692)
					(mid 270.432677 -205.576571)
					(end 270.417798 -205.612492)
				)
			)
		)
	)
	(zone
		(layers "In1.Cu" "In2.Cu")
		(hatch none 0.5)
		(connect_pads
			(clearance 0)
		)
		(min_thickness 0.25)
		(keepout
			(tracks not_allowed)
			(vias allowed)
			(pads allowed)
			(copperpour not_allowed)
			(footprints allowed)
		)
		(placement
			(enabled no)
			(sheetname "")
		)
		(fill yes
			(thermal_gap 0.5)
			(thermal_bridge_width 0.5)
			(island_removal_mode 0)
		)
		(polygon
			(pts
				(arc
					(start 417.646866 -225.571304)
					(mid 417.661745 -225.607225)
					(end 417.697666 -225.622104)
				)
				(arc
					(start 419.097206 -225.622104)
					(mid 419.133127 -225.607225)
					(end 419.148006 -225.571304)
				)
				(arc
					(start 419.148006 -225.162364)
					(mid 419.133127 -225.126443)
					(end 419.097206 -225.111564)
				)
				(arc
					(start 417.697666 -225.111564)
					(mid 417.661745 -225.126443)
					(end 417.646866 -225.162364)
				)
			)
		)
	)
	(zone
		(layers "In1.Cu" "In2.Cu")
		(hatch none 0.5)
		(connect_pads
			(clearance 0)
		)
		(min_thickness 0.25)
		(keepout
			(tracks not_allowed)
			(vias allowed)
			(pads allowed)
			(copperpour not_allowed)
			(footprints allowed)
		)
		(placement
			(enabled no)
			(sheetname "")
		)
		(fill yes
			(thermal_gap 0.5)
			(thermal_bridge_width 0.5)
			(island_removal_mode 0)
		)
		(polygon
			(pts
				(arc
					(start 266.974066 -237.471458)
					(mid 266.988945 -237.507379)
					(end 267.024866 -237.522258)
				)
				(arc
					(start 268.424406 -237.522258)
					(mid 268.460327 -237.507379)
					(end 268.475206 -237.471458)
				)
				(arc
					(start 268.475206 -237.062518)
					(mid 268.460327 -237.026597)
					(end 268.424406 -237.011718)
				)
				(arc
					(start 267.024866 -237.011718)
					(mid 266.988945 -237.026597)
					(end 266.974066 -237.062518)
				)
			)
		)
	)
	(zone
		(layers "In1.Cu" "In2.Cu")
		(hatch none 0.5)
		(connect_pads
			(clearance 0)
		)
		(min_thickness 0.25)
		(keepout
			(tracks not_allowed)
			(vias allowed)
			(pads allowed)
			(copperpour not_allowed)
			(footprints allowed)
		)
		(placement
			(enabled no)
			(sheetname "")
		)
		(fill yes
			(thermal_gap 0.5)
			(thermal_bridge_width 0.5)
			(island_removal_mode 0)
		)
		(polygon
			(pts
				(arc
					(start 7.39013 -286.771334)
					(mid 7.405009 -286.807255)
					(end 7.44093 -286.822134)
				)
				(arc
					(start 8.84047 -286.822134)
					(mid 8.876391 -286.807255)
					(end 8.89127 -286.771334)
				)
				(arc
					(start 8.89127 -286.362394)
					(mid 8.876391 -286.326473)
					(end 8.84047 -286.311594)
				)
				(arc
					(start 7.44093 -286.311594)
					(mid 7.405009 -286.326473)
					(end 7.39013 -286.362394)
				)
			)
		)
	)
	(zone
		(layers "In1.Cu" "In2.Cu")
		(hatch none 0.5)
		(connect_pads
			(clearance 0)
		)
		(min_thickness 0.25)
		(keepout
			(tracks not_allowed)
			(vias allowed)
			(pads allowed)
			(copperpour not_allowed)
			(footprints allowed)
		)
		(placement
			(enabled no)
			(sheetname "")
		)
		(fill yes
			(thermal_gap 0.5)
			(thermal_bridge_width 0.5)
			(island_removal_mode 0)
		)
		(polygon
			(pts
				(arc
					(start 274.517866 -231.521508)
					(mid 274.532745 -231.557429)
					(end 274.568666 -231.572308)
				)
				(arc
					(start 275.968206 -231.572308)
					(mid 276.004127 -231.557429)
					(end 276.019006 -231.521508)
				)
				(arc
					(start 276.019006 -231.112568)
					(mid 276.004127 -231.076647)
					(end 275.968206 -231.061768)
				)
				(arc
					(start 274.568666 -231.061768)
					(mid 274.532745 -231.076647)
					(end 274.517866 -231.112568)
				)
			)
		)
	)
	(zone
		(layers "In1.Cu" "In2.Cu")
		(hatch none 0.5)
		(connect_pads
			(clearance 0)
		)
		(min_thickness 0.25)
		(keepout
			(tracks not_allowed)
			(vias allowed)
			(pads allowed)
			(copperpour not_allowed)
			(footprints allowed)
		)
		(placement
			(enabled no)
			(sheetname "")
		)
		(fill yes
			(thermal_gap 0.5)
			(thermal_bridge_width 0.5)
			(island_removal_mode 0)
		)
		(polygon
			(pts
				(arc
					(start 173.15053 -204.32141)
					(mid 173.165409 -204.357331)
					(end 173.20133 -204.37221)
				)
				(arc
					(start 174.60087 -204.37221)
					(mid 174.636791 -204.357331)
					(end 174.65167 -204.32141)
				)
				(arc
					(start 174.65167 -203.91247)
					(mid 174.636791 -203.876549)
					(end 174.60087 -203.86167)
				)
				(arc
					(start 173.20133 -203.86167)
					(mid 173.165409 -203.876549)
					(end 173.15053 -203.91247)
				)
			)
		)
	)
	(zone
		(layers "In1.Cu" "In2.Cu")
		(hatch none 0.5)
		(connect_pads
			(clearance 0)
		)
		(min_thickness 0.25)
		(keepout
			(tracks not_allowed)
			(vias allowed)
			(pads allowed)
			(copperpour not_allowed)
			(footprints allowed)
		)
		(placement
			(enabled no)
			(sheetname "")
		)
		(fill yes
			(thermal_gap 0.5)
			(thermal_bridge_width 0.5)
			(island_removal_mode 0)
		)
		(polygon
			(pts
				(arc
					(start 19.033998 -315.671454)
					(mid 19.048877 -315.707375)
					(end 19.084798 -315.722254)
				)
				(arc
					(start 20.484338 -315.722254)
					(mid 20.520259 -315.707375)
					(end 20.535138 -315.671454)
				)
				(arc
					(start 20.535138 -315.262514)
					(mid 20.520259 -315.226593)
					(end 20.484338 -315.211714)
				)
				(arc
					(start 19.084798 -315.211714)
					(mid 19.048877 -315.226593)
					(end 19.033998 -315.262514)
				)
			)
		)
	)
	(zone
		(layers "In1.Cu" "In2.Cu")
		(hatch none 0.5)
		(connect_pads
			(clearance 0)
		)
		(min_thickness 0.25)
		(keepout
			(tracks not_allowed)
			(vias allowed)
			(pads allowed)
			(copperpour not_allowed)
			(footprints allowed)
		)
		(placement
			(enabled no)
			(sheetname "")
		)
		(fill yes
			(thermal_gap 0.5)
			(thermal_bridge_width 0.5)
			(island_removal_mode 0)
		)
		(polygon
			(pts
				(arc
					(start 277.961598 -307.171344)
					(mid 277.976477 -307.207265)
					(end 278.012398 -307.222144)
				)
				(arc
					(start 279.411938 -307.222144)
					(mid 279.447859 -307.207265)
					(end 279.462738 -307.171344)
				)
				(arc
					(start 279.462738 -306.762404)
					(mid 279.447859 -306.726483)
					(end 279.411938 -306.711604)
				)
				(arc
					(start 278.012398 -306.711604)
					(mid 277.976477 -306.726483)
					(end 277.961598 -306.762404)
				)
			)
		)
	)
	(zone
		(layers "In1.Cu" "In2.Cu")
		(hatch none 0.5)
		(connect_pads
			(clearance 0)
		)
		(min_thickness 0.25)
		(keepout
			(tracks not_allowed)
			(vias allowed)
			(pads allowed)
			(copperpour not_allowed)
			(footprints allowed)
		)
		(placement
			(enabled no)
			(sheetname "")
		)
		(fill yes
			(thermal_gap 0.5)
			(thermal_bridge_width 0.5)
			(island_removal_mode 0)
		)
		(polygon
			(pts
				(arc
					(start 7.39013 -252.771402)
					(mid 7.405009 -252.807323)
					(end 7.44093 -252.822202)
				)
				(arc
					(start 8.84047 -252.822202)
					(mid 8.876391 -252.807323)
					(end 8.89127 -252.771402)
				)
				(arc
					(start 8.89127 -252.362462)
					(mid 8.876391 -252.326541)
					(end 8.84047 -252.311662)
				)
				(arc
					(start 7.44093 -252.311662)
					(mid 7.405009 -252.326541)
					(end 7.39013 -252.362462)
				)
			)
		)
	)
	(zone
		(layers "In1.Cu" "In2.Cu")
		(hatch none 0.5)
		(connect_pads
			(clearance 0)
		)
		(min_thickness 0.25)
		(keepout
			(tracks not_allowed)
			(vias allowed)
			(pads allowed)
			(copperpour not_allowed)
			(footprints allowed)
		)
		(placement
			(enabled no)
			(sheetname "")
		)
		(fill yes
			(thermal_gap 0.5)
			(thermal_bridge_width 0.5)
			(island_removal_mode 0)
		)
		(polygon
			(pts
				(arc
					(start 289.605466 -199.221344)
					(mid 289.620345 -199.257265)
					(end 289.656266 -199.272144)
				)
				(arc
					(start 291.055806 -199.272144)
					(mid 291.091727 -199.257265)
					(end 291.106606 -199.221344)
				)
				(arc
					(start 291.106606 -198.812404)
					(mid 291.091727 -198.776483)
					(end 291.055806 -198.761604)
				)
				(arc
					(start 289.656266 -198.761604)
					(mid 289.620345 -198.776483)
					(end 289.605466 -198.812404)
				)
			)
		)
	)
	(zone
		(layers "In1.Cu" "In2.Cu")
		(hatch none 0.5)
		(connect_pads
			(clearance 0)
		)
		(min_thickness 0.25)
		(keepout
			(tracks not_allowed)
			(vias allowed)
			(pads allowed)
			(copperpour not_allowed)
			(footprints allowed)
		)
		(placement
			(enabled no)
			(sheetname "")
		)
		(fill yes
			(thermal_gap 0.5)
			(thermal_bridge_width 0.5)
			(island_removal_mode 0)
		)
		(polygon
			(pts
				(arc
					(start 262.873998 -207.721454)
					(mid 262.888877 -207.757375)
					(end 262.924798 -207.772254)
				)
				(arc
					(start 264.324338 -207.772254)
					(mid 264.360259 -207.757375)
					(end 264.375138 -207.721454)
				)
				(arc
					(start 264.375138 -207.312514)
					(mid 264.360259 -207.276593)
					(end 264.324338 -207.261714)
				)
				(arc
					(start 262.924798 -207.261714)
					(mid 262.888877 -207.276593)
					(end 262.873998 -207.312514)
				)
			)
		)
	)
	(zone
		(layers "In1.Cu" "In2.Cu")
		(hatch none 0.5)
		(connect_pads
			(clearance 0)
		)
		(min_thickness 0.25)
		(keepout
			(tracks not_allowed)
			(vias allowed)
			(pads allowed)
			(copperpour not_allowed)
			(footprints allowed)
		)
		(placement
			(enabled no)
			(sheetname "")
		)
		(fill yes
			(thermal_gap 0.5)
			(thermal_bridge_width 0.5)
			(island_removal_mode 0)
		)
		(polygon
			(pts
				(arc
					(start 26.577798 -315.671454)
					(mid 26.592677 -315.707375)
					(end 26.628598 -315.722254)
				)
				(arc
					(start 28.028138 -315.722254)
					(mid 28.064059 -315.707375)
					(end 28.078938 -315.671454)
				)
				(arc
					(start 28.078938 -315.262514)
					(mid 28.064059 -315.226593)
					(end 28.028138 -315.211714)
				)
				(arc
					(start 26.628598 -315.211714)
					(mid 26.592677 -315.226593)
					(end 26.577798 -315.262514)
				)
			)
		)
	)
	(zone
		(layers "In1.Cu" "In2.Cu")
		(hatch none 0.5)
		(connect_pads
			(clearance 0)
		)
		(min_thickness 0.25)
		(keepout
			(tracks not_allowed)
			(vias allowed)
			(pads allowed)
			(copperpour not_allowed)
			(footprints allowed)
		)
		(placement
			(enabled no)
			(sheetname "")
		)
		(fill yes
			(thermal_gap 0.5)
			(thermal_bridge_width 0.5)
			(island_removal_mode 0)
		)
		(polygon
			(pts
				(arc
					(start 413.546798 -268.071346)
					(mid 413.561677 -268.107267)
					(end 413.597598 -268.122146)
				)
				(arc
					(start 414.997138 -268.122146)
					(mid 415.033059 -268.107267)
					(end 415.047938 -268.071346)
				)
				(arc
					(start 415.047938 -267.662406)
					(mid 415.033059 -267.626485)
					(end 414.997138 -267.611606)
				)
				(arc
					(start 413.597598 -267.611606)
					(mid 413.561677 -267.626485)
					(end 413.546798 -267.662406)
				)
			)
		)
	)
	(zone
		(layers "In1.Cu" "In2.Cu")
		(hatch none 0.5)
		(connect_pads
			(clearance 0)
		)
		(min_thickness 0.25)
		(keepout
			(tracks not_allowed)
			(vias allowed)
			(pads allowed)
			(copperpour not_allowed)
			(footprints allowed)
		)
		(placement
			(enabled no)
			(sheetname "")
		)
		(fill yes
			(thermal_gap 0.5)
			(thermal_bridge_width 0.5)
			(island_removal_mode 0)
		)
		(polygon
			(pts
				(arc
					(start 37.56533 -275.721318)
					(mid 37.580209 -275.757239)
					(end 37.61613 -275.772118)
				)
				(arc
					(start 39.01567 -275.772118)
					(mid 39.051591 -275.757239)
					(end 39.06647 -275.721318)
				)
				(arc
					(start 39.06647 -275.312378)
					(mid 39.051591 -275.276457)
					(end 39.01567 -275.261578)
				)
				(arc
					(start 37.61613 -275.261578)
					(mid 37.580209 -275.276457)
					(end 37.56533 -275.312378)
				)
			)
		)
	)
	(zone
		(layers "In1.Cu" "In2.Cu")
		(hatch none 0.5)
		(connect_pads
			(clearance 0)
		)
		(min_thickness 0.25)
		(keepout
			(tracks not_allowed)
			(vias allowed)
			(pads allowed)
			(copperpour not_allowed)
			(footprints allowed)
		)
		(placement
			(enabled no)
			(sheetname "")
		)
		(fill yes
			(thermal_gap 0.5)
			(thermal_bridge_width 0.5)
			(island_removal_mode 0)
		)
		(polygon
			(pts
				(arc
					(start 173.15053 -308.871366)
					(mid 173.165409 -308.907287)
					(end 173.20133 -308.922166)
				)
				(arc
					(start 174.60087 -308.922166)
					(mid 174.636791 -308.907287)
					(end 174.65167 -308.871366)
				)
				(arc
					(start 174.65167 -308.462426)
					(mid 174.636791 -308.426505)
					(end 174.60087 -308.411626)
				)
				(arc
					(start 173.20133 -308.411626)
					(mid 173.165409 -308.426505)
					(end 173.15053 -308.462426)
				)
			)
		)
	)
	(zone
		(layers "In1.Cu" "In2.Cu")
		(hatch none 0.5)
		(connect_pads
			(clearance 0)
		)
		(min_thickness 0.25)
		(keepout
			(tracks not_allowed)
			(vias allowed)
			(pads allowed)
			(copperpour not_allowed)
			(footprints allowed)
		)
		(placement
			(enabled no)
			(sheetname "")
		)
		(fill yes
			(thermal_gap 0.5)
			(thermal_bridge_width 0.5)
			(island_removal_mode 0)
		)
		(polygon
			(pts
				(arc
					(start 436.178198 -291.8714)
					(mid 436.193077 -291.907321)
					(end 436.228998 -291.9222)
				)
				(arc
					(start 437.628538 -291.9222)
					(mid 437.664459 -291.907321)
					(end 437.679338 -291.8714)
				)
				(arc
					(start 437.679338 -291.46246)
					(mid 437.664459 -291.426539)
					(end 437.628538 -291.41166)
				)
				(arc
					(start 436.228998 -291.41166)
					(mid 436.193077 -291.426539)
					(end 436.178198 -291.46246)
				)
			)
		)
	)
	(zone
		(layers "In1.Cu" "In2.Cu")
		(hatch none 0.5)
		(connect_pads
			(clearance 0)
		)
		(min_thickness 0.25)
		(keepout
			(tracks not_allowed)
			(vias allowed)
			(pads allowed)
			(copperpour not_allowed)
			(footprints allowed)
		)
		(placement
			(enabled no)
			(sheetname "")
		)
		(fill yes
			(thermal_gap 0.5)
			(thermal_bridge_width 0.5)
			(island_removal_mode 0)
		)
		(polygon
			(pts
				(arc
					(start 41.665398 -199.221344)
					(mid 41.680277 -199.257265)
					(end 41.716198 -199.272144)
				)
				(arc
					(start 43.115738 -199.272144)
					(mid 43.151659 -199.257265)
					(end 43.166538 -199.221344)
				)
				(arc
					(start 43.166538 -198.812404)
					(mid 43.151659 -198.776483)
					(end 43.115738 -198.761604)
				)
				(arc
					(start 41.716198 -198.761604)
					(mid 41.680277 -198.776483)
					(end 41.665398 -198.812404)
				)
			)
		)
	)
	(zone
		(layers "In1.Cu" "In2.Cu")
		(hatch none 0.5)
		(connect_pads
			(clearance 0)
		)
		(min_thickness 0.25)
		(keepout
			(tracks not_allowed)
			(vias allowed)
			(pads allowed)
			(copperpour not_allowed)
			(footprints allowed)
		)
		(placement
			(enabled no)
			(sheetname "")
		)
		(fill yes
			(thermal_gap 0.5)
			(thermal_bridge_width 0.5)
			(island_removal_mode 0)
		)
		(polygon
			(pts
				(arc
					(start 64.296798 -274.02155)
					(mid 64.311677 -274.057471)
					(end 64.347598 -274.07235)
				)
				(arc
					(start 65.747138 -274.07235)
					(mid 65.783059 -274.057471)
					(end 65.797938 -274.02155)
				)
				(arc
					(start 65.797938 -273.61261)
					(mid 65.783059 -273.576689)
					(end 65.747138 -273.56181)
				)
				(arc
					(start 64.347598 -273.56181)
					(mid 64.311677 -273.576689)
					(end 64.296798 -273.61261)
				)
			)
		)
	)
	(zone
		(layers "In1.Cu" "In2.Cu")
		(hatch none 0.5)
		(connect_pads
			(clearance 0)
		)
		(min_thickness 0.25)
		(keepout
			(tracks not_allowed)
			(vias allowed)
			(pads allowed)
			(copperpour not_allowed)
			(footprints allowed)
		)
		(placement
			(enabled no)
			(sheetname "")
		)
		(fill yes
			(thermal_gap 0.5)
			(thermal_bridge_width 0.5)
			(island_removal_mode 0)
		)
		(polygon
			(pts
				(arc
					(start 19.033998 -206.871316)
					(mid 19.048877 -206.907237)
					(end 19.084798 -206.922116)
				)
				(arc
					(start 20.484338 -206.922116)
					(mid 20.520259 -206.907237)
					(end 20.535138 -206.871316)
				)
				(arc
					(start 20.535138 -206.462376)
					(mid 20.520259 -206.426455)
					(end 20.484338 -206.411576)
				)
				(arc
					(start 19.084798 -206.411576)
					(mid 19.048877 -206.426455)
					(end 19.033998 -206.462376)
				)
			)
		)
	)
	(zone
		(layers "In1.Cu" "In2.Cu")
		(hatch none 0.5)
		(connect_pads
			(clearance 0)
		)
		(min_thickness 0.25)
		(keepout
			(tracks not_allowed)
			(vias allowed)
			(pads allowed)
			(copperpour not_allowed)
			(footprints allowed)
		)
		(placement
			(enabled no)
			(sheetname "")
		)
		(fill yes
			(thermal_gap 0.5)
			(thermal_bridge_width 0.5)
			(island_removal_mode 0)
		)
		(polygon
			(pts
				(arc
					(start 458.809598 -259.57149)
					(mid 458.824477 -259.607411)
					(end 458.860398 -259.62229)
				)
				(arc
					(start 460.259938 -259.62229)
					(mid 460.295859 -259.607411)
					(end 460.310738 -259.57149)
				)
				(arc
					(start 460.310738 -259.16255)
					(mid 460.295859 -259.126629)
					(end 460.259938 -259.11175)
				)
				(arc
					(start 458.860398 -259.11175)
					(mid 458.824477 -259.126629)
					(end 458.809598 -259.16255)
				)
			)
		)
	)
	(zone
		(layers "In1.Cu" "In2.Cu")
		(hatch none 0.5)
		(connect_pads
			(clearance 0)
		)
		(min_thickness 0.25)
		(keepout
			(tracks not_allowed)
			(vias allowed)
			(pads allowed)
			(copperpour not_allowed)
			(footprints allowed)
		)
		(placement
			(enabled no)
			(sheetname "")
		)
		(fill yes
			(thermal_gap 0.5)
			(thermal_bridge_width 0.5)
			(island_removal_mode 0)
		)
		(polygon
			(pts
				(arc
					(start 64.296798 -229.821486)
					(mid 64.311677 -229.857407)
					(end 64.347598 -229.872286)
				)
				(arc
					(start 65.747138 -229.872286)
					(mid 65.783059 -229.857407)
					(end 65.797938 -229.821486)
				)
				(arc
					(start 65.797938 -229.412546)
					(mid 65.783059 -229.376625)
					(end 65.747138 -229.361746)
				)
				(arc
					(start 64.347598 -229.361746)
					(mid 64.311677 -229.376625)
					(end 64.296798 -229.412546)
				)
			)
		)
	)
	(zone
		(layers "In1.Cu" "In2.Cu")
		(hatch none 0.5)
		(connect_pads
			(clearance 0)
		)
		(min_thickness 0.25)
		(keepout
			(tracks not_allowed)
			(vias allowed)
			(pads allowed)
			(copperpour not_allowed)
			(footprints allowed)
		)
		(placement
			(enabled no)
			(sheetname "")
		)
		(fill yes
			(thermal_gap 0.5)
			(thermal_bridge_width 0.5)
			(island_removal_mode 0)
		)
		(polygon
			(pts
				(arc
					(start 417.646866 -267.221462)
					(mid 417.661745 -267.257383)
					(end 417.697666 -267.272262)
				)
				(arc
					(start 419.097206 -267.272262)
					(mid 419.133127 -267.257383)
					(end 419.148006 -267.221462)
				)
				(arc
					(start 419.148006 -266.812522)
					(mid 419.133127 -266.776601)
					(end 419.097206 -266.761722)
				)
				(arc
					(start 417.697666 -266.761722)
					(mid 417.661745 -266.776601)
					(end 417.646866 -266.812522)
				)
			)
		)
	)
	(zone
		(layers "In1.Cu" "In2.Cu")
		(hatch none 0.5)
		(connect_pads
			(clearance 0)
		)
		(min_thickness 0.25)
		(keepout
			(tracks not_allowed)
			(vias allowed)
			(pads allowed)
			(copperpour not_allowed)
			(footprints allowed)
		)
		(placement
			(enabled no)
			(sheetname "")
		)
		(fill yes
			(thermal_gap 0.5)
			(thermal_bridge_width 0.5)
			(island_removal_mode 0)
		)
		(polygon
			(pts
				(arc
					(start 259.430266 -270.621506)
					(mid 259.445145 -270.657427)
					(end 259.481066 -270.672306)
				)
				(arc
					(start 260.880606 -270.672306)
					(mid 260.916527 -270.657427)
					(end 260.931406 -270.621506)
				)
				(arc
					(start 260.931406 -270.212566)
					(mid 260.916527 -270.176645)
					(end 260.880606 -270.161766)
				)
				(arc
					(start 259.481066 -270.161766)
					(mid 259.445145 -270.176645)
					(end 259.430266 -270.212566)
				)
			)
		)
	)
	(zone
		(layers "In1.Cu" "In2.Cu")
		(hatch none 0.5)
		(connect_pads
			(clearance 0)
		)
		(min_thickness 0.25)
		(keepout
			(tracks not_allowed)
			(vias allowed)
			(pads allowed)
			(copperpour not_allowed)
			(footprints allowed)
		)
		(placement
			(enabled no)
			(sheetname "")
		)
		(fill yes
			(thermal_gap 0.5)
			(thermal_bridge_width 0.5)
			(island_removal_mode 0)
		)
		(polygon
			(pts
				(arc
					(start 455.365866 -237.471458)
					(mid 455.380745 -237.507379)
					(end 455.416666 -237.522258)
				)
				(arc
					(start 456.816206 -237.522258)
					(mid 456.852127 -237.507379)
					(end 456.867006 -237.471458)
				)
				(arc
					(start 456.867006 -237.062518)
					(mid 456.852127 -237.026597)
					(end 456.816206 -237.011718)
				)
				(arc
					(start 455.416666 -237.011718)
					(mid 455.380745 -237.026597)
					(end 455.365866 -237.062518)
				)
			)
		)
	)
	(zone
		(layers "In1.Cu" "In2.Cu")
		(hatch none 0.5)
		(connect_pads
			(clearance 0)
		)
		(min_thickness 0.25)
		(keepout
			(tracks not_allowed)
			(vias allowed)
			(pads allowed)
			(copperpour not_allowed)
			(footprints allowed)
		)
		(placement
			(enabled no)
			(sheetname "")
		)
		(fill yes
			(thermal_gap 0.5)
			(thermal_bridge_width 0.5)
			(island_removal_mode 0)
		)
		(polygon
			(pts
				(arc
					(start 158.06293 -301.221394)
					(mid 158.077809 -301.257315)
					(end 158.11373 -301.272194)
				)
				(arc
					(start 159.51327 -301.272194)
					(mid 159.549191 -301.257315)
					(end 159.56407 -301.221394)
				)
				(arc
					(start 159.56407 -300.812454)
					(mid 159.549191 -300.776533)
					(end 159.51327 -300.761654)
				)
				(arc
					(start 158.11373 -300.761654)
					(mid 158.077809 -300.776533)
					(end 158.06293 -300.812454)
				)
			)
		)
	)
	(zone
		(layers "In1.Cu" "In2.Cu")
		(hatch none 0.5)
		(connect_pads
			(clearance 0)
		)
		(min_thickness 0.25)
		(keepout
			(tracks not_allowed)
			(vias allowed)
			(pads allowed)
			(copperpour not_allowed)
			(footprints allowed)
		)
		(placement
			(enabled no)
			(sheetname "")
		)
		(fill yes
			(thermal_gap 0.5)
			(thermal_bridge_width 0.5)
			(island_removal_mode 0)
		)
		(polygon
			(pts
				(arc
					(start 169.706798 -287.621472)
					(mid 169.721677 -287.657393)
					(end 169.757598 -287.672272)
				)
				(arc
					(start 171.157138 -287.672272)
					(mid 171.193059 -287.657393)
					(end 171.207938 -287.621472)
				)
				(arc
					(start 171.207938 -287.212532)
					(mid 171.193059 -287.176611)
					(end 171.157138 -287.161732)
				)
				(arc
					(start 169.757598 -287.161732)
					(mid 169.721677 -287.176611)
					(end 169.706798 -287.212532)
				)
			)
		)
	)
	(zone
		(layers "In1.Cu" "In2.Cu")
		(hatch none 0.5)
		(connect_pads
			(clearance 0)
		)
		(min_thickness 0.25)
		(keepout
			(tracks not_allowed)
			(vias allowed)
			(pads allowed)
			(copperpour not_allowed)
			(footprints allowed)
		)
		(placement
			(enabled no)
			(sheetname "")
		)
		(fill yes
			(thermal_gap 0.5)
			(thermal_bridge_width 0.5)
			(island_removal_mode 0)
		)
		(polygon
			(pts
				(arc
					(start 199.881998 -306.32146)
					(mid 199.896877 -306.357381)
					(end 199.932798 -306.37226)
				)
				(arc
					(start 201.332338 -306.37226)
					(mid 201.368259 -306.357381)
					(end 201.383138 -306.32146)
				)
				(arc
					(start 201.383138 -305.91252)
					(mid 201.368259 -305.876599)
					(end 201.332338 -305.86172)
				)
				(arc
					(start 199.932798 -305.86172)
					(mid 199.896877 -305.876599)
					(end 199.881998 -305.91252)
				)
			)
		)
	)
	(zone
		(layers "In1.Cu" "In2.Cu")
		(hatch none 0.5)
		(connect_pads
			(clearance 0)
		)
		(min_thickness 0.25)
		(keepout
			(tracks not_allowed)
			(vias allowed)
			(pads allowed)
			(copperpour not_allowed)
			(footprints allowed)
		)
		(placement
			(enabled no)
			(sheetname "")
		)
		(fill yes
			(thermal_gap 0.5)
			(thermal_bridge_width 0.5)
			(island_removal_mode 0)
		)
		(polygon
			(pts
				(arc
					(start 26.577798 -216.22131)
					(mid 26.592677 -216.257231)
					(end 26.628598 -216.27211)
				)
				(arc
					(start 28.028138 -216.27211)
					(mid 28.064059 -216.257231)
					(end 28.078938 -216.22131)
				)
				(arc
					(start 28.078938 -215.81237)
					(mid 28.064059 -215.776449)
					(end 28.028138 -215.76157)
				)
				(arc
					(start 26.628598 -215.76157)
					(mid 26.592677 -215.776449)
					(end 26.577798 -215.81237)
				)
			)
		)
	)
	(zone
		(layers "In1.Cu" "In2.Cu")
		(hatch none 0.5)
		(connect_pads
			(clearance 0)
		)
		(min_thickness 0.25)
		(keepout
			(tracks not_allowed)
			(vias allowed)
			(pads allowed)
			(copperpour not_allowed)
			(footprints allowed)
		)
		(placement
			(enabled no)
			(sheetname "")
		)
		(fill yes
			(thermal_gap 0.5)
			(thermal_bridge_width 0.5)
			(island_removal_mode 0)
		)
		(polygon
			(pts
				(arc
					(start 199.881998 -300.37151)
					(mid 199.896877 -300.407431)
					(end 199.932798 -300.42231)
				)
				(arc
					(start 201.332338 -300.42231)
					(mid 201.368259 -300.407431)
					(end 201.383138 -300.37151)
				)
				(arc
					(start 201.383138 -299.96257)
					(mid 201.368259 -299.926649)
					(end 201.332338 -299.91177)
				)
				(arc
					(start 199.932798 -299.91177)
					(mid 199.896877 -299.926649)
					(end 199.881998 -299.96257)
				)
			)
		)
	)
	(zone
		(layers "In1.Cu" "In2.Cu")
		(hatch none 0.5)
		(connect_pads
			(clearance 0)
		)
		(min_thickness 0.25)
		(keepout
			(tracks not_allowed)
			(vias allowed)
			(pads allowed)
			(copperpour not_allowed)
			(footprints allowed)
		)
		(placement
			(enabled no)
			(sheetname "")
		)
		(fill yes
			(thermal_gap 0.5)
			(thermal_bridge_width 0.5)
			(island_removal_mode 0)
		)
		(polygon
			(pts
				(arc
					(start 282.061666 -259.57149)
					(mid 282.076545 -259.607411)
					(end 282.112466 -259.62229)
				)
				(arc
					(start 283.512006 -259.62229)
					(mid 283.547927 -259.607411)
					(end 283.562806 -259.57149)
				)
				(arc
					(start 283.562806 -259.16255)
					(mid 283.547927 -259.126629)
					(end 283.512006 -259.11175)
				)
				(arc
					(start 282.112466 -259.11175)
					(mid 282.076545 -259.126629)
					(end 282.061666 -259.16255)
				)
			)
		)
	)
	(zone
		(layers "In1.Cu" "In2.Cu")
		(hatch none 0.5)
		(connect_pads
			(clearance 0)
		)
		(min_thickness 0.25)
		(keepout
			(tracks not_allowed)
			(vias allowed)
			(pads allowed)
			(copperpour not_allowed)
			(footprints allowed)
		)
		(placement
			(enabled no)
			(sheetname "")
		)
		(fill yes
			(thermal_gap 0.5)
			(thermal_bridge_width 0.5)
			(island_removal_mode 0)
		)
		(polygon
			(pts
				(arc
					(start 428.634398 -314.821316)
					(mid 428.649277 -314.857237)
					(end 428.685198 -314.872116)
				)
				(arc
					(start 430.084738 -314.872116)
					(mid 430.120659 -314.857237)
					(end 430.135538 -314.821316)
				)
				(arc
					(start 430.135538 -314.412376)
					(mid 430.120659 -314.376455)
					(end 430.084738 -314.361576)
				)
				(arc
					(start 428.685198 -314.361576)
					(mid 428.649277 -314.376455)
					(end 428.634398 -314.412376)
				)
			)
		)
	)
	(zone
		(layers "In1.Cu" "In2.Cu")
		(hatch none 0.5)
		(connect_pads
			(clearance 0)
		)
		(min_thickness 0.25)
		(keepout
			(tracks not_allowed)
			(vias allowed)
			(pads allowed)
			(copperpour not_allowed)
			(footprints allowed)
		)
		(placement
			(enabled no)
			(sheetname "")
		)
		(fill yes
			(thermal_gap 0.5)
			(thermal_bridge_width 0.5)
			(island_removal_mode 0)
		)
		(polygon
			(pts
				(arc
					(start 195.78193 -282.521406)
					(mid 195.796809 -282.557327)
					(end 195.83273 -282.572206)
				)
				(arc
					(start 197.23227 -282.572206)
					(mid 197.268191 -282.557327)
					(end 197.28307 -282.521406)
				)
				(arc
					(start 197.28307 -282.112466)
					(mid 197.268191 -282.076545)
					(end 197.23227 -282.061666)
				)
				(arc
					(start 195.83273 -282.061666)
					(mid 195.796809 -282.076545)
					(end 195.78193 -282.112466)
				)
			)
		)
	)
	(zone
		(layers "In1.Cu" "In2.Cu")
		(hatch none 0.5)
		(connect_pads
			(clearance 0)
		)
		(min_thickness 0.25)
		(keepout
			(tracks not_allowed)
			(vias allowed)
			(pads allowed)
			(copperpour not_allowed)
			(footprints allowed)
		)
		(placement
			(enabled no)
			(sheetname "")
		)
		(fill yes
			(thermal_gap 0.5)
			(thermal_bridge_width 0.5)
			(island_removal_mode 0)
		)
		(polygon
			(pts
				(arc
					(start 259.430266 -205.171548)
					(mid 259.445145 -205.207469)
					(end 259.481066 -205.222348)
				)
				(arc
					(start 260.880606 -205.222348)
					(mid 260.916527 -205.207469)
					(end 260.931406 -205.171548)
				)
				(arc
					(start 260.931406 -204.762608)
					(mid 260.916527 -204.726687)
					(end 260.880606 -204.711808)
				)
				(arc
					(start 259.481066 -204.711808)
					(mid 259.445145 -204.726687)
					(end 259.430266 -204.762608)
				)
			)
		)
	)
	(zone
		(layers "In1.Cu" "In2.Cu")
		(hatch none 0.5)
		(connect_pads
			(clearance 0)
		)
		(min_thickness 0.25)
		(keepout
			(tracks not_allowed)
			(vias allowed)
			(pads allowed)
			(copperpour not_allowed)
			(footprints allowed)
		)
		(placement
			(enabled no)
			(sheetname "")
		)
		(fill yes
			(thermal_gap 0.5)
			(thermal_bridge_width 0.5)
			(island_removal_mode 0)
		)
		(polygon
			(pts
				(arc
					(start 312.236866 -260.421374)
					(mid 312.251745 -260.457295)
					(end 312.287666 -260.472174)
				)
				(arc
					(start 313.687206 -260.472174)
					(mid 313.723127 -260.457295)
					(end 313.738006 -260.421374)
				)
				(arc
					(start 313.738006 -260.012434)
					(mid 313.723127 -259.976513)
					(end 313.687206 -259.961634)
				)
				(arc
					(start 312.287666 -259.961634)
					(mid 312.251745 -259.976513)
					(end 312.236866 -260.012434)
				)
			)
		)
	)
	(zone
		(layers "In1.Cu" "In2.Cu")
		(hatch none 0.5)
		(connect_pads
			(clearance 0)
		)
		(min_thickness 0.25)
		(keepout
			(tracks not_allowed)
			(vias allowed)
			(pads allowed)
			(copperpour not_allowed)
			(footprints allowed)
		)
		(placement
			(enabled no)
			(sheetname "")
		)
		(fill yes
			(thermal_gap 0.5)
			(thermal_bridge_width 0.5)
			(island_removal_mode 0)
		)
		(polygon
			(pts
				(arc
					(start 180.69433 -238.321342)
					(mid 180.709209 -238.357263)
					(end 180.74513 -238.372142)
				)
				(arc
					(start 182.14467 -238.372142)
					(mid 182.180591 -238.357263)
					(end 182.19547 -238.321342)
				)
				(arc
					(start 182.19547 -237.912402)
					(mid 182.180591 -237.876481)
					(end 182.14467 -237.861602)
				)
				(arc
					(start 180.74513 -237.861602)
					(mid 180.709209 -237.876481)
					(end 180.69433 -237.912402)
				)
			)
		)
	)
	(zone
		(layers "In1.Cu" "In2.Cu")
		(hatch none 0.5)
		(connect_pads
			(clearance 0)
		)
		(min_thickness 0.25)
		(keepout
			(tracks not_allowed)
			(vias allowed)
			(pads allowed)
			(copperpour not_allowed)
			(footprints allowed)
		)
		(placement
			(enabled no)
			(sheetname "")
		)
		(fill yes
			(thermal_gap 0.5)
			(thermal_bridge_width 0.5)
			(island_removal_mode 0)
		)
		(polygon
			(pts
				(arc
					(start 30.02153 -288.471356)
					(mid 30.036409 -288.507277)
					(end 30.07233 -288.522156)
				)
				(arc
					(start 31.47187 -288.522156)
					(mid 31.507791 -288.507277)
					(end 31.52267 -288.471356)
				)
				(arc
					(start 31.52267 -288.062416)
					(mid 31.507791 -288.026495)
					(end 31.47187 -288.011616)
				)
				(arc
					(start 30.07233 -288.011616)
					(mid 30.036409 -288.026495)
					(end 30.02153 -288.062416)
				)
			)
		)
	)
	(zone
		(layers "In1.Cu" "In2.Cu")
		(hatch none 0.5)
		(connect_pads
			(clearance 0)
		)
		(min_thickness 0.25)
		(keepout
			(tracks not_allowed)
			(vias allowed)
			(pads allowed)
			(copperpour not_allowed)
			(footprints allowed)
		)
		(placement
			(enabled no)
			(sheetname "")
		)
		(fill yes
			(thermal_gap 0.5)
			(thermal_bridge_width 0.5)
			(island_removal_mode 0)
		)
		(polygon
			(pts
				(arc
					(start 26.577798 -312.27141)
					(mid 26.592677 -312.307331)
					(end 26.628598 -312.32221)
				)
				(arc
					(start 28.028138 -312.32221)
					(mid 28.064059 -312.307331)
					(end 28.078938 -312.27141)
				)
				(arc
					(start 28.078938 -311.86247)
					(mid 28.064059 -311.826549)
					(end 28.028138 -311.81167)
				)
				(arc
					(start 26.628598 -311.81167)
					(mid 26.592677 -311.826549)
					(end 26.577798 -311.86247)
				)
			)
		)
	)
	(zone
		(layers "In1.Cu" "In2.Cu")
		(hatch none 0.5)
		(connect_pads
			(clearance 0)
		)
		(min_thickness 0.25)
		(keepout
			(tracks not_allowed)
			(vias allowed)
			(pads allowed)
			(copperpour not_allowed)
			(footprints allowed)
		)
		(placement
			(enabled no)
			(sheetname "")
		)
		(fill yes
			(thermal_gap 0.5)
			(thermal_bridge_width 0.5)
			(island_removal_mode 0)
		)
		(polygon
			(pts
				(arc
					(start 304.693066 -218.77147)
					(mid 304.707945 -218.807391)
					(end 304.743866 -218.82227)
				)
				(arc
					(start 306.143406 -218.82227)
					(mid 306.179327 -218.807391)
					(end 306.194206 -218.77147)
				)
				(arc
					(start 306.194206 -218.36253)
					(mid 306.179327 -218.326609)
					(end 306.143406 -218.31173)
				)
				(arc
					(start 304.743866 -218.31173)
					(mid 304.707945 -218.326609)
					(end 304.693066 -218.36253)
				)
			)
		)
	)
	(zone
		(layers "In1.Cu" "In2.Cu")
		(hatch none 0.5)
		(connect_pads
			(clearance 0)
		)
		(min_thickness 0.25)
		(keepout
			(tracks not_allowed)
			(vias allowed)
			(pads allowed)
			(copperpour not_allowed)
			(footprints allowed)
		)
		(placement
			(enabled no)
			(sheetname "")
		)
		(fill yes
			(thermal_gap 0.5)
			(thermal_bridge_width 0.5)
			(island_removal_mode 0)
		)
		(polygon
			(pts
				(arc
					(start 180.69433 -241.721386)
					(mid 180.709209 -241.757307)
					(end 180.74513 -241.772186)
				)
				(arc
					(start 182.14467 -241.772186)
					(mid 182.180591 -241.757307)
					(end 182.19547 -241.721386)
				)
				(arc
					(start 182.19547 -241.312446)
					(mid 182.180591 -241.276525)
					(end 182.14467 -241.261646)
				)
				(arc
					(start 180.74513 -241.261646)
					(mid 180.709209 -241.276525)
					(end 180.69433 -241.312446)
				)
			)
		)
	)
	(zone
		(layers "In1.Cu" "In2.Cu")
		(hatch none 0.5)
		(connect_pads
			(clearance 0)
		)
		(min_thickness 0.25)
		(keepout
			(tracks not_allowed)
			(vias allowed)
			(pads allowed)
			(copperpour not_allowed)
			(footprints allowed)
		)
		(placement
			(enabled no)
			(sheetname "")
		)
		(fill yes
			(thermal_gap 0.5)
			(thermal_bridge_width 0.5)
			(island_removal_mode 0)
		)
		(polygon
			(pts
				(arc
					(start 34.121598 -195.821554)
					(mid 34.136477 -195.857475)
					(end 34.172398 -195.872354)
				)
				(arc
					(start 35.571938 -195.872354)
					(mid 35.607859 -195.857475)
					(end 35.622738 -195.821554)
				)
				(arc
					(start 35.622738 -195.412614)
					(mid 35.607859 -195.376693)
					(end 35.571938 -195.361814)
				)
				(arc
					(start 34.172398 -195.361814)
					(mid 34.136477 -195.376693)
					(end 34.121598 -195.412614)
				)
			)
		)
	)
	(zone
		(layers "In1.Cu" "In2.Cu")
		(hatch none 0.5)
		(connect_pads
			(clearance 0)
		)
		(min_thickness 0.25)
		(keepout
			(tracks not_allowed)
			(vias allowed)
			(pads allowed)
			(copperpour not_allowed)
			(footprints allowed)
		)
		(placement
			(enabled no)
			(sheetname "")
		)
		(fill yes
			(thermal_gap 0.5)
			(thermal_bridge_width 0.5)
			(island_removal_mode 0)
		)
		(polygon
			(pts
				(arc
					(start 282.061666 -291.021516)
					(mid 282.076545 -291.057437)
					(end 282.112466 -291.072316)
				)
				(arc
					(start 283.512006 -291.072316)
					(mid 283.547927 -291.057437)
					(end 283.562806 -291.021516)
				)
				(arc
					(start 283.562806 -290.612576)
					(mid 283.547927 -290.576655)
					(end 283.512006 -290.561776)
				)
				(arc
					(start 282.112466 -290.561776)
					(mid 282.076545 -290.576655)
					(end 282.061666 -290.612576)
				)
			)
		)
	)
	(zone
		(layers "In1.Cu" "In2.Cu")
		(hatch none 0.5)
		(connect_pads
			(clearance 0)
		)
		(min_thickness 0.25)
		(keepout
			(tracks not_allowed)
			(vias allowed)
			(pads allowed)
			(copperpour not_allowed)
			(footprints allowed)
		)
		(placement
			(enabled no)
			(sheetname "")
		)
		(fill yes
			(thermal_gap 0.5)
			(thermal_bridge_width 0.5)
			(island_removal_mode 0)
		)
		(polygon
			(pts
				(arc
					(start 425.190666 -289.321494)
					(mid 425.205545 -289.357415)
					(end 425.241466 -289.372294)
				)
				(arc
					(start 426.641006 -289.372294)
					(mid 426.676927 -289.357415)
					(end 426.691806 -289.321494)
				)
				(arc
					(start 426.691806 -288.912554)
					(mid 426.676927 -288.876633)
					(end 426.641006 -288.861754)
				)
				(arc
					(start 425.241466 -288.861754)
					(mid 425.205545 -288.876633)
					(end 425.190666 -288.912554)
				)
			)
		)
	)
	(zone
		(layers "In1.Cu" "In2.Cu")
		(hatch none 0.5)
		(connect_pads
			(clearance 0)
		)
		(min_thickness 0.25)
		(keepout
			(tracks not_allowed)
			(vias allowed)
			(pads allowed)
			(copperpour not_allowed)
			(footprints allowed)
		)
		(placement
			(enabled no)
			(sheetname "")
		)
		(fill yes
			(thermal_gap 0.5)
			(thermal_bridge_width 0.5)
			(island_removal_mode 0)
		)
		(polygon
			(pts
				(arc
					(start 440.278266 -251.921518)
					(mid 440.293145 -251.957439)
					(end 440.329066 -251.972318)
				)
				(arc
					(start 441.728606 -251.972318)
					(mid 441.764527 -251.957439)
					(end 441.779406 -251.921518)
				)
				(arc
					(start 441.779406 -251.512578)
					(mid 441.764527 -251.476657)
					(end 441.728606 -251.461778)
				)
				(arc
					(start 440.329066 -251.461778)
					(mid 440.293145 -251.476657)
					(end 440.278266 -251.512578)
				)
			)
		)
	)
	(zone
		(layers "In1.Cu" "In2.Cu")
		(hatch none 0.5)
		(connect_pads
			(clearance 0)
		)
		(min_thickness 0.25)
		(keepout
			(tracks not_allowed)
			(vias allowed)
			(pads allowed)
			(copperpour not_allowed)
			(footprints allowed)
		)
		(placement
			(enabled no)
			(sheetname "")
		)
		(fill yes
			(thermal_gap 0.5)
			(thermal_bridge_width 0.5)
			(island_removal_mode 0)
		)
		(polygon
			(pts
				(arc
					(start 169.706798 -236.62132)
					(mid 169.721677 -236.657241)
					(end 169.757598 -236.67212)
				)
				(arc
					(start 171.157138 -236.67212)
					(mid 171.193059 -236.657241)
					(end 171.207938 -236.62132)
				)
				(arc
					(start 171.207938 -236.21238)
					(mid 171.193059 -236.176459)
					(end 171.157138 -236.16158)
				)
				(arc
					(start 169.757598 -236.16158)
					(mid 169.721677 -236.176459)
					(end 169.706798 -236.21238)
				)
			)
		)
	)
	(zone
		(layers "In1.Cu" "In2.Cu")
		(hatch none 0.5)
		(connect_pads
			(clearance 0)
		)
		(min_thickness 0.25)
		(keepout
			(tracks not_allowed)
			(vias allowed)
			(pads allowed)
			(copperpour not_allowed)
			(footprints allowed)
		)
		(placement
			(enabled no)
			(sheetname "")
		)
		(fill yes
			(thermal_gap 0.5)
			(thermal_bridge_width 0.5)
			(island_removal_mode 0)
		)
		(polygon
			(pts
				(arc
					(start 417.646866 -223.871536)
					(mid 417.661745 -223.907457)
					(end 417.697666 -223.922336)
				)
				(arc
					(start 419.097206 -223.922336)
					(mid 419.133127 -223.907457)
					(end 419.148006 -223.871536)
				)
				(arc
					(start 419.148006 -223.462596)
					(mid 419.133127 -223.426675)
					(end 419.097206 -223.411796)
				)
				(arc
					(start 417.697666 -223.411796)
					(mid 417.661745 -223.426675)
					(end 417.646866 -223.462596)
				)
			)
		)
	)
	(zone
		(layers "In1.Cu" "In2.Cu")
		(hatch none 0.5)
		(connect_pads
			(clearance 0)
		)
		(min_thickness 0.25)
		(keepout
			(tracks not_allowed)
			(vias allowed)
			(pads allowed)
			(copperpour not_allowed)
			(footprints allowed)
		)
		(placement
			(enabled no)
			(sheetname "")
		)
		(fill yes
			(thermal_gap 0.5)
			(thermal_bridge_width 0.5)
			(island_removal_mode 0)
		)
		(polygon
			(pts
				(arc
					(start 413.546798 -240.021364)
					(mid 413.561677 -240.057285)
					(end 413.597598 -240.072164)
				)
				(arc
					(start 414.997138 -240.072164)
					(mid 415.033059 -240.057285)
					(end 415.047938 -240.021364)
				)
				(arc
					(start 415.047938 -239.612424)
					(mid 415.033059 -239.576503)
					(end 414.997138 -239.561624)
				)
				(arc
					(start 413.597598 -239.561624)
					(mid 413.561677 -239.576503)
					(end 413.546798 -239.612424)
				)
			)
		)
	)
	(zone
		(layers "In1.Cu" "In2.Cu")
		(hatch none 0.5)
		(connect_pads
			(clearance 0)
		)
		(min_thickness 0.25)
		(keepout
			(tracks not_allowed)
			(vias allowed)
			(pads allowed)
			(copperpour not_allowed)
			(footprints allowed)
		)
		(placement
			(enabled no)
			(sheetname "")
		)
		(fill yes
			(thermal_gap 0.5)
			(thermal_bridge_width 0.5)
			(island_removal_mode 0)
		)
		(polygon
			(pts
				(arc
					(start 199.881998 -315.671454)
					(mid 199.896877 -315.707375)
					(end 199.932798 -315.722254)
				)
				(arc
					(start 201.332338 -315.722254)
					(mid 201.368259 -315.707375)
					(end 201.383138 -315.671454)
				)
				(arc
					(start 201.383138 -315.262514)
					(mid 201.368259 -315.226593)
					(end 201.332338 -315.211714)
				)
				(arc
					(start 199.932798 -315.211714)
					(mid 199.896877 -315.226593)
					(end 199.881998 -315.262514)
				)
			)
		)
	)
	(zone
		(layers "In1.Cu" "In2.Cu")
		(hatch none 0.5)
		(connect_pads
			(clearance 0)
		)
		(min_thickness 0.25)
		(keepout
			(tracks not_allowed)
			(vias allowed)
			(pads allowed)
			(copperpour not_allowed)
			(footprints allowed)
		)
		(placement
			(enabled no)
			(sheetname "")
		)
		(fill yes
			(thermal_gap 0.5)
			(thermal_bridge_width 0.5)
			(island_removal_mode 0)
		)
		(polygon
			(pts
				(arc
					(start 308.136798 -268.071346)
					(mid 308.151677 -268.107267)
					(end 308.187598 -268.122146)
				)
				(arc
					(start 309.587138 -268.122146)
					(mid 309.623059 -268.107267)
					(end 309.637938 -268.071346)
				)
				(arc
					(start 309.637938 -267.662406)
					(mid 309.623059 -267.626485)
					(end 309.587138 -267.611606)
				)
				(arc
					(start 308.187598 -267.611606)
					(mid 308.151677 -267.626485)
					(end 308.136798 -267.662406)
				)
			)
		)
	)
	(zone
		(layers "In1.Cu" "In2.Cu")
		(hatch none 0.5)
		(connect_pads
			(clearance 0)
		)
		(min_thickness 0.25)
		(keepout
			(tracks not_allowed)
			(vias allowed)
			(pads allowed)
			(copperpour not_allowed)
			(footprints allowed)
		)
		(placement
			(enabled no)
			(sheetname "")
		)
		(fill yes
			(thermal_gap 0.5)
			(thermal_bridge_width 0.5)
			(island_removal_mode 0)
		)
		(polygon
			(pts
				(arc
					(start 169.706798 -309.721504)
					(mid 169.721677 -309.757425)
					(end 169.757598 -309.772304)
				)
				(arc
					(start 171.157138 -309.772304)
					(mid 171.193059 -309.757425)
					(end 171.207938 -309.721504)
				)
				(arc
					(start 171.207938 -309.312564)
					(mid 171.193059 -309.276643)
					(end 171.157138 -309.261764)
				)
				(arc
					(start 169.757598 -309.261764)
					(mid 169.721677 -309.276643)
					(end 169.706798 -309.312564)
				)
			)
		)
	)
	(zone
		(layers "In1.Cu" "In2.Cu")
		(hatch none 0.5)
		(connect_pads
			(clearance 0)
		)
		(min_thickness 0.25)
		(keepout
			(tracks not_allowed)
			(vias allowed)
			(pads allowed)
			(copperpour not_allowed)
			(footprints allowed)
		)
		(placement
			(enabled no)
			(sheetname "")
		)
		(fill yes
			(thermal_gap 0.5)
			(thermal_bridge_width 0.5)
			(island_removal_mode 0)
		)
		(polygon
			(pts
				(arc
					(start 285.505398 -269.771368)
					(mid 285.520277 -269.807289)
					(end 285.556198 -269.822168)
				)
				(arc
					(start 286.955738 -269.822168)
					(mid 286.991659 -269.807289)
					(end 287.006538 -269.771368)
				)
				(arc
					(start 287.006538 -269.362428)
					(mid 286.991659 -269.326507)
					(end 286.955738 -269.311628)
				)
				(arc
					(start 285.556198 -269.311628)
					(mid 285.520277 -269.326507)
					(end 285.505398 -269.362428)
				)
			)
		)
	)
	(zone
		(layers "In1.Cu" "In2.Cu")
		(hatch none 0.5)
		(connect_pads
			(clearance 0)
		)
		(min_thickness 0.25)
		(keepout
			(tracks not_allowed)
			(vias allowed)
			(pads allowed)
			(copperpour not_allowed)
			(footprints allowed)
		)
		(placement
			(enabled no)
			(sheetname "")
		)
		(fill yes
			(thermal_gap 0.5)
			(thermal_bridge_width 0.5)
			(island_removal_mode 0)
		)
		(polygon
			(pts
				(arc
					(start 293.049198 -247.671336)
					(mid 293.064077 -247.707257)
					(end 293.099998 -247.722136)
				)
				(arc
					(start 294.499538 -247.722136)
					(mid 294.535459 -247.707257)
					(end 294.550338 -247.671336)
				)
				(arc
					(start 294.550338 -247.262396)
					(mid 294.535459 -247.226475)
					(end 294.499538 -247.211596)
				)
				(arc
					(start 293.099998 -247.211596)
					(mid 293.064077 -247.226475)
					(end 293.049198 -247.262396)
				)
			)
		)
	)
	(zone
		(layers "In1.Cu" "In2.Cu")
		(hatch none 0.5)
		(connect_pads
			(clearance 0)
		)
		(min_thickness 0.25)
		(keepout
			(tracks not_allowed)
			(vias allowed)
			(pads allowed)
			(copperpour not_allowed)
			(footprints allowed)
		)
		(placement
			(enabled no)
			(sheetname "")
		)
		(fill yes
			(thermal_gap 0.5)
			(thermal_bridge_width 0.5)
			(island_removal_mode 0)
		)
		(polygon
			(pts
				(arc
					(start 308.136798 -273.171412)
					(mid 308.151677 -273.207333)
					(end 308.187598 -273.222212)
				)
				(arc
					(start 309.587138 -273.222212)
					(mid 309.623059 -273.207333)
					(end 309.637938 -273.171412)
				)
				(arc
					(start 309.637938 -272.762472)
					(mid 309.623059 -272.726551)
					(end 309.587138 -272.711672)
				)
				(arc
					(start 308.187598 -272.711672)
					(mid 308.151677 -272.726551)
					(end 308.136798 -272.762472)
				)
			)
		)
	)
	(zone
		(layers "In1.Cu" "In2.Cu")
		(hatch none 0.5)
		(connect_pads
			(clearance 0)
		)
		(min_thickness 0.25)
		(keepout
			(tracks not_allowed)
			(vias allowed)
			(pads allowed)
			(copperpour not_allowed)
			(footprints allowed)
		)
		(placement
			(enabled no)
			(sheetname "")
		)
		(fill yes
			(thermal_gap 0.5)
			(thermal_bridge_width 0.5)
			(island_removal_mode 0)
		)
		(polygon
			(pts
				(arc
					(start 293.049198 -261.271512)
					(mid 293.064077 -261.307433)
					(end 293.099998 -261.322312)
				)
				(arc
					(start 294.499538 -261.322312)
					(mid 294.535459 -261.307433)
					(end 294.550338 -261.271512)
				)
				(arc
					(start 294.550338 -260.862572)
					(mid 294.535459 -260.826651)
					(end 294.499538 -260.811772)
				)
				(arc
					(start 293.099998 -260.811772)
					(mid 293.064077 -260.826651)
					(end 293.049198 -260.862572)
				)
			)
		)
	)
	(zone
		(layers "In1.Cu" "In2.Cu")
		(hatch none 0.5)
		(connect_pads
			(clearance 0)
		)
		(min_thickness 0.25)
		(keepout
			(tracks not_allowed)
			(vias allowed)
			(pads allowed)
			(copperpour not_allowed)
			(footprints allowed)
		)
		(placement
			(enabled no)
			(sheetname "")
		)
		(fill yes
			(thermal_gap 0.5)
			(thermal_bridge_width 0.5)
			(island_removal_mode 0)
		)
		(polygon
			(pts
				(arc
					(start 210.86953 -297.82135)
					(mid 210.884409 -297.857271)
					(end 210.92033 -297.87215)
				)
				(arc
					(start 212.31987 -297.87215)
					(mid 212.355791 -297.857271)
					(end 212.37067 -297.82135)
				)
				(arc
					(start 212.37067 -297.41241)
					(mid 212.355791 -297.376489)
					(end 212.31987 -297.36161)
				)
				(arc
					(start 210.92033 -297.36161)
					(mid 210.884409 -297.376489)
					(end 210.86953 -297.41241)
				)
			)
		)
	)
	(zone
		(layers "In1.Cu" "In2.Cu")
		(hatch none 0.5)
		(connect_pads
			(clearance 0)
		)
		(min_thickness 0.25)
		(keepout
			(tracks not_allowed)
			(vias allowed)
			(pads allowed)
			(copperpour not_allowed)
			(footprints allowed)
		)
		(placement
			(enabled no)
			(sheetname "")
		)
		(fill yes
			(thermal_gap 0.5)
			(thermal_bridge_width 0.5)
			(island_removal_mode 0)
		)
		(polygon
			(pts
				(arc
					(start 7.39013 -235.771436)
					(mid 7.405009 -235.807357)
					(end 7.44093 -235.822236)
				)
				(arc
					(start 8.84047 -235.822236)
					(mid 8.876391 -235.807357)
					(end 8.89127 -235.771436)
				)
				(arc
					(start 8.89127 -235.362496)
					(mid 8.876391 -235.326575)
					(end 8.84047 -235.311696)
				)
				(arc
					(start 7.44093 -235.311696)
					(mid 7.405009 -235.326575)
					(end 7.39013 -235.362496)
				)
			)
		)
	)
	(zone
		(layers "In1.Cu" "In2.Cu")
		(hatch none 0.5)
		(connect_pads
			(clearance 0)
		)
		(min_thickness 0.25)
		(keepout
			(tracks not_allowed)
			(vias allowed)
			(pads allowed)
			(copperpour not_allowed)
			(footprints allowed)
		)
		(placement
			(enabled no)
			(sheetname "")
		)
		(fill yes
			(thermal_gap 0.5)
			(thermal_bridge_width 0.5)
			(island_removal_mode 0)
		)
		(polygon
			(pts
				(arc
					(start 304.693066 -239.17148)
					(mid 304.707945 -239.207401)
					(end 304.743866 -239.22228)
				)
				(arc
					(start 306.143406 -239.22228)
					(mid 306.179327 -239.207401)
					(end 306.194206 -239.17148)
				)
				(arc
					(start 306.194206 -238.76254)
					(mid 306.179327 -238.726619)
					(end 306.143406 -238.71174)
				)
				(arc
					(start 304.743866 -238.71174)
					(mid 304.707945 -238.726619)
					(end 304.693066 -238.76254)
				)
			)
		)
	)
	(zone
		(layers "In1.Cu" "In2.Cu")
		(hatch none 0.5)
		(connect_pads
			(clearance 0)
		)
		(min_thickness 0.25)
		(keepout
			(tracks not_allowed)
			(vias allowed)
			(pads allowed)
			(copperpour not_allowed)
			(footprints allowed)
		)
		(placement
			(enabled no)
			(sheetname "")
		)
		(fill yes
			(thermal_gap 0.5)
			(thermal_bridge_width 0.5)
			(island_removal_mode 0)
		)
		(polygon
			(pts
				(arc
					(start 285.505398 -215.371426)
					(mid 285.520277 -215.407347)
					(end 285.556198 -215.422226)
				)
				(arc
					(start 286.955738 -215.422226)
					(mid 286.991659 -215.407347)
					(end 287.006538 -215.371426)
				)
				(arc
					(start 287.006538 -214.962486)
					(mid 286.991659 -214.926565)
					(end 286.955738 -214.911686)
				)
				(arc
					(start 285.556198 -214.911686)
					(mid 285.520277 -214.926565)
					(end 285.505398 -214.962486)
				)
			)
		)
	)
	(zone
		(layers "In1.Cu" "In2.Cu")
		(hatch none 0.5)
		(connect_pads
			(clearance 0)
		)
		(min_thickness 0.25)
		(keepout
			(tracks not_allowed)
			(vias allowed)
			(pads allowed)
			(copperpour not_allowed)
			(footprints allowed)
		)
		(placement
			(enabled no)
			(sheetname "")
		)
		(fill yes
			(thermal_gap 0.5)
			(thermal_bridge_width 0.5)
			(island_removal_mode 0)
		)
		(polygon
			(pts
				(arc
					(start 60.19673 -280.821384)
					(mid 60.211609 -280.857305)
					(end 60.24753 -280.872184)
				)
				(arc
					(start 61.64707 -280.872184)
					(mid 61.682991 -280.857305)
					(end 61.69787 -280.821384)
				)
				(arc
					(start 61.69787 -280.412444)
					(mid 61.682991 -280.376523)
					(end 61.64707 -280.361644)
				)
				(arc
					(start 60.24753 -280.361644)
					(mid 60.211609 -280.376523)
					(end 60.19673 -280.412444)
				)
			)
		)
	)
	(zone
		(layers "In1.Cu" "In2.Cu")
		(hatch none 0.5)
		(connect_pads
			(clearance 0)
		)
		(min_thickness 0.25)
		(keepout
			(tracks not_allowed)
			(vias allowed)
			(pads allowed)
			(copperpour not_allowed)
			(footprints allowed)
		)
		(placement
			(enabled no)
			(sheetname "")
		)
		(fill yes
			(thermal_gap 0.5)
			(thermal_bridge_width 0.5)
			(island_removal_mode 0)
		)
		(polygon
			(pts
				(arc
					(start 282.061666 -227.271326)
					(mid 282.076545 -227.307247)
					(end 282.112466 -227.322126)
				)
				(arc
					(start 283.512006 -227.322126)
					(mid 283.547927 -227.307247)
					(end 283.562806 -227.271326)
				)
				(arc
					(start 283.562806 -226.862386)
					(mid 283.547927 -226.826465)
					(end 283.512006 -226.811586)
				)
				(arc
					(start 282.112466 -226.811586)
					(mid 282.076545 -226.826465)
					(end 282.061666 -226.862386)
				)
			)
		)
	)
	(zone
		(layers "In1.Cu" "In2.Cu")
		(hatch none 0.5)
		(connect_pads
			(clearance 0)
		)
		(min_thickness 0.25)
		(keepout
			(tracks not_allowed)
			(vias allowed)
			(pads allowed)
			(copperpour not_allowed)
			(footprints allowed)
		)
		(placement
			(enabled no)
			(sheetname "")
		)
		(fill yes
			(thermal_gap 0.5)
			(thermal_bridge_width 0.5)
			(island_removal_mode 0)
		)
		(polygon
			(pts
				(arc
					(start 462.909666 -231.521508)
					(mid 462.924545 -231.557429)
					(end 462.960466 -231.572308)
				)
				(arc
					(start 464.360006 -231.572308)
					(mid 464.395927 -231.557429)
					(end 464.410806 -231.521508)
				)
				(arc
					(start 464.410806 -231.112568)
					(mid 464.395927 -231.076647)
					(end 464.360006 -231.061768)
				)
				(arc
					(start 462.960466 -231.061768)
					(mid 462.924545 -231.076647)
					(end 462.909666 -231.112568)
				)
			)
		)
	)
	(zone
		(layers "In1.Cu" "In2.Cu")
		(hatch none 0.5)
		(connect_pads
			(clearance 0)
		)
		(min_thickness 0.25)
		(keepout
			(tracks not_allowed)
			(vias allowed)
			(pads allowed)
			(copperpour not_allowed)
			(footprints allowed)
		)
		(placement
			(enabled no)
			(sheetname "")
		)
		(fill yes
			(thermal_gap 0.5)
			(thermal_bridge_width 0.5)
			(island_removal_mode 0)
		)
		(polygon
			(pts
				(arc
					(start 192.338198 -240.871502)
					(mid 192.353077 -240.907423)
					(end 192.388998 -240.922302)
				)
				(arc
					(start 193.788538 -240.922302)
					(mid 193.824459 -240.907423)
					(end 193.839338 -240.871502)
				)
				(arc
					(start 193.839338 -240.462562)
					(mid 193.824459 -240.426641)
					(end 193.788538 -240.411762)
				)
				(arc
					(start 192.388998 -240.411762)
					(mid 192.353077 -240.426641)
					(end 192.338198 -240.462562)
				)
			)
		)
	)
	(zone
		(layers "In1.Cu" "In2.Cu")
		(hatch none 0.5)
		(connect_pads
			(clearance 0)
		)
		(min_thickness 0.25)
		(keepout
			(tracks not_allowed)
			(vias allowed)
			(pads allowed)
			(copperpour not_allowed)
			(footprints allowed)
		)
		(placement
			(enabled no)
			(sheetname "")
		)
		(fill yes
			(thermal_gap 0.5)
			(thermal_bridge_width 0.5)
			(island_removal_mode 0)
		)
		(polygon
			(pts
				(arc
					(start 451.265798 -280.821384)
					(mid 451.280677 -280.857305)
					(end 451.316598 -280.872184)
				)
				(arc
					(start 452.716138 -280.872184)
					(mid 452.752059 -280.857305)
					(end 452.766938 -280.821384)
				)
				(arc
					(start 452.766938 -280.412444)
					(mid 452.752059 -280.376523)
					(end 452.716138 -280.361644)
				)
				(arc
					(start 451.316598 -280.361644)
					(mid 451.280677 -280.376523)
					(end 451.265798 -280.412444)
				)
			)
		)
	)
	(zone
		(layers "In1.Cu" "In2.Cu")
		(hatch none 0.5)
		(connect_pads
			(clearance 0)
		)
		(min_thickness 0.25)
		(keepout
			(tracks not_allowed)
			(vias allowed)
			(pads allowed)
			(copperpour not_allowed)
			(footprints allowed)
		)
		(placement
			(enabled no)
			(sheetname "")
		)
		(fill yes
			(thermal_gap 0.5)
			(thermal_bridge_width 0.5)
			(island_removal_mode 0)
		)
		(polygon
			(pts
				(arc
					(start 417.646866 -229.821486)
					(mid 417.661745 -229.857407)
					(end 417.697666 -229.872286)
				)
				(arc
					(start 419.097206 -229.872286)
					(mid 419.133127 -229.857407)
					(end 419.148006 -229.821486)
				)
				(arc
					(start 419.148006 -229.412546)
					(mid 419.133127 -229.376625)
					(end 419.097206 -229.361746)
				)
				(arc
					(start 417.697666 -229.361746)
					(mid 417.661745 -229.376625)
					(end 417.646866 -229.412546)
				)
			)
		)
	)
	(zone
		(layers "In1.Cu" "In2.Cu")
		(hatch none 0.5)
		(connect_pads
			(clearance 0)
		)
		(min_thickness 0.25)
		(keepout
			(tracks not_allowed)
			(vias allowed)
			(pads allowed)
			(copperpour not_allowed)
			(footprints allowed)
		)
		(placement
			(enabled no)
			(sheetname "")
		)
		(fill yes
			(thermal_gap 0.5)
			(thermal_bridge_width 0.5)
			(island_removal_mode 0)
		)
		(polygon
			(pts
				(arc
					(start 169.706798 -304.621438)
					(mid 169.721677 -304.657359)
					(end 169.757598 -304.672238)
				)
				(arc
					(start 171.157138 -304.672238)
					(mid 171.193059 -304.657359)
					(end 171.207938 -304.621438)
				)
				(arc
					(start 171.207938 -304.212498)
					(mid 171.193059 -304.176577)
					(end 171.157138 -304.161698)
				)
				(arc
					(start 169.757598 -304.161698)
					(mid 169.721677 -304.176577)
					(end 169.706798 -304.212498)
				)
			)
		)
	)
	(zone
		(layers "In1.Cu" "In2.Cu")
		(hatch none 0.5)
		(connect_pads
			(clearance 0)
		)
		(min_thickness 0.25)
		(keepout
			(tracks not_allowed)
			(vias allowed)
			(pads allowed)
			(copperpour not_allowed)
			(footprints allowed)
		)
		(placement
			(enabled no)
			(sheetname "")
		)
		(fill yes
			(thermal_gap 0.5)
			(thermal_bridge_width 0.5)
			(island_removal_mode 0)
		)
		(polygon
			(pts
				(arc
					(start 282.061666 -278.271478)
					(mid 282.076545 -278.307399)
					(end 282.112466 -278.322278)
				)
				(arc
					(start 283.512006 -278.322278)
					(mid 283.547927 -278.307399)
					(end 283.562806 -278.271478)
				)
				(arc
					(start 283.562806 -277.862538)
					(mid 283.547927 -277.826617)
					(end 283.512006 -277.811738)
				)
				(arc
					(start 282.112466 -277.811738)
					(mid 282.076545 -277.826617)
					(end 282.061666 -277.862538)
				)
			)
		)
	)
	(zone
		(layers "In1.Cu" "In2.Cu")
		(hatch none 0.5)
		(connect_pads
			(clearance 0)
		)
		(min_thickness 0.25)
		(keepout
			(tracks not_allowed)
			(vias allowed)
			(pads allowed)
			(copperpour not_allowed)
			(footprints allowed)
		)
		(placement
			(enabled no)
			(sheetname "")
		)
		(fill yes
			(thermal_gap 0.5)
			(thermal_bridge_width 0.5)
			(island_removal_mode 0)
		)
		(polygon
			(pts
				(arc
					(start 262.873998 -302.921416)
					(mid 262.888877 -302.957337)
					(end 262.924798 -302.972216)
				)
				(arc
					(start 264.324338 -302.972216)
					(mid 264.360259 -302.957337)
					(end 264.375138 -302.921416)
				)
				(arc
					(start 264.375138 -302.512476)
					(mid 264.360259 -302.476555)
					(end 264.324338 -302.461676)
				)
				(arc
					(start 262.924798 -302.461676)
					(mid 262.888877 -302.476555)
					(end 262.873998 -302.512476)
				)
			)
		)
	)
	(zone
		(layers "In1.Cu" "In2.Cu")
		(hatch none 0.5)
		(connect_pads
			(clearance 0)
		)
		(min_thickness 0.25)
		(keepout
			(tracks not_allowed)
			(vias allowed)
			(pads allowed)
			(copperpour not_allowed)
			(footprints allowed)
		)
		(placement
			(enabled no)
			(sheetname "")
		)
		(fill yes
			(thermal_gap 0.5)
			(thermal_bridge_width 0.5)
			(island_removal_mode 0)
		)
		(polygon
			(pts
				(arc
					(start 274.517866 -195.821554)
					(mid 274.532745 -195.857475)
					(end 274.568666 -195.872354)
				)
				(arc
					(start 275.968206 -195.872354)
					(mid 276.004127 -195.857475)
					(end 276.019006 -195.821554)
				)
				(arc
					(start 276.019006 -195.412614)
					(mid 276.004127 -195.376693)
					(end 275.968206 -195.361814)
				)
				(arc
					(start 274.568666 -195.361814)
					(mid 274.532745 -195.376693)
					(end 274.517866 -195.412614)
				)
			)
		)
	)
	(zone
		(layers "In1.Cu" "In2.Cu")
		(hatch none 0.5)
		(connect_pads
			(clearance 0)
		)
		(min_thickness 0.25)
		(keepout
			(tracks not_allowed)
			(vias allowed)
			(pads allowed)
			(copperpour not_allowed)
			(footprints allowed)
		)
		(placement
			(enabled no)
			(sheetname "")
		)
		(fill yes
			(thermal_gap 0.5)
			(thermal_bridge_width 0.5)
			(island_removal_mode 0)
		)
		(polygon
			(pts
				(arc
					(start 22.47773 -200.921366)
					(mid 22.492609 -200.957287)
					(end 22.52853 -200.972166)
				)
				(arc
					(start 23.92807 -200.972166)
					(mid 23.963991 -200.957287)
					(end 23.97887 -200.921366)
				)
				(arc
					(start 23.97887 -200.512426)
					(mid 23.963991 -200.476505)
					(end 23.92807 -200.461626)
				)
				(arc
					(start 22.52853 -200.461626)
					(mid 22.492609 -200.476505)
					(end 22.47773 -200.512426)
				)
			)
		)
	)
	(zone
		(layers "In1.Cu" "In2.Cu")
		(hatch none 0.5)
		(connect_pads
			(clearance 0)
		)
		(min_thickness 0.25)
		(keepout
			(tracks not_allowed)
			(vias allowed)
			(pads allowed)
			(copperpour not_allowed)
			(footprints allowed)
		)
		(placement
			(enabled no)
			(sheetname "")
		)
		(fill yes
			(thermal_gap 0.5)
			(thermal_bridge_width 0.5)
			(island_removal_mode 0)
		)
		(polygon
			(pts
				(arc
					(start 169.706798 -223.871536)
					(mid 169.721677 -223.907457)
					(end 169.757598 -223.922336)
				)
				(arc
					(start 171.157138 -223.922336)
					(mid 171.193059 -223.907457)
					(end 171.207938 -223.871536)
				)
				(arc
					(start 171.207938 -223.462596)
					(mid 171.193059 -223.426675)
					(end 171.157138 -223.411796)
				)
				(arc
					(start 169.757598 -223.411796)
					(mid 169.721677 -223.426675)
					(end 169.706798 -223.462596)
				)
			)
		)
	)
	(zone
		(layers "In1.Cu" "In2.Cu")
		(hatch none 0.5)
		(connect_pads
			(clearance 0)
		)
		(min_thickness 0.25)
		(keepout
			(tracks not_allowed)
			(vias allowed)
			(pads allowed)
			(copperpour not_allowed)
			(footprints allowed)
		)
		(placement
			(enabled no)
			(sheetname "")
		)
		(fill yes
			(thermal_gap 0.5)
			(thermal_bridge_width 0.5)
			(island_removal_mode 0)
		)
		(polygon
			(pts
				(arc
					(start 410.103066 -233.22153)
					(mid 410.117945 -233.257451)
					(end 410.153866 -233.27233)
				)
				(arc
					(start 411.553406 -233.27233)
					(mid 411.589327 -233.257451)
					(end 411.604206 -233.22153)
				)
				(arc
					(start 411.604206 -232.81259)
					(mid 411.589327 -232.776669)
					(end 411.553406 -232.76179)
				)
				(arc
					(start 410.153866 -232.76179)
					(mid 410.117945 -232.776669)
					(end 410.103066 -232.81259)
				)
			)
		)
	)
	(zone
		(layers "In1.Cu" "In2.Cu")
		(hatch none 0.5)
		(connect_pads
			(clearance 0)
		)
		(min_thickness 0.25)
		(keepout
			(tracks not_allowed)
			(vias allowed)
			(pads allowed)
			(copperpour not_allowed)
			(footprints allowed)
		)
		(placement
			(enabled no)
			(sheetname "")
		)
		(fill yes
			(thermal_gap 0.5)
			(thermal_bridge_width 0.5)
			(island_removal_mode 0)
		)
		(polygon
			(pts
				(arc
					(start 274.517866 -248.521474)
					(mid 274.532745 -248.557395)
					(end 274.568666 -248.572274)
				)
				(arc
					(start 275.968206 -248.572274)
					(mid 276.004127 -248.557395)
					(end 276.019006 -248.521474)
				)
				(arc
					(start 276.019006 -248.112534)
					(mid 276.004127 -248.076613)
					(end 275.968206 -248.061734)
				)
				(arc
					(start 274.568666 -248.061734)
					(mid 274.532745 -248.076613)
					(end 274.517866 -248.112534)
				)
			)
		)
	)
	(zone
		(layers "In1.Cu" "In2.Cu")
		(hatch none 0.5)
		(connect_pads
			(clearance 0)
		)
		(min_thickness 0.25)
		(keepout
			(tracks not_allowed)
			(vias allowed)
			(pads allowed)
			(copperpour not_allowed)
			(footprints allowed)
		)
		(placement
			(enabled no)
			(sheetname "")
		)
		(fill yes
			(thermal_gap 0.5)
			(thermal_bridge_width 0.5)
			(island_removal_mode 0)
		)
		(polygon
			(pts
				(arc
					(start 22.47773 -247.671336)
					(mid 22.492609 -247.707257)
					(end 22.52853 -247.722136)
				)
				(arc
					(start 23.92807 -247.722136)
					(mid 23.963991 -247.707257)
					(end 23.97887 -247.671336)
				)
				(arc
					(start 23.97887 -247.262396)
					(mid 23.963991 -247.226475)
					(end 23.92807 -247.211596)
				)
				(arc
					(start 22.52853 -247.211596)
					(mid 22.492609 -247.226475)
					(end 22.47773 -247.262396)
				)
			)
		)
	)
	(zone
		(layers "In1.Cu" "In2.Cu")
		(hatch none 0.5)
		(connect_pads
			(clearance 0)
		)
		(min_thickness 0.25)
		(keepout
			(tracks not_allowed)
			(vias allowed)
			(pads allowed)
			(copperpour not_allowed)
			(footprints allowed)
		)
		(placement
			(enabled no)
			(sheetname "")
		)
		(fill yes
			(thermal_gap 0.5)
			(thermal_bridge_width 0.5)
			(island_removal_mode 0)
		)
		(polygon
			(pts
				(arc
					(start 214.969598 -231.521508)
					(mid 214.984477 -231.557429)
					(end 215.020398 -231.572308)
				)
				(arc
					(start 216.419938 -231.572308)
					(mid 216.455859 -231.557429)
					(end 216.470738 -231.521508)
				)
				(arc
					(start 216.470738 -231.112568)
					(mid 216.455859 -231.076647)
					(end 216.419938 -231.061768)
				)
				(arc
					(start 215.020398 -231.061768)
					(mid 214.984477 -231.076647)
					(end 214.969598 -231.112568)
				)
			)
		)
	)
	(zone
		(layers "In1.Cu" "In2.Cu")
		(hatch none 0.5)
		(connect_pads
			(clearance 0)
		)
		(min_thickness 0.25)
		(keepout
			(tracks not_allowed)
			(vias allowed)
			(pads allowed)
			(copperpour not_allowed)
			(footprints allowed)
		)
		(placement
			(enabled no)
			(sheetname "")
		)
		(fill yes
			(thermal_gap 0.5)
			(thermal_bridge_width 0.5)
			(island_removal_mode 0)
		)
		(polygon
			(pts
				(arc
					(start 440.278266 -206.871316)
					(mid 440.293145 -206.907237)
					(end 440.329066 -206.922116)
				)
				(arc
					(start 441.728606 -206.922116)
					(mid 441.764527 -206.907237)
					(end 441.779406 -206.871316)
				)
				(arc
					(start 441.779406 -206.462376)
					(mid 441.764527 -206.426455)
					(end 441.728606 -206.411576)
				)
				(arc
					(start 440.329066 -206.411576)
					(mid 440.293145 -206.426455)
					(end 440.278266 -206.462376)
				)
			)
		)
	)
	(zone
		(layers "In1.Cu" "In2.Cu")
		(hatch none 0.5)
		(connect_pads
			(clearance 0)
		)
		(min_thickness 0.25)
		(keepout
			(tracks not_allowed)
			(vias allowed)
			(pads allowed)
			(copperpour not_allowed)
			(footprints allowed)
		)
		(placement
			(enabled no)
			(sheetname "")
		)
		(fill yes
			(thermal_gap 0.5)
			(thermal_bridge_width 0.5)
			(island_removal_mode 0)
		)
		(polygon
			(pts
				(arc
					(start 447.822066 -199.221344)
					(mid 447.836945 -199.257265)
					(end 447.872866 -199.272144)
				)
				(arc
					(start 449.272406 -199.272144)
					(mid 449.308327 -199.257265)
					(end 449.323206 -199.221344)
				)
				(arc
					(start 449.323206 -198.812404)
					(mid 449.308327 -198.776483)
					(end 449.272406 -198.761604)
				)
				(arc
					(start 447.872866 -198.761604)
					(mid 447.836945 -198.776483)
					(end 447.822066 -198.812404)
				)
			)
		)
	)
	(zone
		(layers "In1.Cu" "In2.Cu")
		(hatch none 0.5)
		(connect_pads
			(clearance 0)
		)
		(min_thickness 0.25)
		(keepout
			(tracks not_allowed)
			(vias allowed)
			(pads allowed)
			(copperpour not_allowed)
			(footprints allowed)
		)
		(placement
			(enabled no)
			(sheetname "")
		)
		(fill yes
			(thermal_gap 0.5)
			(thermal_bridge_width 0.5)
			(island_removal_mode 0)
		)
		(polygon
			(pts
				(arc
					(start 270.417798 -204.32141)
					(mid 270.432677 -204.357331)
					(end 270.468598 -204.37221)
				)
				(arc
					(start 271.868138 -204.37221)
					(mid 271.904059 -204.357331)
					(end 271.918938 -204.32141)
				)
				(arc
					(start 271.918938 -203.91247)
					(mid 271.904059 -203.876549)
					(end 271.868138 -203.86167)
				)
				(arc
					(start 270.468598 -203.86167)
					(mid 270.432677 -203.876549)
					(end 270.417798 -203.91247)
				)
			)
		)
	)
	(zone
		(layers "In1.Cu" "In2.Cu")
		(hatch none 0.5)
		(connect_pads
			(clearance 0)
		)
		(min_thickness 0.25)
		(keepout
			(tracks not_allowed)
			(vias allowed)
			(pads allowed)
			(copperpour not_allowed)
			(footprints allowed)
		)
		(placement
			(enabled no)
			(sheetname "")
		)
		(fill yes
			(thermal_gap 0.5)
			(thermal_bridge_width 0.5)
			(island_removal_mode 0)
		)
		(polygon
			(pts
				(arc
					(start 455.365866 -217.921332)
					(mid 455.380745 -217.957253)
					(end 455.416666 -217.972132)
				)
				(arc
					(start 456.816206 -217.972132)
					(mid 456.852127 -217.957253)
					(end 456.867006 -217.921332)
				)
				(arc
					(start 456.867006 -217.512392)
					(mid 456.852127 -217.476471)
					(end 456.816206 -217.461592)
				)
				(arc
					(start 455.416666 -217.461592)
					(mid 455.380745 -217.476471)
					(end 455.365866 -217.512392)
				)
			)
		)
	)
	(zone
		(layers "In1.Cu" "In2.Cu")
		(hatch none 0.5)
		(connect_pads
			(clearance 0)
		)
		(min_thickness 0.25)
		(keepout
			(tracks not_allowed)
			(vias allowed)
			(pads allowed)
			(copperpour not_allowed)
			(footprints allowed)
		)
		(placement
			(enabled no)
			(sheetname "")
		)
		(fill yes
			(thermal_gap 0.5)
			(thermal_bridge_width 0.5)
			(island_removal_mode 0)
		)
		(polygon
			(pts
				(arc
					(start 293.049198 -235.771436)
					(mid 293.064077 -235.807357)
					(end 293.099998 -235.822236)
				)
				(arc
					(start 294.499538 -235.822236)
					(mid 294.535459 -235.807357)
					(end 294.550338 -235.771436)
				)
				(arc
					(start 294.550338 -235.362496)
					(mid 294.535459 -235.326575)
					(end 294.499538 -235.311696)
				)
				(arc
					(start 293.099998 -235.311696)
					(mid 293.064077 -235.326575)
					(end 293.049198 -235.362496)
				)
			)
		)
	)
	(zone
		(layers "In1.Cu" "In2.Cu")
		(hatch none 0.5)
		(connect_pads
			(clearance 0)
		)
		(min_thickness 0.25)
		(keepout
			(tracks not_allowed)
			(vias allowed)
			(pads allowed)
			(copperpour not_allowed)
			(footprints allowed)
		)
		(placement
			(enabled no)
			(sheetname "")
		)
		(fill yes
			(thermal_gap 0.5)
			(thermal_bridge_width 0.5)
			(island_removal_mode 0)
		)
		(polygon
			(pts
				(arc
					(start 406.002998 -252.771402)
					(mid 406.017877 -252.807323)
					(end 406.053798 -252.822202)
				)
				(arc
					(start 407.453338 -252.822202)
					(mid 407.489259 -252.807323)
					(end 407.504138 -252.771402)
				)
				(arc
					(start 407.504138 -252.362462)
					(mid 407.489259 -252.326541)
					(end 407.453338 -252.311662)
				)
				(arc
					(start 406.053798 -252.311662)
					(mid 406.017877 -252.326541)
					(end 406.002998 -252.362462)
				)
			)
		)
	)
	(zone
		(layers "In1.Cu" "In2.Cu")
		(hatch none 0.5)
		(connect_pads
			(clearance 0)
		)
		(min_thickness 0.25)
		(keepout
			(tracks not_allowed)
			(vias allowed)
			(pads allowed)
			(copperpour not_allowed)
			(footprints allowed)
		)
		(placement
			(enabled no)
			(sheetname "")
		)
		(fill yes
			(thermal_gap 0.5)
			(thermal_bridge_width 0.5)
			(island_removal_mode 0)
		)
		(polygon
			(pts
				(arc
					(start 455.365866 -298.671488)
					(mid 455.380745 -298.707409)
					(end 455.416666 -298.722288)
				)
				(arc
					(start 456.816206 -298.722288)
					(mid 456.852127 -298.707409)
					(end 456.867006 -298.671488)
				)
				(arc
					(start 456.867006 -298.262548)
					(mid 456.852127 -298.226627)
					(end 456.816206 -298.211748)
				)
				(arc
					(start 455.416666 -298.211748)
					(mid 455.380745 -298.226627)
					(end 455.365866 -298.262548)
				)
			)
		)
	)
	(zone
		(layers "In1.Cu" "In2.Cu")
		(hatch none 0.5)
		(connect_pads
			(clearance 0)
		)
		(min_thickness 0.25)
		(keepout
			(tracks not_allowed)
			(vias allowed)
			(pads allowed)
			(copperpour not_allowed)
			(footprints allowed)
		)
		(placement
			(enabled no)
			(sheetname "")
		)
		(fill yes
			(thermal_gap 0.5)
			(thermal_bridge_width 0.5)
			(island_removal_mode 0)
		)
		(polygon
			(pts
				(arc
					(start 447.822066 -211.121498)
					(mid 447.836945 -211.157419)
					(end 447.872866 -211.172298)
				)
				(arc
					(start 449.272406 -211.172298)
					(mid 449.308327 -211.157419)
					(end 449.323206 -211.121498)
				)
				(arc
					(start 449.323206 -210.712558)
					(mid 449.308327 -210.676637)
					(end 449.272406 -210.661758)
				)
				(arc
					(start 447.872866 -210.661758)
					(mid 447.836945 -210.676637)
					(end 447.822066 -210.712558)
				)
			)
		)
	)
	(zone
		(layers "In1.Cu" "In2.Cu")
		(hatch none 0.5)
		(connect_pads
			(clearance 0)
		)
		(min_thickness 0.25)
		(keepout
			(tracks not_allowed)
			(vias allowed)
			(pads allowed)
			(copperpour not_allowed)
			(footprints allowed)
		)
		(placement
			(enabled no)
			(sheetname "")
		)
		(fill yes
			(thermal_gap 0.5)
			(thermal_bridge_width 0.5)
			(island_removal_mode 0)
		)
		(polygon
			(pts
				(arc
					(start 262.873998 -294.421306)
					(mid 262.888877 -294.457227)
					(end 262.924798 -294.472106)
				)
				(arc
					(start 264.324338 -294.472106)
					(mid 264.360259 -294.457227)
					(end 264.375138 -294.421306)
				)
				(arc
					(start 264.375138 -294.012366)
					(mid 264.360259 -293.976445)
					(end 264.324338 -293.961566)
				)
				(arc
					(start 262.924798 -293.961566)
					(mid 262.888877 -293.976445)
					(end 262.873998 -294.012366)
				)
			)
		)
	)
	(zone
		(layers "In1.Cu" "In2.Cu")
		(hatch none 0.5)
		(connect_pads
			(clearance 0)
		)
		(min_thickness 0.25)
		(keepout
			(tracks not_allowed)
			(vias allowed)
			(pads allowed)
			(copperpour not_allowed)
			(footprints allowed)
		)
		(placement
			(enabled no)
			(sheetname "")
		)
		(fill yes
			(thermal_gap 0.5)
			(thermal_bridge_width 0.5)
			(island_removal_mode 0)
		)
		(polygon
			(pts
				(arc
					(start 432.734466 -197.521322)
					(mid 432.749345 -197.557243)
					(end 432.785266 -197.572122)
				)
				(arc
					(start 434.184806 -197.572122)
					(mid 434.220727 -197.557243)
					(end 434.235606 -197.521322)
				)
				(arc
					(start 434.235606 -197.112382)
					(mid 434.220727 -197.076461)
					(end 434.184806 -197.061582)
				)
				(arc
					(start 432.785266 -197.061582)
					(mid 432.749345 -197.076461)
					(end 432.734466 -197.112382)
				)
			)
		)
	)
	(zone
		(layers "In1.Cu" "In2.Cu")
		(hatch none 0.5)
		(connect_pads
			(clearance 0)
		)
		(min_thickness 0.25)
		(keepout
			(tracks not_allowed)
			(vias allowed)
			(pads allowed)
			(copperpour not_allowed)
			(footprints allowed)
		)
		(placement
			(enabled no)
			(sheetname "")
		)
		(fill yes
			(thermal_gap 0.5)
			(thermal_bridge_width 0.5)
			(island_removal_mode 0)
		)
		(polygon
			(pts
				(arc
					(start 312.236866 -268.921484)
					(mid 312.251745 -268.957405)
					(end 312.287666 -268.972284)
				)
				(arc
					(start 313.687206 -268.972284)
					(mid 313.723127 -268.957405)
					(end 313.738006 -268.921484)
				)
				(arc
					(start 313.738006 -268.512544)
					(mid 313.723127 -268.476623)
					(end 313.687206 -268.461744)
				)
				(arc
					(start 312.287666 -268.461744)
					(mid 312.251745 -268.476623)
					(end 312.236866 -268.512544)
				)
			)
		)
	)
	(zone
		(layers "In1.Cu" "In2.Cu")
		(hatch none 0.5)
		(connect_pads
			(clearance 0)
		)
		(min_thickness 0.25)
		(keepout
			(tracks not_allowed)
			(vias allowed)
			(pads allowed)
			(copperpour not_allowed)
			(footprints allowed)
		)
		(placement
			(enabled no)
			(sheetname "")
		)
		(fill yes
			(thermal_gap 0.5)
			(thermal_bridge_width 0.5)
			(island_removal_mode 0)
		)
		(polygon
			(pts
				(arc
					(start 462.909666 -259.57149)
					(mid 462.924545 -259.607411)
					(end 462.960466 -259.62229)
				)
				(arc
					(start 464.360006 -259.62229)
					(mid 464.395927 -259.607411)
					(end 464.410806 -259.57149)
				)
				(arc
					(start 464.410806 -259.16255)
					(mid 464.395927 -259.126629)
					(end 464.360006 -259.11175)
				)
				(arc
					(start 462.960466 -259.11175)
					(mid 462.924545 -259.126629)
					(end 462.909666 -259.16255)
				)
			)
		)
	)
	(zone
		(layers "In1.Cu" "In2.Cu")
		(hatch none 0.5)
		(connect_pads
			(clearance 0)
		)
		(min_thickness 0.25)
		(keepout
			(tracks not_allowed)
			(vias allowed)
			(pads allowed)
			(copperpour not_allowed)
			(footprints allowed)
		)
		(placement
			(enabled no)
			(sheetname "")
		)
		(fill yes
			(thermal_gap 0.5)
			(thermal_bridge_width 0.5)
			(island_removal_mode 0)
		)
		(polygon
			(pts
				(arc
					(start 56.752998 -222.171514)
					(mid 56.767877 -222.207435)
					(end 56.803798 -222.222314)
				)
				(arc
					(start 58.203338 -222.222314)
					(mid 58.239259 -222.207435)
					(end 58.254138 -222.171514)
				)
				(arc
					(start 58.254138 -221.762574)
					(mid 58.239259 -221.726653)
					(end 58.203338 -221.711774)
				)
				(arc
					(start 56.803798 -221.711774)
					(mid 56.767877 -221.726653)
					(end 56.752998 -221.762574)
				)
			)
		)
	)
	(zone
		(layers "In1.Cu" "In2.Cu")
		(hatch none 0.5)
		(connect_pads
			(clearance 0)
		)
		(min_thickness 0.25)
		(keepout
			(tracks not_allowed)
			(vias allowed)
			(pads allowed)
			(copperpour not_allowed)
			(footprints allowed)
		)
		(placement
			(enabled no)
			(sheetname "")
		)
		(fill yes
			(thermal_gap 0.5)
			(thermal_bridge_width 0.5)
			(island_removal_mode 0)
		)
		(polygon
			(pts
				(arc
					(start 199.881998 -211.121498)
					(mid 199.896877 -211.157419)
					(end 199.932798 -211.172298)
				)
				(arc
					(start 201.332338 -211.172298)
					(mid 201.368259 -211.157419)
					(end 201.383138 -211.121498)
				)
				(arc
					(start 201.383138 -210.712558)
					(mid 201.368259 -210.676637)
					(end 201.332338 -210.661758)
				)
				(arc
					(start 199.932798 -210.661758)
					(mid 199.896877 -210.676637)
					(end 199.881998 -210.712558)
				)
			)
		)
	)
	(zone
		(layers "In1.Cu" "In2.Cu")
		(hatch none 0.5)
		(connect_pads
			(clearance 0)
		)
		(min_thickness 0.25)
		(keepout
			(tracks not_allowed)
			(vias allowed)
			(pads allowed)
			(copperpour not_allowed)
			(footprints allowed)
		)
		(placement
			(enabled no)
			(sheetname "")
		)
		(fill yes
			(thermal_gap 0.5)
			(thermal_bridge_width 0.5)
			(island_removal_mode 0)
		)
		(polygon
			(pts
				(arc
					(start 304.693066 -225.571304)
					(mid 304.707945 -225.607225)
					(end 304.743866 -225.622104)
				)
				(arc
					(start 306.143406 -225.622104)
					(mid 306.179327 -225.607225)
					(end 306.194206 -225.571304)
				)
				(arc
					(start 306.194206 -225.162364)
					(mid 306.179327 -225.126443)
					(end 306.143406 -225.111564)
				)
				(arc
					(start 304.743866 -225.111564)
					(mid 304.707945 -225.126443)
					(end 304.693066 -225.162364)
				)
			)
		)
	)
	(zone
		(layers "In1.Cu" "In2.Cu")
		(hatch none 0.5)
		(connect_pads
			(clearance 0)
		)
		(min_thickness 0.25)
		(keepout
			(tracks not_allowed)
			(vias allowed)
			(pads allowed)
			(copperpour not_allowed)
			(footprints allowed)
		)
		(placement
			(enabled no)
			(sheetname "")
		)
		(fill yes
			(thermal_gap 0.5)
			(thermal_bridge_width 0.5)
			(island_removal_mode 0)
		)
		(polygon
			(pts
				(arc
					(start 428.634398 -196.671438)
					(mid 428.649277 -196.707359)
					(end 428.685198 -196.722238)
				)
				(arc
					(start 430.084738 -196.722238)
					(mid 430.120659 -196.707359)
					(end 430.135538 -196.671438)
				)
				(arc
					(start 430.135538 -196.262498)
					(mid 430.120659 -196.226577)
					(end 430.084738 -196.211698)
				)
				(arc
					(start 428.685198 -196.211698)
					(mid 428.649277 -196.226577)
					(end 428.634398 -196.262498)
				)
			)
		)
	)
	(zone
		(layers "In1.Cu" "In2.Cu")
		(hatch none 0.5)
		(connect_pads
			(clearance 0)
		)
		(min_thickness 0.25)
		(keepout
			(tracks not_allowed)
			(vias allowed)
			(pads allowed)
			(copperpour not_allowed)
			(footprints allowed)
		)
		(placement
			(enabled no)
			(sheetname "")
		)
		(fill yes
			(thermal_gap 0.5)
			(thermal_bridge_width 0.5)
			(island_removal_mode 0)
		)
		(polygon
			(pts
				(arc
					(start 289.605466 -259.57149)
					(mid 289.620345 -259.607411)
					(end 289.656266 -259.62229)
				)
				(arc
					(start 291.055806 -259.62229)
					(mid 291.091727 -259.607411)
					(end 291.106606 -259.57149)
				)
				(arc
					(start 291.106606 -259.16255)
					(mid 291.091727 -259.126629)
					(end 291.055806 -259.11175)
				)
				(arc
					(start 289.656266 -259.11175)
					(mid 289.620345 -259.126629)
					(end 289.605466 -259.16255)
				)
			)
		)
	)
	(zone
		(layers "In1.Cu" "In2.Cu")
		(hatch none 0.5)
		(connect_pads
			(clearance 0)
		)
		(min_thickness 0.25)
		(keepout
			(tracks not_allowed)
			(vias allowed)
			(pads allowed)
			(copperpour not_allowed)
			(footprints allowed)
		)
		(placement
			(enabled no)
			(sheetname "")
		)
		(fill yes
			(thermal_gap 0.5)
			(thermal_bridge_width 0.5)
			(island_removal_mode 0)
		)
		(polygon
			(pts
				(arc
					(start 64.296798 -234.921298)
					(mid 64.311677 -234.957219)
					(end 64.347598 -234.972098)
				)
				(arc
					(start 65.747138 -234.972098)
					(mid 65.783059 -234.957219)
					(end 65.797938 -234.921298)
				)
				(arc
					(start 65.797938 -234.512358)
					(mid 65.783059 -234.476437)
					(end 65.747138 -234.461558)
				)
				(arc
					(start 64.347598 -234.461558)
					(mid 64.311677 -234.476437)
					(end 64.296798 -234.512358)
				)
			)
		)
	)
	(zone
		(layers "In1.Cu" "In2.Cu")
		(hatch none 0.5)
		(connect_pads
			(clearance 0)
		)
		(min_thickness 0.25)
		(keepout
			(tracks not_allowed)
			(vias allowed)
			(pads allowed)
			(copperpour not_allowed)
			(footprints allowed)
		)
		(placement
			(enabled no)
			(sheetname "")
		)
		(fill yes
			(thermal_gap 0.5)
			(thermal_bridge_width 0.5)
			(island_removal_mode 0)
		)
		(polygon
			(pts
				(arc
					(start 188.23813 -314.821316)
					(mid 188.253009 -314.857237)
					(end 188.28893 -314.872116)
				)
				(arc
					(start 189.68847 -314.872116)
					(mid 189.724391 -314.857237)
					(end 189.73927 -314.821316)
				)
				(arc
					(start 189.73927 -314.412376)
					(mid 189.724391 -314.376455)
					(end 189.68847 -314.361576)
				)
				(arc
					(start 188.28893 -314.361576)
					(mid 188.253009 -314.376455)
					(end 188.23813 -314.412376)
				)
			)
		)
	)
	(zone
		(layers "In1.Cu" "In2.Cu")
		(hatch none 0.5)
		(connect_pads
			(clearance 0)
		)
		(min_thickness 0.25)
		(keepout
			(tracks not_allowed)
			(vias allowed)
			(pads allowed)
			(copperpour not_allowed)
			(footprints allowed)
		)
		(placement
			(enabled no)
			(sheetname "")
		)
		(fill yes
			(thermal_gap 0.5)
			(thermal_bridge_width 0.5)
			(island_removal_mode 0)
		)
		(polygon
			(pts
				(arc
					(start 436.178198 -221.321376)
					(mid 436.193077 -221.357297)
					(end 436.228998 -221.372176)
				)
				(arc
					(start 437.628538 -221.372176)
					(mid 437.664459 -221.357297)
					(end 437.679338 -221.321376)
				)
				(arc
					(start 437.679338 -220.912436)
					(mid 437.664459 -220.876515)
					(end 437.628538 -220.861636)
				)
				(arc
					(start 436.228998 -220.861636)
					(mid 436.193077 -220.876515)
					(end 436.178198 -220.912436)
				)
			)
		)
	)
	(zone
		(layers "In1.Cu" "In2.Cu")
		(hatch none 0.5)
		(connect_pads
			(clearance 0)
		)
		(min_thickness 0.25)
		(keepout
			(tracks not_allowed)
			(vias allowed)
			(pads allowed)
			(copperpour not_allowed)
			(footprints allowed)
		)
		(placement
			(enabled no)
			(sheetname "")
		)
		(fill yes
			(thermal_gap 0.5)
			(thermal_bridge_width 0.5)
			(island_removal_mode 0)
		)
		(polygon
			(pts
				(arc
					(start 304.693066 -228.121464)
					(mid 304.707945 -228.157385)
					(end 304.743866 -228.172264)
				)
				(arc
					(start 306.143406 -228.172264)
					(mid 306.179327 -228.157385)
					(end 306.194206 -228.121464)
				)
				(arc
					(start 306.194206 -227.712524)
					(mid 306.179327 -227.676603)
					(end 306.143406 -227.661724)
				)
				(arc
					(start 304.743866 -227.661724)
					(mid 304.707945 -227.676603)
					(end 304.693066 -227.712524)
				)
			)
		)
	)
	(zone
		(layers "In1.Cu" "In2.Cu")
		(hatch none 0.5)
		(connect_pads
			(clearance 0)
		)
		(min_thickness 0.25)
		(keepout
			(tracks not_allowed)
			(vias allowed)
			(pads allowed)
			(copperpour not_allowed)
			(footprints allowed)
		)
		(placement
			(enabled no)
			(sheetname "")
		)
		(fill yes
			(thermal_gap 0.5)
			(thermal_bridge_width 0.5)
			(island_removal_mode 0)
		)
		(polygon
			(pts
				(arc
					(start 259.430266 -304.621438)
					(mid 259.445145 -304.657359)
					(end 259.481066 -304.672238)
				)
				(arc
					(start 260.880606 -304.672238)
					(mid 260.916527 -304.657359)
					(end 260.931406 -304.621438)
				)
				(arc
					(start 260.931406 -304.212498)
					(mid 260.916527 -304.176577)
					(end 260.880606 -304.161698)
				)
				(arc
					(start 259.481066 -304.161698)
					(mid 259.445145 -304.176577)
					(end 259.430266 -304.212498)
				)
			)
		)
	)
	(zone
		(layers "In1.Cu" "In2.Cu")
		(hatch none 0.5)
		(connect_pads
			(clearance 0)
		)
		(min_thickness 0.25)
		(keepout
			(tracks not_allowed)
			(vias allowed)
			(pads allowed)
			(copperpour not_allowed)
			(footprints allowed)
		)
		(placement
			(enabled no)
			(sheetname "")
		)
		(fill yes
			(thermal_gap 0.5)
			(thermal_bridge_width 0.5)
			(island_removal_mode 0)
		)
		(polygon
			(pts
				(arc
					(start 37.56533 -290.171378)
					(mid 37.580209 -290.207299)
					(end 37.61613 -290.222178)
				)
				(arc
					(start 39.01567 -290.222178)
					(mid 39.051591 -290.207299)
					(end 39.06647 -290.171378)
				)
				(arc
					(start 39.06647 -289.762438)
					(mid 39.051591 -289.726517)
					(end 39.01567 -289.711638)
				)
				(arc
					(start 37.61613 -289.711638)
					(mid 37.580209 -289.726517)
					(end 37.56533 -289.762438)
				)
			)
		)
	)
	(zone
		(layers "In1.Cu" "In2.Cu")
		(hatch none 0.5)
		(connect_pads
			(clearance 0)
		)
		(min_thickness 0.25)
		(keepout
			(tracks not_allowed)
			(vias allowed)
			(pads allowed)
			(copperpour not_allowed)
			(footprints allowed)
		)
		(placement
			(enabled no)
			(sheetname "")
		)
		(fill yes
			(thermal_gap 0.5)
			(thermal_bridge_width 0.5)
			(island_removal_mode 0)
		)
		(polygon
			(pts
				(arc
					(start 158.06293 -235.771436)
					(mid 158.077809 -235.807357)
					(end 158.11373 -235.822236)
				)
				(arc
					(start 159.51327 -235.822236)
					(mid 159.549191 -235.807357)
					(end 159.56407 -235.771436)
				)
				(arc
					(start 159.56407 -235.362496)
					(mid 159.549191 -235.326575)
					(end 159.51327 -235.311696)
				)
				(arc
					(start 158.11373 -235.311696)
					(mid 158.077809 -235.326575)
					(end 158.06293 -235.362496)
				)
			)
		)
	)
	(zone
		(layers "In1.Cu" "In2.Cu")
		(hatch none 0.5)
		(connect_pads
			(clearance 0)
		)
		(min_thickness 0.25)
		(keepout
			(tracks not_allowed)
			(vias allowed)
			(pads allowed)
			(copperpour not_allowed)
			(footprints allowed)
		)
		(placement
			(enabled no)
			(sheetname "")
		)
		(fill yes
			(thermal_gap 0.5)
			(thermal_bridge_width 0.5)
			(island_removal_mode 0)
		)
		(polygon
			(pts
				(arc
					(start 410.103066 -195.821554)
					(mid 410.117945 -195.857475)
					(end 410.153866 -195.872354)
				)
				(arc
					(start 411.553406 -195.872354)
					(mid 411.589327 -195.857475)
					(end 411.604206 -195.821554)
				)
				(arc
					(start 411.604206 -195.412614)
					(mid 411.589327 -195.376693)
					(end 411.553406 -195.361814)
				)
				(arc
					(start 410.153866 -195.361814)
					(mid 410.117945 -195.376693)
					(end 410.103066 -195.412614)
				)
			)
		)
	)
	(zone
		(layers "In1.Cu" "In2.Cu")
		(hatch none 0.5)
		(connect_pads
			(clearance 0)
		)
		(min_thickness 0.25)
		(keepout
			(tracks not_allowed)
			(vias allowed)
			(pads allowed)
			(copperpour not_allowed)
			(footprints allowed)
		)
		(placement
			(enabled no)
			(sheetname "")
		)
		(fill yes
			(thermal_gap 0.5)
			(thermal_bridge_width 0.5)
			(island_removal_mode 0)
		)
		(polygon
			(pts
				(arc
					(start 289.605466 -309.721504)
					(mid 289.620345 -309.757425)
					(end 289.656266 -309.772304)
				)
				(arc
					(start 291.055806 -309.772304)
					(mid 291.091727 -309.757425)
					(end 291.106606 -309.721504)
				)
				(arc
					(start 291.106606 -309.312564)
					(mid 291.091727 -309.276643)
					(end 291.055806 -309.261764)
				)
				(arc
					(start 289.656266 -309.261764)
					(mid 289.620345 -309.276643)
					(end 289.605466 -309.312564)
				)
			)
		)
	)
	(zone
		(layers "In1.Cu" "In2.Cu")
		(hatch none 0.5)
		(connect_pads
			(clearance 0)
		)
		(min_thickness 0.25)
		(keepout
			(tracks not_allowed)
			(vias allowed)
			(pads allowed)
			(copperpour not_allowed)
			(footprints allowed)
		)
		(placement
			(enabled no)
			(sheetname "")
		)
		(fill yes
			(thermal_gap 0.5)
			(thermal_bridge_width 0.5)
			(island_removal_mode 0)
		)
		(polygon
			(pts
				(arc
					(start 188.23813 -228.121464)
					(mid 188.253009 -228.157385)
					(end 188.28893 -228.172264)
				)
				(arc
					(start 189.68847 -228.172264)
					(mid 189.724391 -228.157385)
					(end 189.73927 -228.121464)
				)
				(arc
					(start 189.73927 -227.712524)
					(mid 189.724391 -227.676603)
					(end 189.68847 -227.661724)
				)
				(arc
					(start 188.28893 -227.661724)
					(mid 188.253009 -227.676603)
					(end 188.23813 -227.712524)
				)
			)
		)
	)
	(zone
		(layers "In1.Cu" "In2.Cu")
		(hatch none 0.5)
		(connect_pads
			(clearance 0)
		)
		(min_thickness 0.25)
		(keepout
			(tracks not_allowed)
			(vias allowed)
			(pads allowed)
			(copperpour not_allowed)
			(footprints allowed)
		)
		(placement
			(enabled no)
			(sheetname "")
		)
		(fill yes
			(thermal_gap 0.5)
			(thermal_bridge_width 0.5)
			(island_removal_mode 0)
		)
		(polygon
			(pts
				(arc
					(start 462.909666 -216.22131)
					(mid 462.924545 -216.257231)
					(end 462.960466 -216.27211)
				)
				(arc
					(start 464.360006 -216.27211)
					(mid 464.395927 -216.257231)
					(end 464.410806 -216.22131)
				)
				(arc
					(start 464.410806 -215.81237)
					(mid 464.395927 -215.776449)
					(end 464.360006 -215.76157)
				)
				(arc
					(start 462.960466 -215.76157)
					(mid 462.924545 -215.776449)
					(end 462.909666 -215.81237)
				)
			)
		)
	)
	(zone
		(layers "In1.Cu" "In2.Cu")
		(hatch none 0.5)
		(connect_pads
			(clearance 0)
		)
		(min_thickness 0.25)
		(keepout
			(tracks not_allowed)
			(vias allowed)
			(pads allowed)
			(copperpour not_allowed)
			(footprints allowed)
		)
		(placement
			(enabled no)
			(sheetname "")
		)
		(fill yes
			(thermal_gap 0.5)
			(thermal_bridge_width 0.5)
			(island_removal_mode 0)
		)
		(polygon
			(pts
				(arc
					(start 421.090598 -224.72142)
					(mid 421.105477 -224.757341)
					(end 421.141398 -224.77222)
				)
				(arc
					(start 422.540938 -224.77222)
					(mid 422.576859 -224.757341)
					(end 422.591738 -224.72142)
				)
				(arc
					(start 422.591738 -224.31248)
					(mid 422.576859 -224.276559)
					(end 422.540938 -224.26168)
				)
				(arc
					(start 421.141398 -224.26168)
					(mid 421.105477 -224.276559)
					(end 421.090598 -224.31248)
				)
			)
		)
	)
	(zone
		(layers "In1.Cu" "In2.Cu")
		(hatch none 0.5)
		(connect_pads
			(clearance 0)
		)
		(min_thickness 0.25)
		(keepout
			(tracks not_allowed)
			(vias allowed)
			(pads allowed)
			(copperpour not_allowed)
			(footprints allowed)
		)
		(placement
			(enabled no)
			(sheetname "")
		)
		(fill yes
			(thermal_gap 0.5)
			(thermal_bridge_width 0.5)
			(island_removal_mode 0)
		)
		(polygon
			(pts
				(arc
					(start 440.278266 -212.82152)
					(mid 440.293145 -212.857441)
					(end 440.329066 -212.87232)
				)
				(arc
					(start 441.728606 -212.87232)
					(mid 441.764527 -212.857441)
					(end 441.779406 -212.82152)
				)
				(arc
					(start 441.779406 -212.41258)
					(mid 441.764527 -212.376659)
					(end 441.728606 -212.36178)
				)
				(arc
					(start 440.329066 -212.36178)
					(mid 440.293145 -212.376659)
					(end 440.278266 -212.41258)
				)
			)
		)
	)
	(zone
		(layers "In1.Cu" "In2.Cu")
		(hatch none 0.5)
		(connect_pads
			(clearance 0)
		)
		(min_thickness 0.25)
		(keepout
			(tracks not_allowed)
			(vias allowed)
			(pads allowed)
			(copperpour not_allowed)
			(footprints allowed)
		)
		(placement
			(enabled no)
			(sheetname "")
		)
		(fill yes
			(thermal_gap 0.5)
			(thermal_bridge_width 0.5)
			(island_removal_mode 0)
		)
		(polygon
			(pts
				(arc
					(start 406.002998 -238.321342)
					(mid 406.017877 -238.357263)
					(end 406.053798 -238.372142)
				)
				(arc
					(start 407.453338 -238.372142)
					(mid 407.489259 -238.357263)
					(end 407.504138 -238.321342)
				)
				(arc
					(start 407.504138 -237.912402)
					(mid 407.489259 -237.876481)
					(end 407.453338 -237.861602)
				)
				(arc
					(start 406.053798 -237.861602)
					(mid 406.017877 -237.876481)
					(end 406.002998 -237.912402)
				)
			)
		)
	)
	(zone
		(layers "In1.Cu" "In2.Cu")
		(hatch none 0.5)
		(connect_pads
			(clearance 0)
		)
		(min_thickness 0.25)
		(keepout
			(tracks not_allowed)
			(vias allowed)
			(pads allowed)
			(copperpour not_allowed)
			(footprints allowed)
		)
		(placement
			(enabled no)
			(sheetname "")
		)
		(fill yes
			(thermal_gap 0.5)
			(thermal_bridge_width 0.5)
			(island_removal_mode 0)
		)
		(polygon
			(pts
				(arc
					(start 30.02153 -259.57149)
					(mid 30.036409 -259.607411)
					(end 30.07233 -259.62229)
				)
				(arc
					(start 31.47187 -259.62229)
					(mid 31.507791 -259.607411)
					(end 31.52267 -259.57149)
				)
				(arc
					(start 31.52267 -259.16255)
					(mid 31.507791 -259.126629)
					(end 31.47187 -259.11175)
				)
				(arc
					(start 30.07233 -259.11175)
					(mid 30.036409 -259.126629)
					(end 30.02153 -259.16255)
				)
			)
		)
	)
	(zone
		(layers "In1.Cu" "In2.Cu")
		(hatch none 0.5)
		(connect_pads
			(clearance 0)
		)
		(min_thickness 0.25)
		(keepout
			(tracks not_allowed)
			(vias allowed)
			(pads allowed)
			(copperpour not_allowed)
			(footprints allowed)
		)
		(placement
			(enabled no)
			(sheetname "")
		)
		(fill yes
			(thermal_gap 0.5)
			(thermal_bridge_width 0.5)
			(island_removal_mode 0)
		)
		(polygon
			(pts
				(arc
					(start 180.69433 -266.371324)
					(mid 180.709209 -266.407245)
					(end 180.74513 -266.422124)
				)
				(arc
					(start 182.14467 -266.422124)
					(mid 182.180591 -266.407245)
					(end 182.19547 -266.371324)
				)
				(arc
					(start 182.19547 -265.962384)
					(mid 182.180591 -265.926463)
					(end 182.14467 -265.911584)
				)
				(arc
					(start 180.74513 -265.911584)
					(mid 180.709209 -265.926463)
					(end 180.69433 -265.962384)
				)
			)
		)
	)
	(zone
		(layers "In1.Cu" "In2.Cu")
		(hatch none 0.5)
		(connect_pads
			(clearance 0)
		)
		(min_thickness 0.25)
		(keepout
			(tracks not_allowed)
			(vias allowed)
			(pads allowed)
			(copperpour not_allowed)
			(footprints allowed)
		)
		(placement
			(enabled no)
			(sheetname "")
		)
		(fill yes
			(thermal_gap 0.5)
			(thermal_bridge_width 0.5)
			(island_removal_mode 0)
		)
		(polygon
			(pts
				(arc
					(start 277.961598 -262.971534)
					(mid 277.976477 -263.007455)
					(end 278.012398 -263.022334)
				)
				(arc
					(start 279.411938 -263.022334)
					(mid 279.447859 -263.007455)
					(end 279.462738 -262.971534)
				)
				(arc
					(start 279.462738 -262.562594)
					(mid 279.447859 -262.526673)
					(end 279.411938 -262.511794)
				)
				(arc
					(start 278.012398 -262.511794)
					(mid 277.976477 -262.526673)
					(end 277.961598 -262.562594)
				)
			)
		)
	)
	(zone
		(layers "In1.Cu" "In2.Cu")
		(hatch none 0.5)
		(connect_pads
			(clearance 0)
		)
		(min_thickness 0.25)
		(keepout
			(tracks not_allowed)
			(vias allowed)
			(pads allowed)
			(copperpour not_allowed)
			(footprints allowed)
		)
		(placement
			(enabled no)
			(sheetname "")
		)
		(fill yes
			(thermal_gap 0.5)
			(thermal_bridge_width 0.5)
			(island_removal_mode 0)
		)
		(polygon
			(pts
				(arc
					(start 203.32573 -219.621354)
					(mid 203.340609 -219.657275)
					(end 203.37653 -219.672154)
				)
				(arc
					(start 204.77607 -219.672154)
					(mid 204.811991 -219.657275)
					(end 204.82687 -219.621354)
				)
				(arc
					(start 204.82687 -219.212414)
					(mid 204.811991 -219.176493)
					(end 204.77607 -219.161614)
				)
				(arc
					(start 203.37653 -219.161614)
					(mid 203.340609 -219.176493)
					(end 203.32573 -219.212414)
				)
			)
		)
	)
	(zone
		(layers "In1.Cu" "In2.Cu")
		(hatch none 0.5)
		(connect_pads
			(clearance 0)
		)
		(min_thickness 0.25)
		(keepout
			(tracks not_allowed)
			(vias allowed)
			(pads allowed)
			(copperpour not_allowed)
			(footprints allowed)
		)
		(placement
			(enabled no)
			(sheetname "")
		)
		(fill yes
			(thermal_gap 0.5)
			(thermal_bridge_width 0.5)
			(island_removal_mode 0)
		)
		(polygon
			(pts
				(arc
					(start 266.974066 -302.071532)
					(mid 266.988945 -302.107453)
					(end 267.024866 -302.122332)
				)
				(arc
					(start 268.424406 -302.122332)
					(mid 268.460327 -302.107453)
					(end 268.475206 -302.071532)
				)
				(arc
					(start 268.475206 -301.662592)
					(mid 268.460327 -301.626671)
					(end 268.424406 -301.611792)
				)
				(arc
					(start 267.024866 -301.611792)
					(mid 266.988945 -301.626671)
					(end 266.974066 -301.662592)
				)
			)
		)
	)
	(zone
		(layers "In1.Cu" "In2.Cu")
		(hatch none 0.5)
		(connect_pads
			(clearance 0)
		)
		(min_thickness 0.25)
		(keepout
			(tracks not_allowed)
			(vias allowed)
			(pads allowed)
			(copperpour not_allowed)
			(footprints allowed)
		)
		(placement
			(enabled no)
			(sheetname "")
		)
		(fill yes
			(thermal_gap 0.5)
			(thermal_bridge_width 0.5)
			(island_removal_mode 0)
		)
		(polygon
			(pts
				(arc
					(start 458.809598 -243.421408)
					(mid 458.824477 -243.457329)
					(end 458.860398 -243.472208)
				)
				(arc
					(start 460.259938 -243.472208)
					(mid 460.295859 -243.457329)
					(end 460.310738 -243.421408)
				)
				(arc
					(start 460.310738 -243.012468)
					(mid 460.295859 -242.976547)
					(end 460.259938 -242.961668)
				)
				(arc
					(start 458.860398 -242.961668)
					(mid 458.824477 -242.976547)
					(end 458.809598 -243.012468)
				)
			)
		)
	)
	(zone
		(layers "In1.Cu" "In2.Cu")
		(hatch none 0.5)
		(connect_pads
			(clearance 0)
		)
		(min_thickness 0.25)
		(keepout
			(tracks not_allowed)
			(vias allowed)
			(pads allowed)
			(copperpour not_allowed)
			(footprints allowed)
		)
		(placement
			(enabled no)
			(sheetname "")
		)
		(fill yes
			(thermal_gap 0.5)
			(thermal_bridge_width 0.5)
			(island_removal_mode 0)
		)
		(polygon
			(pts
				(arc
					(start 300.592998 -234.071414)
					(mid 300.607877 -234.107335)
					(end 300.643798 -234.122214)
				)
				(arc
					(start 302.043338 -234.122214)
					(mid 302.079259 -234.107335)
					(end 302.094138 -234.071414)
				)
				(arc
					(start 302.094138 -233.662474)
					(mid 302.079259 -233.626553)
					(end 302.043338 -233.611674)
				)
				(arc
					(start 300.643798 -233.611674)
					(mid 300.607877 -233.626553)
					(end 300.592998 -233.662474)
				)
			)
		)
	)
	(zone
		(layers "In1.Cu" "In2.Cu")
		(hatch none 0.5)
		(connect_pads
			(clearance 0)
		)
		(min_thickness 0.25)
		(keepout
			(tracks not_allowed)
			(vias allowed)
			(pads allowed)
			(copperpour not_allowed)
			(footprints allowed)
		)
		(placement
			(enabled no)
			(sheetname "")
		)
		(fill yes
			(thermal_gap 0.5)
			(thermal_bridge_width 0.5)
			(island_removal_mode 0)
		)
		(polygon
			(pts
				(arc
					(start 56.752998 -289.321494)
					(mid 56.767877 -289.357415)
					(end 56.803798 -289.372294)
				)
				(arc
					(start 58.203338 -289.372294)
					(mid 58.239259 -289.357415)
					(end 58.254138 -289.321494)
				)
				(arc
					(start 58.254138 -288.912554)
					(mid 58.239259 -288.876633)
					(end 58.203338 -288.861754)
				)
				(arc
					(start 56.803798 -288.861754)
					(mid 56.767877 -288.876633)
					(end 56.752998 -288.912554)
				)
			)
		)
	)
	(zone
		(layers "In1.Cu" "In2.Cu")
		(hatch none 0.5)
		(connect_pads
			(clearance 0)
		)
		(min_thickness 0.25)
		(keepout
			(tracks not_allowed)
			(vias allowed)
			(pads allowed)
			(copperpour not_allowed)
			(footprints allowed)
		)
		(placement
			(enabled no)
			(sheetname "")
		)
		(fill yes
			(thermal_gap 0.5)
			(thermal_bridge_width 0.5)
			(island_removal_mode 0)
		)
		(polygon
			(pts
				(arc
					(start 30.02153 -241.721386)
					(mid 30.036409 -241.757307)
					(end 30.07233 -241.772186)
				)
				(arc
					(start 31.47187 -241.772186)
					(mid 31.507791 -241.757307)
					(end 31.52267 -241.721386)
				)
				(arc
					(start 31.52267 -241.312446)
					(mid 31.507791 -241.276525)
					(end 31.47187 -241.261646)
				)
				(arc
					(start 30.07233 -241.261646)
					(mid 30.036409 -241.276525)
					(end 30.02153 -241.312446)
				)
			)
		)
	)
	(zone
		(layers "In1.Cu" "In2.Cu")
		(hatch none 0.5)
		(connect_pads
			(clearance 0)
		)
		(min_thickness 0.25)
		(keepout
			(tracks not_allowed)
			(vias allowed)
			(pads allowed)
			(copperpour not_allowed)
			(footprints allowed)
		)
		(placement
			(enabled no)
			(sheetname "")
		)
		(fill yes
			(thermal_gap 0.5)
			(thermal_bridge_width 0.5)
			(island_removal_mode 0)
		)
		(polygon
			(pts
				(arc
					(start 413.546798 -314.821316)
					(mid 413.561677 -314.857237)
					(end 413.597598 -314.872116)
				)
				(arc
					(start 414.997138 -314.872116)
					(mid 415.033059 -314.857237)
					(end 415.047938 -314.821316)
				)
				(arc
					(start 415.047938 -314.412376)
					(mid 415.033059 -314.376455)
					(end 414.997138 -314.361576)
				)
				(arc
					(start 413.597598 -314.361576)
					(mid 413.561677 -314.376455)
					(end 413.546798 -314.412376)
				)
			)
		)
	)
	(zone
		(layers "In1.Cu" "In2.Cu")
		(hatch none 0.5)
		(connect_pads
			(clearance 0)
		)
		(min_thickness 0.25)
		(keepout
			(tracks not_allowed)
			(vias allowed)
			(pads allowed)
			(copperpour not_allowed)
			(footprints allowed)
		)
		(placement
			(enabled no)
			(sheetname "")
		)
		(fill yes
			(thermal_gap 0.5)
			(thermal_bridge_width 0.5)
			(island_removal_mode 0)
		)
		(polygon
			(pts
				(arc
					(start 203.32573 -221.321376)
					(mid 203.340609 -221.357297)
					(end 203.37653 -221.372176)
				)
				(arc
					(start 204.77607 -221.372176)
					(mid 204.811991 -221.357297)
					(end 204.82687 -221.321376)
				)
				(arc
					(start 204.82687 -220.912436)
					(mid 204.811991 -220.876515)
					(end 204.77607 -220.861636)
				)
				(arc
					(start 203.37653 -220.861636)
					(mid 203.340609 -220.876515)
					(end 203.32573 -220.912436)
				)
			)
		)
	)
	(zone
		(layers "In1.Cu" "In2.Cu")
		(hatch none 0.5)
		(connect_pads
			(clearance 0)
		)
		(min_thickness 0.25)
		(keepout
			(tracks not_allowed)
			(vias allowed)
			(pads allowed)
			(copperpour not_allowed)
			(footprints allowed)
		)
		(placement
			(enabled no)
			(sheetname "")
		)
		(fill yes
			(thermal_gap 0.5)
			(thermal_bridge_width 0.5)
			(island_removal_mode 0)
		)
		(polygon
			(pts
				(arc
					(start 266.974066 -225.571304)
					(mid 266.988945 -225.607225)
					(end 267.024866 -225.622104)
				)
				(arc
					(start 268.424406 -225.622104)
					(mid 268.460327 -225.607225)
					(end 268.475206 -225.571304)
				)
				(arc
					(start 268.475206 -225.162364)
					(mid 268.460327 -225.126443)
					(end 268.424406 -225.111564)
				)
				(arc
					(start 267.024866 -225.111564)
					(mid 266.988945 -225.126443)
					(end 266.974066 -225.162364)
				)
			)
		)
	)
	(zone
		(layers "In1.Cu" "In2.Cu")
		(hatch none 0.5)
		(connect_pads
			(clearance 0)
		)
		(min_thickness 0.25)
		(keepout
			(tracks not_allowed)
			(vias allowed)
			(pads allowed)
			(copperpour not_allowed)
			(footprints allowed)
		)
		(placement
			(enabled no)
			(sheetname "")
		)
		(fill yes
			(thermal_gap 0.5)
			(thermal_bridge_width 0.5)
			(island_removal_mode 0)
		)
		(polygon
			(pts
				(arc
					(start 436.178198 -266.371324)
					(mid 436.193077 -266.407245)
					(end 436.228998 -266.422124)
				)
				(arc
					(start 437.628538 -266.422124)
					(mid 437.664459 -266.407245)
					(end 437.679338 -266.371324)
				)
				(arc
					(start 437.679338 -265.962384)
					(mid 437.664459 -265.926463)
					(end 437.628538 -265.911584)
				)
				(arc
					(start 436.228998 -265.911584)
					(mid 436.193077 -265.926463)
					(end 436.178198 -265.962384)
				)
			)
		)
	)
	(zone
		(layers "In1.Cu" "In2.Cu")
		(hatch none 0.5)
		(connect_pads
			(clearance 0)
		)
		(min_thickness 0.25)
		(keepout
			(tracks not_allowed)
			(vias allowed)
			(pads allowed)
			(copperpour not_allowed)
			(footprints allowed)
		)
		(placement
			(enabled no)
			(sheetname "")
		)
		(fill yes
			(thermal_gap 0.5)
			(thermal_bridge_width 0.5)
			(island_removal_mode 0)
		)
		(polygon
			(pts
				(arc
					(start 158.06293 -232.371392)
					(mid 158.077809 -232.407313)
					(end 158.11373 -232.422192)
				)
				(arc
					(start 159.51327 -232.422192)
					(mid 159.549191 -232.407313)
					(end 159.56407 -232.371392)
				)
				(arc
					(start 159.56407 -231.962452)
					(mid 159.549191 -231.926531)
					(end 159.51327 -231.911652)
				)
				(arc
					(start 158.11373 -231.911652)
					(mid 158.077809 -231.926531)
					(end 158.06293 -231.962452)
				)
			)
		)
	)
	(zone
		(layers "In1.Cu" "In2.Cu")
		(hatch none 0.5)
		(connect_pads
			(clearance 0)
		)
		(min_thickness 0.25)
		(keepout
			(tracks not_allowed)
			(vias allowed)
			(pads allowed)
			(copperpour not_allowed)
			(footprints allowed)
		)
		(placement
			(enabled no)
			(sheetname "")
		)
		(fill yes
			(thermal_gap 0.5)
			(thermal_bridge_width 0.5)
			(island_removal_mode 0)
		)
		(polygon
			(pts
				(arc
					(start 49.209198 -278.271478)
					(mid 49.224077 -278.307399)
					(end 49.259998 -278.322278)
				)
				(arc
					(start 50.659538 -278.322278)
					(mid 50.695459 -278.307399)
					(end 50.710338 -278.271478)
				)
				(arc
					(start 50.710338 -277.862538)
					(mid 50.695459 -277.826617)
					(end 50.659538 -277.811738)
				)
				(arc
					(start 49.259998 -277.811738)
					(mid 49.224077 -277.826617)
					(end 49.209198 -277.862538)
				)
			)
		)
	)
	(zone
		(layers "In1.Cu" "In2.Cu")
		(hatch none 0.5)
		(connect_pads
			(clearance 0)
		)
		(min_thickness 0.25)
		(keepout
			(tracks not_allowed)
			(vias allowed)
			(pads allowed)
			(copperpour not_allowed)
			(footprints allowed)
		)
		(placement
			(enabled no)
			(sheetname "")
		)
		(fill yes
			(thermal_gap 0.5)
			(thermal_bridge_width 0.5)
			(island_removal_mode 0)
		)
		(polygon
			(pts
				(arc
					(start 304.693066 -302.071532)
					(mid 304.707945 -302.107453)
					(end 304.743866 -302.122332)
				)
				(arc
					(start 306.143406 -302.122332)
					(mid 306.179327 -302.107453)
					(end 306.194206 -302.071532)
				)
				(arc
					(start 306.194206 -301.662592)
					(mid 306.179327 -301.626671)
					(end 306.143406 -301.611792)
				)
				(arc
					(start 304.743866 -301.611792)
					(mid 304.707945 -301.626671)
					(end 304.693066 -301.662592)
				)
			)
		)
	)
	(zone
		(layers "In1.Cu" "In2.Cu")
		(hatch none 0.5)
		(connect_pads
			(clearance 0)
		)
		(min_thickness 0.25)
		(keepout
			(tracks not_allowed)
			(vias allowed)
			(pads allowed)
			(copperpour not_allowed)
			(footprints allowed)
		)
		(placement
			(enabled no)
			(sheetname "")
		)
		(fill yes
			(thermal_gap 0.5)
			(thermal_bridge_width 0.5)
			(island_removal_mode 0)
		)
		(polygon
			(pts
				(arc
					(start 210.86953 -264.671302)
					(mid 210.884409 -264.707223)
					(end 210.92033 -264.722102)
				)
				(arc
					(start 212.31987 -264.722102)
					(mid 212.355791 -264.707223)
					(end 212.37067 -264.671302)
				)
				(arc
					(start 212.37067 -264.262362)
					(mid 212.355791 -264.226441)
					(end 212.31987 -264.211562)
				)
				(arc
					(start 210.92033 -264.211562)
					(mid 210.884409 -264.226441)
					(end 210.86953 -264.262362)
				)
			)
		)
	)
	(zone
		(layers "In1.Cu" "In2.Cu")
		(hatch none 0.5)
		(connect_pads
			(clearance 0)
		)
		(min_thickness 0.25)
		(keepout
			(tracks not_allowed)
			(vias allowed)
			(pads allowed)
			(copperpour not_allowed)
			(footprints allowed)
		)
		(placement
			(enabled no)
			(sheetname "")
		)
		(fill yes
			(thermal_gap 0.5)
			(thermal_bridge_width 0.5)
			(island_removal_mode 0)
		)
		(polygon
			(pts
				(arc
					(start 207.425798 -302.921416)
					(mid 207.440677 -302.957337)
					(end 207.476598 -302.972216)
				)
				(arc
					(start 208.876138 -302.972216)
					(mid 208.912059 -302.957337)
					(end 208.926938 -302.921416)
				)
				(arc
					(start 208.926938 -302.512476)
					(mid 208.912059 -302.476555)
					(end 208.876138 -302.461676)
				)
				(arc
					(start 207.476598 -302.461676)
					(mid 207.440677 -302.476555)
					(end 207.425798 -302.512476)
				)
			)
		)
	)
	(zone
		(layers "In1.Cu" "In2.Cu")
		(hatch none 0.5)
		(connect_pads
			(clearance 0)
		)
		(min_thickness 0.25)
		(keepout
			(tracks not_allowed)
			(vias allowed)
			(pads allowed)
			(copperpour not_allowed)
			(footprints allowed)
		)
		(placement
			(enabled no)
			(sheetname "")
		)
		(fill yes
			(thermal_gap 0.5)
			(thermal_bridge_width 0.5)
			(island_removal_mode 0)
		)
		(polygon
			(pts
				(arc
					(start 293.049198 -303.7713)
					(mid 293.064077 -303.807221)
					(end 293.099998 -303.8221)
				)
				(arc
					(start 294.499538 -303.8221)
					(mid 294.535459 -303.807221)
					(end 294.550338 -303.7713)
				)
				(arc
					(start 294.550338 -303.36236)
					(mid 294.535459 -303.326439)
					(end 294.499538 -303.31156)
				)
				(arc
					(start 293.099998 -303.31156)
					(mid 293.064077 -303.326439)
					(end 293.049198 -303.36236)
				)
			)
		)
	)
	(zone
		(layers "In1.Cu" "In2.Cu")
		(hatch none 0.5)
		(connect_pads
			(clearance 0)
		)
		(min_thickness 0.25)
		(keepout
			(tracks not_allowed)
			(vias allowed)
			(pads allowed)
			(copperpour not_allowed)
			(footprints allowed)
		)
		(placement
			(enabled no)
			(sheetname "")
		)
		(fill yes
			(thermal_gap 0.5)
			(thermal_bridge_width 0.5)
			(island_removal_mode 0)
		)
		(polygon
			(pts
				(arc
					(start 45.10913 -302.921416)
					(mid 45.124009 -302.957337)
					(end 45.15993 -302.972216)
				)
				(arc
					(start 46.55947 -302.972216)
					(mid 46.595391 -302.957337)
					(end 46.61027 -302.921416)
				)
				(arc
					(start 46.61027 -302.512476)
					(mid 46.595391 -302.476555)
					(end 46.55947 -302.461676)
				)
				(arc
					(start 45.15993 -302.461676)
					(mid 45.124009 -302.476555)
					(end 45.10913 -302.512476)
				)
			)
		)
	)
	(zone
		(layers "In1.Cu" "In2.Cu")
		(hatch none 0.5)
		(connect_pads
			(clearance 0)
		)
		(min_thickness 0.25)
		(keepout
			(tracks not_allowed)
			(vias allowed)
			(pads allowed)
			(copperpour not_allowed)
			(footprints allowed)
		)
		(placement
			(enabled no)
			(sheetname "")
		)
		(fill yes
			(thermal_gap 0.5)
			(thermal_bridge_width 0.5)
			(island_removal_mode 0)
		)
		(polygon
			(pts
				(arc
					(start 203.32573 -249.371358)
					(mid 203.340609 -249.407279)
					(end 203.37653 -249.422158)
				)
				(arc
					(start 204.77607 -249.422158)
					(mid 204.811991 -249.407279)
					(end 204.82687 -249.371358)
				)
				(arc
					(start 204.82687 -248.962418)
					(mid 204.811991 -248.926497)
					(end 204.77607 -248.911618)
				)
				(arc
					(start 203.37653 -248.911618)
					(mid 203.340609 -248.926497)
					(end 203.32573 -248.962418)
				)
			)
		)
	)
	(zone
		(layers "In1.Cu" "In2.Cu")
		(hatch none 0.5)
		(connect_pads
			(clearance 0)
		)
		(min_thickness 0.25)
		(keepout
			(tracks not_allowed)
			(vias allowed)
			(pads allowed)
			(copperpour not_allowed)
			(footprints allowed)
		)
		(placement
			(enabled no)
			(sheetname "")
		)
		(fill yes
			(thermal_gap 0.5)
			(thermal_bridge_width 0.5)
			(island_removal_mode 0)
		)
		(polygon
			(pts
				(arc
					(start 34.121598 -278.271478)
					(mid 34.136477 -278.307399)
					(end 34.172398 -278.322278)
				)
				(arc
					(start 35.571938 -278.322278)
					(mid 35.607859 -278.307399)
					(end 35.622738 -278.271478)
				)
				(arc
					(start 35.622738 -277.862538)
					(mid 35.607859 -277.826617)
					(end 35.571938 -277.811738)
				)
				(arc
					(start 34.172398 -277.811738)
					(mid 34.136477 -277.826617)
					(end 34.121598 -277.862538)
				)
			)
		)
	)
	(zone
		(layers "In1.Cu" "In2.Cu")
		(hatch none 0.5)
		(connect_pads
			(clearance 0)
		)
		(min_thickness 0.25)
		(keepout
			(tracks not_allowed)
			(vias allowed)
			(pads allowed)
			(copperpour not_allowed)
			(footprints allowed)
		)
		(placement
			(enabled no)
			(sheetname "")
		)
		(fill yes
			(thermal_gap 0.5)
			(thermal_bridge_width 0.5)
			(island_removal_mode 0)
		)
		(polygon
			(pts
				(arc
					(start 22.47773 -238.321342)
					(mid 22.492609 -238.357263)
					(end 22.52853 -238.372142)
				)
				(arc
					(start 23.92807 -238.372142)
					(mid 23.963991 -238.357263)
					(end 23.97887 -238.321342)
				)
				(arc
					(start 23.97887 -237.912402)
					(mid 23.963991 -237.876481)
					(end 23.92807 -237.861602)
				)
				(arc
					(start 22.52853 -237.861602)
					(mid 22.492609 -237.876481)
					(end 22.47773 -237.912402)
				)
			)
		)
	)
	(zone
		(layers "In1.Cu" "In2.Cu")
		(hatch none 0.5)
		(connect_pads
			(clearance 0)
		)
		(min_thickness 0.25)
		(keepout
			(tracks not_allowed)
			(vias allowed)
			(pads allowed)
			(copperpour not_allowed)
			(footprints allowed)
		)
		(placement
			(enabled no)
			(sheetname "")
		)
		(fill yes
			(thermal_gap 0.5)
			(thermal_bridge_width 0.5)
			(island_removal_mode 0)
		)
		(polygon
			(pts
				(arc
					(start 406.002998 -280.821384)
					(mid 406.017877 -280.857305)
					(end 406.053798 -280.872184)
				)
				(arc
					(start 407.453338 -280.872184)
					(mid 407.489259 -280.857305)
					(end 407.504138 -280.821384)
				)
				(arc
					(start 407.504138 -280.412444)
					(mid 407.489259 -280.376523)
					(end 407.453338 -280.361644)
				)
				(arc
					(start 406.053798 -280.361644)
					(mid 406.017877 -280.376523)
					(end 406.002998 -280.412444)
				)
			)
		)
	)
	(zone
		(layers "In1.Cu" "In2.Cu")
		(hatch none 0.5)
		(connect_pads
			(clearance 0)
		)
		(min_thickness 0.25)
		(keepout
			(tracks not_allowed)
			(vias allowed)
			(pads allowed)
			(copperpour not_allowed)
			(footprints allowed)
		)
		(placement
			(enabled no)
			(sheetname "")
		)
		(fill yes
			(thermal_gap 0.5)
			(thermal_bridge_width 0.5)
			(island_removal_mode 0)
		)
		(polygon
			(pts
				(arc
					(start 45.10913 -243.421408)
					(mid 45.124009 -243.457329)
					(end 45.15993 -243.472208)
				)
				(arc
					(start 46.55947 -243.472208)
					(mid 46.595391 -243.457329)
					(end 46.61027 -243.421408)
				)
				(arc
					(start 46.61027 -243.012468)
					(mid 46.595391 -242.976547)
					(end 46.55947 -242.961668)
				)
				(arc
					(start 45.15993 -242.961668)
					(mid 45.124009 -242.976547)
					(end 45.10913 -243.012468)
				)
			)
		)
	)
	(zone
		(layers "In1.Cu" "In2.Cu")
		(hatch none 0.5)
		(connect_pads
			(clearance 0)
		)
		(min_thickness 0.25)
		(keepout
			(tracks not_allowed)
			(vias allowed)
			(pads allowed)
			(copperpour not_allowed)
			(footprints allowed)
		)
		(placement
			(enabled no)
			(sheetname "")
		)
		(fill yes
			(thermal_gap 0.5)
			(thermal_bridge_width 0.5)
			(island_removal_mode 0)
		)
		(polygon
			(pts
				(arc
					(start 425.190666 -223.871536)
					(mid 425.205545 -223.907457)
					(end 425.241466 -223.922336)
				)
				(arc
					(start 426.641006 -223.922336)
					(mid 426.676927 -223.907457)
					(end 426.691806 -223.871536)
				)
				(arc
					(start 426.691806 -223.462596)
					(mid 426.676927 -223.426675)
					(end 426.641006 -223.411796)
				)
				(arc
					(start 425.241466 -223.411796)
					(mid 425.205545 -223.426675)
					(end 425.190666 -223.462596)
				)
			)
		)
	)
	(zone
		(layers "In1.Cu" "In2.Cu")
		(hatch none 0.5)
		(connect_pads
			(clearance 0)
		)
		(min_thickness 0.25)
		(keepout
			(tracks not_allowed)
			(vias allowed)
			(pads allowed)
			(copperpour not_allowed)
			(footprints allowed)
		)
		(placement
			(enabled no)
			(sheetname "")
		)
		(fill yes
			(thermal_gap 0.5)
			(thermal_bridge_width 0.5)
			(island_removal_mode 0)
		)
		(polygon
			(pts
				(arc
					(start 203.32573 -247.671336)
					(mid 203.340609 -247.707257)
					(end 203.37653 -247.722136)
				)
				(arc
					(start 204.77607 -247.722136)
					(mid 204.811991 -247.707257)
					(end 204.82687 -247.671336)
				)
				(arc
					(start 204.82687 -247.262396)
					(mid 204.811991 -247.226475)
					(end 204.77607 -247.211596)
				)
				(arc
					(start 203.37653 -247.211596)
					(mid 203.340609 -247.226475)
					(end 203.32573 -247.262396)
				)
			)
		)
	)
	(zone
		(layers "In1.Cu" "In2.Cu")
		(hatch none 0.5)
		(connect_pads
			(clearance 0)
		)
		(min_thickness 0.25)
		(keepout
			(tracks not_allowed)
			(vias allowed)
			(pads allowed)
			(copperpour not_allowed)
			(footprints allowed)
		)
		(placement
			(enabled no)
			(sheetname "")
		)
		(fill yes
			(thermal_gap 0.5)
			(thermal_bridge_width 0.5)
			(island_removal_mode 0)
		)
		(polygon
			(pts
				(arc
					(start 462.909666 -313.971432)
					(mid 462.924545 -314.007353)
					(end 462.960466 -314.022232)
				)
				(arc
					(start 464.360006 -314.022232)
					(mid 464.395927 -314.007353)
					(end 464.410806 -313.971432)
				)
				(arc
					(start 464.410806 -313.562492)
					(mid 464.395927 -313.526571)
					(end 464.360006 -313.511692)
				)
				(arc
					(start 462.960466 -313.511692)
					(mid 462.924545 -313.526571)
					(end 462.909666 -313.562492)
				)
			)
		)
	)
	(zone
		(layers "In1.Cu" "In2.Cu")
		(hatch none 0.5)
		(connect_pads
			(clearance 0)
		)
		(min_thickness 0.25)
		(keepout
			(tracks not_allowed)
			(vias allowed)
			(pads allowed)
			(copperpour not_allowed)
			(footprints allowed)
		)
		(placement
			(enabled no)
			(sheetname "")
		)
		(fill yes
			(thermal_gap 0.5)
			(thermal_bridge_width 0.5)
			(island_removal_mode 0)
		)
		(polygon
			(pts
				(arc
					(start 262.873998 -215.371426)
					(mid 262.888877 -215.407347)
					(end 262.924798 -215.422226)
				)
				(arc
					(start 264.324338 -215.422226)
					(mid 264.360259 -215.407347)
					(end 264.375138 -215.371426)
				)
				(arc
					(start 264.375138 -214.962486)
					(mid 264.360259 -214.926565)
					(end 264.324338 -214.911686)
				)
				(arc
					(start 262.924798 -214.911686)
					(mid 262.888877 -214.926565)
					(end 262.873998 -214.962486)
				)
			)
		)
	)
	(zone
		(layers "In1.Cu" "In2.Cu")
		(hatch none 0.5)
		(connect_pads
			(clearance 0)
		)
		(min_thickness 0.25)
		(keepout
			(tracks not_allowed)
			(vias allowed)
			(pads allowed)
			(copperpour not_allowed)
			(footprints allowed)
		)
		(placement
			(enabled no)
			(sheetname "")
		)
		(fill yes
			(thermal_gap 0.5)
			(thermal_bridge_width 0.5)
			(island_removal_mode 0)
		)
		(polygon
			(pts
				(arc
					(start 169.706798 -205.171548)
					(mid 169.721677 -205.207469)
					(end 169.757598 -205.222348)
				)
				(arc
					(start 171.157138 -205.222348)
					(mid 171.193059 -205.207469)
					(end 171.207938 -205.171548)
				)
				(arc
					(start 171.207938 -204.762608)
					(mid 171.193059 -204.726687)
					(end 171.157138 -204.711808)
				)
				(arc
					(start 169.757598 -204.711808)
					(mid 169.721677 -204.726687)
					(end 169.706798 -204.762608)
				)
			)
		)
	)
	(zone
		(layers "In1.Cu" "In2.Cu")
		(hatch none 0.5)
		(connect_pads
			(clearance 0)
		)
		(min_thickness 0.25)
		(keepout
			(tracks not_allowed)
			(vias allowed)
			(pads allowed)
			(copperpour not_allowed)
			(footprints allowed)
		)
		(placement
			(enabled no)
			(sheetname "")
		)
		(fill yes
			(thermal_gap 0.5)
			(thermal_bridge_width 0.5)
			(island_removal_mode 0)
		)
		(polygon
			(pts
				(arc
					(start 262.873998 -303.7713)
					(mid 262.888877 -303.807221)
					(end 262.924798 -303.8221)
				)
				(arc
					(start 264.324338 -303.8221)
					(mid 264.360259 -303.807221)
					(end 264.375138 -303.7713)
				)
				(arc
					(start 264.375138 -303.36236)
					(mid 264.360259 -303.326439)
					(end 264.324338 -303.31156)
				)
				(arc
					(start 262.924798 -303.31156)
					(mid 262.888877 -303.326439)
					(end 262.873998 -303.36236)
				)
			)
		)
	)
	(zone
		(layers "In1.Cu" "In2.Cu")
		(hatch none 0.5)
		(connect_pads
			(clearance 0)
		)
		(min_thickness 0.25)
		(keepout
			(tracks not_allowed)
			(vias allowed)
			(pads allowed)
			(copperpour not_allowed)
			(footprints allowed)
		)
		(placement
			(enabled no)
			(sheetname "")
		)
		(fill yes
			(thermal_gap 0.5)
			(thermal_bridge_width 0.5)
			(island_removal_mode 0)
		)
		(polygon
			(pts
				(arc
					(start 262.873998 -209.421476)
					(mid 262.888877 -209.457397)
					(end 262.924798 -209.472276)
				)
				(arc
					(start 264.324338 -209.472276)
					(mid 264.360259 -209.457397)
					(end 264.375138 -209.421476)
				)
				(arc
					(start 264.375138 -209.012536)
					(mid 264.360259 -208.976615)
					(end 264.324338 -208.961736)
				)
				(arc
					(start 262.924798 -208.961736)
					(mid 262.888877 -208.976615)
					(end 262.873998 -209.012536)
				)
			)
		)
	)
	(zone
		(layers "In1.Cu" "In2.Cu")
		(hatch none 0.5)
		(connect_pads
			(clearance 0)
		)
		(min_thickness 0.25)
		(keepout
			(tracks not_allowed)
			(vias allowed)
			(pads allowed)
			(copperpour not_allowed)
			(footprints allowed)
		)
		(placement
			(enabled no)
			(sheetname "")
		)
		(fill yes
			(thermal_gap 0.5)
			(thermal_bridge_width 0.5)
			(island_removal_mode 0)
		)
		(polygon
			(pts
				(arc
					(start 11.490198 -279.9715)
					(mid 11.505077 -280.007421)
					(end 11.540998 -280.0223)
				)
				(arc
					(start 12.940538 -280.0223)
					(mid 12.976459 -280.007421)
					(end 12.991338 -279.9715)
				)
				(arc
					(start 12.991338 -279.56256)
					(mid 12.976459 -279.526639)
					(end 12.940538 -279.51176)
				)
				(arc
					(start 11.540998 -279.51176)
					(mid 11.505077 -279.526639)
					(end 11.490198 -279.56256)
				)
			)
		)
	)
	(zone
		(layers "In1.Cu" "In2.Cu")
		(hatch none 0.5)
		(connect_pads
			(clearance 0)
		)
		(min_thickness 0.25)
		(keepout
			(tracks not_allowed)
			(vias allowed)
			(pads allowed)
			(copperpour not_allowed)
			(footprints allowed)
		)
		(placement
			(enabled no)
			(sheetname "")
		)
		(fill yes
			(thermal_gap 0.5)
			(thermal_bridge_width 0.5)
			(island_removal_mode 0)
		)
		(polygon
			(pts
				(arc
					(start 266.974066 -205.171548)
					(mid 266.988945 -205.207469)
					(end 267.024866 -205.222348)
				)
				(arc
					(start 268.424406 -205.222348)
					(mid 268.460327 -205.207469)
					(end 268.475206 -205.171548)
				)
				(arc
					(start 268.475206 -204.762608)
					(mid 268.460327 -204.726687)
					(end 268.424406 -204.711808)
				)
				(arc
					(start 267.024866 -204.711808)
					(mid 266.988945 -204.726687)
					(end 266.974066 -204.762608)
				)
			)
		)
	)
	(zone
		(layers "In1.Cu" "In2.Cu")
		(hatch none 0.5)
		(connect_pads
			(clearance 0)
		)
		(min_thickness 0.25)
		(keepout
			(tracks not_allowed)
			(vias allowed)
			(pads allowed)
			(copperpour not_allowed)
			(footprints allowed)
		)
		(placement
			(enabled no)
			(sheetname "")
		)
		(fill yes
			(thermal_gap 0.5)
			(thermal_bridge_width 0.5)
			(island_removal_mode 0)
		)
		(polygon
			(pts
				(arc
					(start 282.061666 -270.621506)
					(mid 282.076545 -270.657427)
					(end 282.112466 -270.672306)
				)
				(arc
					(start 283.512006 -270.672306)
					(mid 283.547927 -270.657427)
					(end 283.562806 -270.621506)
				)
				(arc
					(start 283.562806 -270.212566)
					(mid 283.547927 -270.176645)
					(end 283.512006 -270.161766)
				)
				(arc
					(start 282.112466 -270.161766)
					(mid 282.076545 -270.176645)
					(end 282.061666 -270.212566)
				)
			)
		)
	)
	(zone
		(layers "In1.Cu" "In2.Cu")
		(hatch none 0.5)
		(connect_pads
			(clearance 0)
		)
		(min_thickness 0.25)
		(keepout
			(tracks not_allowed)
			(vias allowed)
			(pads allowed)
			(copperpour not_allowed)
			(footprints allowed)
		)
		(placement
			(enabled no)
			(sheetname "")
		)
		(fill yes
			(thermal_gap 0.5)
			(thermal_bridge_width 0.5)
			(island_removal_mode 0)
		)
		(polygon
			(pts
				(arc
					(start 443.721998 -228.121464)
					(mid 443.736877 -228.157385)
					(end 443.772798 -228.172264)
				)
				(arc
					(start 445.172338 -228.172264)
					(mid 445.208259 -228.157385)
					(end 445.223138 -228.121464)
				)
				(arc
					(start 445.223138 -227.712524)
					(mid 445.208259 -227.676603)
					(end 445.172338 -227.661724)
				)
				(arc
					(start 443.772798 -227.661724)
					(mid 443.736877 -227.676603)
					(end 443.721998 -227.712524)
				)
			)
		)
	)
	(zone
		(layers "In1.Cu" "In2.Cu")
		(hatch none 0.5)
		(connect_pads
			(clearance 0)
		)
		(min_thickness 0.25)
		(keepout
			(tracks not_allowed)
			(vias allowed)
			(pads allowed)
			(copperpour not_allowed)
			(footprints allowed)
		)
		(placement
			(enabled no)
			(sheetname "")
		)
		(fill yes
			(thermal_gap 0.5)
			(thermal_bridge_width 0.5)
			(island_removal_mode 0)
		)
		(polygon
			(pts
				(arc
					(start 277.961598 -221.321376)
					(mid 277.976477 -221.357297)
					(end 278.012398 -221.372176)
				)
				(arc
					(start 279.411938 -221.372176)
					(mid 279.447859 -221.357297)
					(end 279.462738 -221.321376)
				)
				(arc
					(start 279.462738 -220.912436)
					(mid 279.447859 -220.876515)
					(end 279.411938 -220.861636)
				)
				(arc
					(start 278.012398 -220.861636)
					(mid 277.976477 -220.876515)
					(end 277.961598 -220.912436)
				)
			)
		)
	)
	(zone
		(layers "In1.Cu" "In2.Cu")
		(hatch none 0.5)
		(connect_pads
			(clearance 0)
		)
		(min_thickness 0.25)
		(keepout
			(tracks not_allowed)
			(vias allowed)
			(pads allowed)
			(copperpour not_allowed)
			(footprints allowed)
		)
		(placement
			(enabled no)
			(sheetname "")
		)
		(fill yes
			(thermal_gap 0.5)
			(thermal_bridge_width 0.5)
			(island_removal_mode 0)
		)
		(polygon
			(pts
				(arc
					(start 34.121598 -222.171514)
					(mid 34.136477 -222.207435)
					(end 34.172398 -222.222314)
				)
				(arc
					(start 35.571938 -222.222314)
					(mid 35.607859 -222.207435)
					(end 35.622738 -222.171514)
				)
				(arc
					(start 35.622738 -221.762574)
					(mid 35.607859 -221.726653)
					(end 35.571938 -221.711774)
				)
				(arc
					(start 34.172398 -221.711774)
					(mid 34.136477 -221.726653)
					(end 34.121598 -221.762574)
				)
			)
		)
	)
	(zone
		(layers "In1.Cu" "In2.Cu")
		(hatch none 0.5)
		(connect_pads
			(clearance 0)
		)
		(min_thickness 0.25)
		(keepout
			(tracks not_allowed)
			(vias allowed)
			(pads allowed)
			(copperpour not_allowed)
			(footprints allowed)
		)
		(placement
			(enabled no)
			(sheetname "")
		)
		(fill yes
			(thermal_gap 0.5)
			(thermal_bridge_width 0.5)
			(island_removal_mode 0)
		)
		(polygon
			(pts
				(arc
					(start 214.969598 -216.22131)
					(mid 214.984477 -216.257231)
					(end 215.020398 -216.27211)
				)
				(arc
					(start 216.419938 -216.27211)
					(mid 216.455859 -216.257231)
					(end 216.470738 -216.22131)
				)
				(arc
					(start 216.470738 -215.81237)
					(mid 216.455859 -215.776449)
					(end 216.419938 -215.76157)
				)
				(arc
					(start 215.020398 -215.76157)
					(mid 214.984477 -215.776449)
					(end 214.969598 -215.81237)
				)
			)
		)
	)
	(zone
		(layers "In1.Cu" "In2.Cu")
		(hatch none 0.5)
		(connect_pads
			(clearance 0)
		)
		(min_thickness 0.25)
		(keepout
			(tracks not_allowed)
			(vias allowed)
			(pads allowed)
			(copperpour not_allowed)
			(footprints allowed)
		)
		(placement
			(enabled no)
			(sheetname "")
		)
		(fill yes
			(thermal_gap 0.5)
			(thermal_bridge_width 0.5)
			(island_removal_mode 0)
		)
		(polygon
			(pts
				(arc
					(start 282.061666 -200.071482)
					(mid 282.076545 -200.107403)
					(end 282.112466 -200.122282)
				)
				(arc
					(start 283.512006 -200.122282)
					(mid 283.547927 -200.107403)
					(end 283.562806 -200.071482)
				)
				(arc
					(start 283.562806 -199.662542)
					(mid 283.547927 -199.626621)
					(end 283.512006 -199.611742)
				)
				(arc
					(start 282.112466 -199.611742)
					(mid 282.076545 -199.626621)
					(end 282.061666 -199.662542)
				)
			)
		)
	)
	(zone
		(layers "In1.Cu" "In2.Cu")
		(hatch none 0.5)
		(connect_pads
			(clearance 0)
		)
		(min_thickness 0.25)
		(keepout
			(tracks not_allowed)
			(vias allowed)
			(pads allowed)
			(copperpour not_allowed)
			(footprints allowed)
		)
		(placement
			(enabled no)
			(sheetname "")
		)
		(fill yes
			(thermal_gap 0.5)
			(thermal_bridge_width 0.5)
			(island_removal_mode 0)
		)
		(polygon
			(pts
				(arc
					(start 11.490198 -206.871316)
					(mid 11.505077 -206.907237)
					(end 11.540998 -206.922116)
				)
				(arc
					(start 12.940538 -206.922116)
					(mid 12.976459 -206.907237)
					(end 12.991338 -206.871316)
				)
				(arc
					(start 12.991338 -206.462376)
					(mid 12.976459 -206.426455)
					(end 12.940538 -206.411576)
				)
				(arc
					(start 11.540998 -206.411576)
					(mid 11.505077 -206.426455)
					(end 11.490198 -206.462376)
				)
			)
		)
	)
	(zone
		(layers "In1.Cu" "In2.Cu")
		(hatch none 0.5)
		(connect_pads
			(clearance 0)
		)
		(min_thickness 0.25)
		(keepout
			(tracks not_allowed)
			(vias allowed)
			(pads allowed)
			(copperpour not_allowed)
			(footprints allowed)
		)
		(placement
			(enabled no)
			(sheetname "")
		)
		(fill yes
			(thermal_gap 0.5)
			(thermal_bridge_width 0.5)
			(island_removal_mode 0)
		)
		(polygon
			(pts
				(arc
					(start 177.250598 -208.571338)
					(mid 177.265477 -208.607259)
					(end 177.301398 -208.622138)
				)
				(arc
					(start 178.700938 -208.622138)
					(mid 178.736859 -208.607259)
					(end 178.751738 -208.571338)
				)
				(arc
					(start 178.751738 -208.162398)
					(mid 178.736859 -208.126477)
					(end 178.700938 -208.111598)
				)
				(arc
					(start 177.301398 -208.111598)
					(mid 177.265477 -208.126477)
					(end 177.250598 -208.162398)
				)
			)
		)
	)
	(zone
		(layers "In1.Cu" "In2.Cu")
		(hatch none 0.5)
		(connect_pads
			(clearance 0)
		)
		(min_thickness 0.25)
		(keepout
			(tracks not_allowed)
			(vias allowed)
			(pads allowed)
			(copperpour not_allowed)
			(footprints allowed)
		)
		(placement
			(enabled no)
			(sheetname "")
		)
		(fill yes
			(thermal_gap 0.5)
			(thermal_bridge_width 0.5)
			(island_removal_mode 0)
		)
		(polygon
			(pts
				(arc
					(start 158.06293 -196.671438)
					(mid 158.077809 -196.707359)
					(end 158.11373 -196.722238)
				)
				(arc
					(start 159.51327 -196.722238)
					(mid 159.549191 -196.707359)
					(end 159.56407 -196.671438)
				)
				(arc
					(start 159.56407 -196.262498)
					(mid 159.549191 -196.226577)
					(end 159.51327 -196.211698)
				)
				(arc
					(start 158.11373 -196.211698)
					(mid 158.077809 -196.226577)
					(end 158.06293 -196.262498)
				)
			)
		)
	)
	(zone
		(layers "In1.Cu" "In2.Cu")
		(hatch none 0.5)
		(connect_pads
			(clearance 0)
		)
		(min_thickness 0.25)
		(keepout
			(tracks not_allowed)
			(vias allowed)
			(pads allowed)
			(copperpour not_allowed)
			(footprints allowed)
		)
		(placement
			(enabled no)
			(sheetname "")
		)
		(fill yes
			(thermal_gap 0.5)
			(thermal_bridge_width 0.5)
			(island_removal_mode 0)
		)
		(polygon
			(pts
				(arc
					(start 165.60673 -209.421476)
					(mid 165.621609 -209.457397)
					(end 165.65753 -209.472276)
				)
				(arc
					(start 167.05707 -209.472276)
					(mid 167.092991 -209.457397)
					(end 167.10787 -209.421476)
				)
				(arc
					(start 167.10787 -209.012536)
					(mid 167.092991 -208.976615)
					(end 167.05707 -208.961736)
				)
				(arc
					(start 165.65753 -208.961736)
					(mid 165.621609 -208.976615)
					(end 165.60673 -209.012536)
				)
			)
		)
	)
	(zone
		(layers "In1.Cu" "In2.Cu")
		(hatch none 0.5)
		(connect_pads
			(clearance 0)
		)
		(min_thickness 0.25)
		(keepout
			(tracks not_allowed)
			(vias allowed)
			(pads allowed)
			(copperpour not_allowed)
			(footprints allowed)
		)
		(placement
			(enabled no)
			(sheetname "")
		)
		(fill yes
			(thermal_gap 0.5)
			(thermal_bridge_width 0.5)
			(island_removal_mode 0)
		)
		(polygon
			(pts
				(arc
					(start 210.86953 -303.7713)
					(mid 210.884409 -303.807221)
					(end 210.92033 -303.8221)
				)
				(arc
					(start 212.31987 -303.8221)
					(mid 212.355791 -303.807221)
					(end 212.37067 -303.7713)
				)
				(arc
					(start 212.37067 -303.36236)
					(mid 212.355791 -303.326439)
					(end 212.31987 -303.31156)
				)
				(arc
					(start 210.92033 -303.31156)
					(mid 210.884409 -303.326439)
					(end 210.86953 -303.36236)
				)
			)
		)
	)
	(zone
		(layers "In1.Cu" "In2.Cu")
		(hatch none 0.5)
		(connect_pads
			(clearance 0)
		)
		(min_thickness 0.25)
		(keepout
			(tracks not_allowed)
			(vias allowed)
			(pads allowed)
			(copperpour not_allowed)
			(footprints allowed)
		)
		(placement
			(enabled no)
			(sheetname "")
		)
		(fill yes
			(thermal_gap 0.5)
			(thermal_bridge_width 0.5)
			(island_removal_mode 0)
		)
		(polygon
			(pts
				(arc
					(start 45.10913 -284.221428)
					(mid 45.124009 -284.257349)
					(end 45.15993 -284.272228)
				)
				(arc
					(start 46.55947 -284.272228)
					(mid 46.595391 -284.257349)
					(end 46.61027 -284.221428)
				)
				(arc
					(start 46.61027 -283.812488)
					(mid 46.595391 -283.776567)
					(end 46.55947 -283.761688)
				)
				(arc
					(start 45.15993 -283.761688)
					(mid 45.124009 -283.776567)
					(end 45.10913 -283.812488)
				)
			)
		)
	)
	(zone
		(layers "In1.Cu" "In2.Cu")
		(hatch none 0.5)
		(connect_pads
			(clearance 0)
		)
		(min_thickness 0.25)
		(keepout
			(tracks not_allowed)
			(vias allowed)
			(pads allowed)
			(copperpour not_allowed)
			(footprints allowed)
		)
		(placement
			(enabled no)
			(sheetname "")
		)
		(fill yes
			(thermal_gap 0.5)
			(thermal_bridge_width 0.5)
			(island_removal_mode 0)
		)
		(polygon
			(pts
				(arc
					(start 293.049198 -238.321342)
					(mid 293.064077 -238.357263)
					(end 293.099998 -238.372142)
				)
				(arc
					(start 294.499538 -238.372142)
					(mid 294.535459 -238.357263)
					(end 294.550338 -238.321342)
				)
				(arc
					(start 294.550338 -237.912402)
					(mid 294.535459 -237.876481)
					(end 294.499538 -237.861602)
				)
				(arc
					(start 293.099998 -237.861602)
					(mid 293.064077 -237.876481)
					(end 293.049198 -237.912402)
				)
			)
		)
	)
	(zone
		(layers "In1.Cu" "In2.Cu")
		(hatch none 0.5)
		(connect_pads
			(clearance 0)
		)
		(min_thickness 0.25)
		(keepout
			(tracks not_allowed)
			(vias allowed)
			(pads allowed)
			(copperpour not_allowed)
			(footprints allowed)
		)
		(placement
			(enabled no)
			(sheetname "")
		)
		(fill yes
			(thermal_gap 0.5)
			(thermal_bridge_width 0.5)
			(island_removal_mode 0)
		)
		(polygon
			(pts
				(arc
					(start 214.969598 -272.321528)
					(mid 214.984477 -272.357449)
					(end 215.020398 -272.372328)
				)
				(arc
					(start 216.419938 -272.372328)
					(mid 216.455859 -272.357449)
					(end 216.470738 -272.321528)
				)
				(arc
					(start 216.470738 -271.912588)
					(mid 216.455859 -271.876667)
					(end 216.419938 -271.861788)
				)
				(arc
					(start 215.020398 -271.861788)
					(mid 214.984477 -271.876667)
					(end 214.969598 -271.912588)
				)
			)
		)
	)
	(zone
		(layers "In1.Cu" "In2.Cu")
		(hatch none 0.5)
		(connect_pads
			(clearance 0)
		)
		(min_thickness 0.25)
		(keepout
			(tracks not_allowed)
			(vias allowed)
			(pads allowed)
			(copperpour not_allowed)
			(footprints allowed)
		)
		(placement
			(enabled no)
			(sheetname "")
		)
		(fill yes
			(thermal_gap 0.5)
			(thermal_bridge_width 0.5)
			(island_removal_mode 0)
		)
		(polygon
			(pts
				(arc
					(start 30.02153 -226.421442)
					(mid 30.036409 -226.457363)
					(end 30.07233 -226.472242)
				)
				(arc
					(start 31.47187 -226.472242)
					(mid 31.507791 -226.457363)
					(end 31.52267 -226.421442)
				)
				(arc
					(start 31.52267 -226.012502)
					(mid 31.507791 -225.976581)
					(end 31.47187 -225.961702)
				)
				(arc
					(start 30.07233 -225.961702)
					(mid 30.036409 -225.976581)
					(end 30.02153 -226.012502)
				)
			)
		)
	)
	(zone
		(layers "In1.Cu" "In2.Cu")
		(hatch none 0.5)
		(connect_pads
			(clearance 0)
		)
		(min_thickness 0.25)
		(keepout
			(tracks not_allowed)
			(vias allowed)
			(pads allowed)
			(copperpour not_allowed)
			(footprints allowed)
		)
		(placement
			(enabled no)
			(sheetname "")
		)
		(fill yes
			(thermal_gap 0.5)
			(thermal_bridge_width 0.5)
			(island_removal_mode 0)
		)
		(polygon
			(pts
				(arc
					(start 203.32573 -218.77147)
					(mid 203.340609 -218.807391)
					(end 203.37653 -218.82227)
				)
				(arc
					(start 204.77607 -218.82227)
					(mid 204.811991 -218.807391)
					(end 204.82687 -218.77147)
				)
				(arc
					(start 204.82687 -218.36253)
					(mid 204.811991 -218.326609)
					(end 204.77607 -218.31173)
				)
				(arc
					(start 203.37653 -218.31173)
					(mid 203.340609 -218.326609)
					(end 203.32573 -218.36253)
				)
			)
		)
	)
	(zone
		(layers "In1.Cu" "In2.Cu")
		(hatch none 0.5)
		(connect_pads
			(clearance 0)
		)
		(min_thickness 0.25)
		(keepout
			(tracks not_allowed)
			(vias allowed)
			(pads allowed)
			(copperpour not_allowed)
			(footprints allowed)
		)
		(placement
			(enabled no)
			(sheetname "")
		)
		(fill yes
			(thermal_gap 0.5)
			(thermal_bridge_width 0.5)
			(island_removal_mode 0)
		)
		(polygon
			(pts
				(arc
					(start 406.002998 -213.671404)
					(mid 406.017877 -213.707325)
					(end 406.053798 -213.722204)
				)
				(arc
					(start 407.453338 -213.722204)
					(mid 407.489259 -213.707325)
					(end 407.504138 -213.671404)
				)
				(arc
					(start 407.504138 -213.262464)
					(mid 407.489259 -213.226543)
					(end 407.453338 -213.211664)
				)
				(arc
					(start 406.053798 -213.211664)
					(mid 406.017877 -213.226543)
					(end 406.002998 -213.262464)
				)
			)
		)
	)
	(zone
		(layers "In1.Cu" "In2.Cu")
		(hatch none 0.5)
		(connect_pads
			(clearance 0)
		)
		(min_thickness 0.25)
		(keepout
			(tracks not_allowed)
			(vias allowed)
			(pads allowed)
			(copperpour not_allowed)
			(footprints allowed)
		)
		(placement
			(enabled no)
			(sheetname "")
		)
		(fill yes
			(thermal_gap 0.5)
			(thermal_bridge_width 0.5)
			(island_removal_mode 0)
		)
		(polygon
			(pts
				(arc
					(start 7.39013 -264.671302)
					(mid 7.405009 -264.707223)
					(end 7.44093 -264.722102)
				)
				(arc
					(start 8.84047 -264.722102)
					(mid 8.876391 -264.707223)
					(end 8.89127 -264.671302)
				)
				(arc
					(start 8.89127 -264.262362)
					(mid 8.876391 -264.226441)
					(end 8.84047 -264.211562)
				)
				(arc
					(start 7.44093 -264.211562)
					(mid 7.405009 -264.226441)
					(end 7.39013 -264.262362)
				)
			)
		)
	)
	(zone
		(layers "In1.Cu" "In2.Cu")
		(hatch none 0.5)
		(connect_pads
			(clearance 0)
		)
		(min_thickness 0.25)
		(keepout
			(tracks not_allowed)
			(vias allowed)
			(pads allowed)
			(copperpour not_allowed)
			(footprints allowed)
		)
		(placement
			(enabled no)
			(sheetname "")
		)
		(fill yes
			(thermal_gap 0.5)
			(thermal_bridge_width 0.5)
			(island_removal_mode 0)
		)
		(polygon
			(pts
				(arc
					(start 289.605466 -293.571422)
					(mid 289.620345 -293.607343)
					(end 289.656266 -293.622222)
				)
				(arc
					(start 291.055806 -293.622222)
					(mid 291.091727 -293.607343)
					(end 291.106606 -293.571422)
				)
				(arc
					(start 291.106606 -293.162482)
					(mid 291.091727 -293.126561)
					(end 291.055806 -293.111682)
				)
				(arc
					(start 289.656266 -293.111682)
					(mid 289.620345 -293.126561)
					(end 289.605466 -293.162482)
				)
			)
		)
	)
	(zone
		(layers "In1.Cu" "In2.Cu")
		(hatch none 0.5)
		(connect_pads
			(clearance 0)
		)
		(min_thickness 0.25)
		(keepout
			(tracks not_allowed)
			(vias allowed)
			(pads allowed)
			(copperpour not_allowed)
			(footprints allowed)
		)
		(placement
			(enabled no)
			(sheetname "")
		)
		(fill yes
			(thermal_gap 0.5)
			(thermal_bridge_width 0.5)
			(island_removal_mode 0)
		)
		(polygon
			(pts
				(arc
					(start 447.822066 -209.421476)
					(mid 447.836945 -209.457397)
					(end 447.872866 -209.472276)
				)
				(arc
					(start 449.272406 -209.472276)
					(mid 449.308327 -209.457397)
					(end 449.323206 -209.421476)
				)
				(arc
					(start 449.323206 -209.012536)
					(mid 449.308327 -208.976615)
					(end 449.272406 -208.961736)
				)
				(arc
					(start 447.872866 -208.961736)
					(mid 447.836945 -208.976615)
					(end 447.822066 -209.012536)
				)
			)
		)
	)
	(zone
		(layers "In1.Cu" "In2.Cu")
		(hatch none 0.5)
		(connect_pads
			(clearance 0)
		)
		(min_thickness 0.25)
		(keepout
			(tracks not_allowed)
			(vias allowed)
			(pads allowed)
			(copperpour not_allowed)
			(footprints allowed)
		)
		(placement
			(enabled no)
			(sheetname "")
		)
		(fill yes
			(thermal_gap 0.5)
			(thermal_bridge_width 0.5)
			(island_removal_mode 0)
		)
		(polygon
			(pts
				(arc
					(start 436.178198 -305.471322)
					(mid 436.193077 -305.507243)
					(end 436.228998 -305.522122)
				)
				(arc
					(start 437.628538 -305.522122)
					(mid 437.664459 -305.507243)
					(end 437.679338 -305.471322)
				)
				(arc
					(start 437.679338 -305.062382)
					(mid 437.664459 -305.026461)
					(end 437.628538 -305.011582)
				)
				(arc
					(start 436.228998 -305.011582)
					(mid 436.193077 -305.026461)
					(end 436.178198 -305.062382)
				)
			)
		)
	)
	(zone
		(layers "In1.Cu" "In2.Cu")
		(hatch none 0.5)
		(connect_pads
			(clearance 0)
		)
		(min_thickness 0.25)
		(keepout
			(tracks not_allowed)
			(vias allowed)
			(pads allowed)
			(copperpour not_allowed)
			(footprints allowed)
		)
		(placement
			(enabled no)
			(sheetname "")
		)
		(fill yes
			(thermal_gap 0.5)
			(thermal_bridge_width 0.5)
			(island_removal_mode 0)
		)
		(polygon
			(pts
				(arc
					(start 173.15053 -224.72142)
					(mid 173.165409 -224.757341)
					(end 173.20133 -224.77222)
				)
				(arc
					(start 174.60087 -224.77222)
					(mid 174.636791 -224.757341)
					(end 174.65167 -224.72142)
				)
				(arc
					(start 174.65167 -224.31248)
					(mid 174.636791 -224.276559)
					(end 174.60087 -224.26168)
				)
				(arc
					(start 173.20133 -224.26168)
					(mid 173.165409 -224.276559)
					(end 173.15053 -224.31248)
				)
			)
		)
	)
	(zone
		(layers "In1.Cu" "In2.Cu")
		(hatch none 0.5)
		(connect_pads
			(clearance 0)
		)
		(min_thickness 0.25)
		(keepout
			(tracks not_allowed)
			(vias allowed)
			(pads allowed)
			(copperpour not_allowed)
			(footprints allowed)
		)
		(placement
			(enabled no)
			(sheetname "")
		)
		(fill yes
			(thermal_gap 0.5)
			(thermal_bridge_width 0.5)
			(island_removal_mode 0)
		)
		(polygon
			(pts
				(arc
					(start 266.974066 -240.871502)
					(mid 266.988945 -240.907423)
					(end 267.024866 -240.922302)
				)
				(arc
					(start 268.424406 -240.922302)
					(mid 268.460327 -240.907423)
					(end 268.475206 -240.871502)
				)
				(arc
					(start 268.475206 -240.462562)
					(mid 268.460327 -240.426641)
					(end 268.424406 -240.411762)
				)
				(arc
					(start 267.024866 -240.411762)
					(mid 266.988945 -240.426641)
					(end 266.974066 -240.462562)
				)
			)
		)
	)
	(zone
		(layers "In1.Cu" "In2.Cu")
		(hatch none 0.5)
		(connect_pads
			(clearance 0)
		)
		(min_thickness 0.25)
		(keepout
			(tracks not_allowed)
			(vias allowed)
			(pads allowed)
			(copperpour not_allowed)
			(footprints allowed)
		)
		(placement
			(enabled no)
			(sheetname "")
		)
		(fill yes
			(thermal_gap 0.5)
			(thermal_bridge_width 0.5)
			(island_removal_mode 0)
		)
		(polygon
			(pts
				(arc
					(start 458.809598 -271.47139)
					(mid 458.824477 -271.507311)
					(end 458.860398 -271.52219)
				)
				(arc
					(start 460.259938 -271.52219)
					(mid 460.295859 -271.507311)
					(end 460.310738 -271.47139)
				)
				(arc
					(start 460.310738 -271.06245)
					(mid 460.295859 -271.026529)
					(end 460.259938 -271.01165)
				)
				(arc
					(start 458.860398 -271.01165)
					(mid 458.824477 -271.026529)
					(end 458.809598 -271.06245)
				)
			)
		)
	)
	(zone
		(layers "In1.Cu" "In2.Cu")
		(hatch none 0.5)
		(connect_pads
			(clearance 0)
		)
		(min_thickness 0.25)
		(keepout
			(tracks not_allowed)
			(vias allowed)
			(pads allowed)
			(copperpour not_allowed)
			(footprints allowed)
		)
		(placement
			(enabled no)
			(sheetname "")
		)
		(fill yes
			(thermal_gap 0.5)
			(thermal_bridge_width 0.5)
			(island_removal_mode 0)
		)
		(polygon
			(pts
				(arc
					(start 192.338198 -302.921416)
					(mid 192.353077 -302.957337)
					(end 192.388998 -302.972216)
				)
				(arc
					(start 193.788538 -302.972216)
					(mid 193.824459 -302.957337)
					(end 193.839338 -302.921416)
				)
				(arc
					(start 193.839338 -302.512476)
					(mid 193.824459 -302.476555)
					(end 193.788538 -302.461676)
				)
				(arc
					(start 192.388998 -302.461676)
					(mid 192.353077 -302.476555)
					(end 192.338198 -302.512476)
				)
			)
		)
	)
	(zone
		(layers "In1.Cu" "In2.Cu")
		(hatch none 0.5)
		(connect_pads
			(clearance 0)
		)
		(min_thickness 0.25)
		(keepout
			(tracks not_allowed)
			(vias allowed)
			(pads allowed)
			(copperpour not_allowed)
			(footprints allowed)
		)
		(placement
			(enabled no)
			(sheetname "")
		)
		(fill yes
			(thermal_gap 0.5)
			(thermal_bridge_width 0.5)
			(island_removal_mode 0)
		)
		(polygon
			(pts
				(arc
					(start 451.265798 -211.971382)
					(mid 451.280677 -212.007303)
					(end 451.316598 -212.022182)
				)
				(arc
					(start 452.716138 -212.022182)
					(mid 452.752059 -212.007303)
					(end 452.766938 -211.971382)
				)
				(arc
					(start 452.766938 -211.562442)
					(mid 452.752059 -211.526521)
					(end 452.716138 -211.511642)
				)
				(arc
					(start 451.316598 -211.511642)
					(mid 451.280677 -211.526521)
					(end 451.265798 -211.562442)
				)
			)
		)
	)
	(zone
		(layers "In1.Cu" "In2.Cu")
		(hatch none 0.5)
		(connect_pads
			(clearance 0)
		)
		(min_thickness 0.25)
		(keepout
			(tracks not_allowed)
			(vias allowed)
			(pads allowed)
			(copperpour not_allowed)
			(footprints allowed)
		)
		(placement
			(enabled no)
			(sheetname "")
		)
		(fill yes
			(thermal_gap 0.5)
			(thermal_bridge_width 0.5)
			(island_removal_mode 0)
		)
		(polygon
			(pts
				(arc
					(start 37.56533 -296.121328)
					(mid 37.580209 -296.157249)
					(end 37.61613 -296.172128)
				)
				(arc
					(start 39.01567 -296.172128)
					(mid 39.051591 -296.157249)
					(end 39.06647 -296.121328)
				)
				(arc
					(start 39.06647 -295.712388)
					(mid 39.051591 -295.676467)
					(end 39.01567 -295.661588)
				)
				(arc
					(start 37.61613 -295.661588)
					(mid 37.580209 -295.676467)
					(end 37.56533 -295.712388)
				)
			)
		)
	)
	(zone
		(layers "In1.Cu" "In2.Cu")
		(hatch none 0.5)
		(connect_pads
			(clearance 0)
		)
		(min_thickness 0.25)
		(keepout
			(tracks not_allowed)
			(vias allowed)
			(pads allowed)
			(copperpour not_allowed)
			(footprints allowed)
		)
		(placement
			(enabled no)
			(sheetname "")
		)
		(fill yes
			(thermal_gap 0.5)
			(thermal_bridge_width 0.5)
			(island_removal_mode 0)
		)
		(polygon
			(pts
				(arc
					(start 270.417798 -262.971534)
					(mid 270.432677 -263.007455)
					(end 270.468598 -263.022334)
				)
				(arc
					(start 271.868138 -263.022334)
					(mid 271.904059 -263.007455)
					(end 271.918938 -262.971534)
				)
				(arc
					(start 271.918938 -262.562594)
					(mid 271.904059 -262.526673)
					(end 271.868138 -262.511794)
				)
				(arc
					(start 270.468598 -262.511794)
					(mid 270.432677 -262.526673)
					(end 270.417798 -262.562594)
				)
			)
		)
	)
	(zone
		(layers "In1.Cu" "In2.Cu")
		(hatch none 0.5)
		(connect_pads
			(clearance 0)
		)
		(min_thickness 0.25)
		(keepout
			(tracks not_allowed)
			(vias allowed)
			(pads allowed)
			(copperpour not_allowed)
			(footprints allowed)
		)
		(placement
			(enabled no)
			(sheetname "")
		)
		(fill yes
			(thermal_gap 0.5)
			(thermal_bridge_width 0.5)
			(island_removal_mode 0)
		)
		(polygon
			(pts
				(arc
					(start 64.296798 -199.221344)
					(mid 64.311677 -199.257265)
					(end 64.347598 -199.272144)
				)
				(arc
					(start 65.747138 -199.272144)
					(mid 65.783059 -199.257265)
					(end 65.797938 -199.221344)
				)
				(arc
					(start 65.797938 -198.812404)
					(mid 65.783059 -198.776483)
					(end 65.747138 -198.761604)
				)
				(arc
					(start 64.347598 -198.761604)
					(mid 64.311677 -198.776483)
					(end 64.296798 -198.812404)
				)
			)
		)
	)
	(zone
		(layers "In1.Cu" "In2.Cu")
		(hatch none 0.5)
		(connect_pads
			(clearance 0)
		)
		(min_thickness 0.25)
		(keepout
			(tracks not_allowed)
			(vias allowed)
			(pads allowed)
			(copperpour not_allowed)
			(footprints allowed)
		)
		(placement
			(enabled no)
			(sheetname "")
		)
		(fill yes
			(thermal_gap 0.5)
			(thermal_bridge_width 0.5)
			(island_removal_mode 0)
		)
		(polygon
			(pts
				(arc
					(start 451.265798 -286.771334)
					(mid 451.280677 -286.807255)
					(end 451.316598 -286.822134)
				)
				(arc
					(start 452.716138 -286.822134)
					(mid 452.752059 -286.807255)
					(end 452.766938 -286.771334)
				)
				(arc
					(start 452.766938 -286.362394)
					(mid 452.752059 -286.326473)
					(end 452.716138 -286.311594)
				)
				(arc
					(start 451.316598 -286.311594)
					(mid 451.280677 -286.326473)
					(end 451.265798 -286.362394)
				)
			)
		)
	)
	(zone
		(layers "In1.Cu" "In2.Cu")
		(hatch none 0.5)
		(connect_pads
			(clearance 0)
		)
		(min_thickness 0.25)
		(keepout
			(tracks not_allowed)
			(vias allowed)
			(pads allowed)
			(copperpour not_allowed)
			(footprints allowed)
		)
		(placement
			(enabled no)
			(sheetname "")
		)
		(fill yes
			(thermal_gap 0.5)
			(thermal_bridge_width 0.5)
			(island_removal_mode 0)
		)
		(polygon
			(pts
				(arc
					(start 207.425798 -312.27141)
					(mid 207.440677 -312.307331)
					(end 207.476598 -312.32221)
				)
				(arc
					(start 208.876138 -312.32221)
					(mid 208.912059 -312.307331)
					(end 208.926938 -312.27141)
				)
				(arc
					(start 208.926938 -311.86247)
					(mid 208.912059 -311.826549)
					(end 208.876138 -311.81167)
				)
				(arc
					(start 207.476598 -311.81167)
					(mid 207.440677 -311.826549)
					(end 207.425798 -311.86247)
				)
			)
		)
	)
	(zone
		(layers "In1.Cu" "In2.Cu")
		(hatch none 0.5)
		(connect_pads
			(clearance 0)
		)
		(min_thickness 0.25)
		(keepout
			(tracks not_allowed)
			(vias allowed)
			(pads allowed)
			(copperpour not_allowed)
			(footprints allowed)
		)
		(placement
			(enabled no)
			(sheetname "")
		)
		(fill yes
			(thermal_gap 0.5)
			(thermal_bridge_width 0.5)
			(island_removal_mode 0)
		)
		(polygon
			(pts
				(arc
					(start 60.19673 -228.121464)
					(mid 60.211609 -228.157385)
					(end 60.24753 -228.172264)
				)
				(arc
					(start 61.64707 -228.172264)
					(mid 61.682991 -228.157385)
					(end 61.69787 -228.121464)
				)
				(arc
					(start 61.69787 -227.712524)
					(mid 61.682991 -227.676603)
					(end 61.64707 -227.661724)
				)
				(arc
					(start 60.24753 -227.661724)
					(mid 60.211609 -227.676603)
					(end 60.19673 -227.712524)
				)
			)
		)
	)
	(zone
		(layers "In1.Cu" "In2.Cu")
		(hatch none 0.5)
		(connect_pads
			(clearance 0)
		)
		(min_thickness 0.25)
		(keepout
			(tracks not_allowed)
			(vias allowed)
			(pads allowed)
			(copperpour not_allowed)
			(footprints allowed)
		)
		(placement
			(enabled no)
			(sheetname "")
		)
		(fill yes
			(thermal_gap 0.5)
			(thermal_bridge_width 0.5)
			(island_removal_mode 0)
		)
		(polygon
			(pts
				(arc
					(start 443.721998 -244.271292)
					(mid 443.736877 -244.307213)
					(end 443.772798 -244.322092)
				)
				(arc
					(start 445.172338 -244.322092)
					(mid 445.208259 -244.307213)
					(end 445.223138 -244.271292)
				)
				(arc
					(start 445.223138 -243.862352)
					(mid 445.208259 -243.826431)
					(end 445.172338 -243.811552)
				)
				(arc
					(start 443.772798 -243.811552)
					(mid 443.736877 -243.826431)
					(end 443.721998 -243.862352)
				)
			)
		)
	)
	(zone
		(layers "In1.Cu" "In2.Cu")
		(hatch none 0.5)
		(connect_pads
			(clearance 0)
		)
		(min_thickness 0.25)
		(keepout
			(tracks not_allowed)
			(vias allowed)
			(pads allowed)
			(copperpour not_allowed)
			(footprints allowed)
		)
		(placement
			(enabled no)
			(sheetname "")
		)
		(fill yes
			(thermal_gap 0.5)
			(thermal_bridge_width 0.5)
			(island_removal_mode 0)
		)
		(polygon
			(pts
				(arc
					(start 214.969598 -274.02155)
					(mid 214.984477 -274.057471)
					(end 215.020398 -274.07235)
				)
				(arc
					(start 216.419938 -274.07235)
					(mid 216.455859 -274.057471)
					(end 216.470738 -274.02155)
				)
				(arc
					(start 216.470738 -273.61261)
					(mid 216.455859 -273.576689)
					(end 216.419938 -273.56181)
				)
				(arc
					(start 215.020398 -273.56181)
					(mid 214.984477 -273.576689)
					(end 214.969598 -273.61261)
				)
			)
		)
	)
	(zone
		(layers "In1.Cu" "In2.Cu")
		(hatch none 0.5)
		(connect_pads
			(clearance 0)
		)
		(min_thickness 0.25)
		(keepout
			(tracks not_allowed)
			(vias allowed)
			(pads allowed)
			(copperpour not_allowed)
			(footprints allowed)
		)
		(placement
			(enabled no)
			(sheetname "")
		)
		(fill yes
			(thermal_gap 0.5)
			(thermal_bridge_width 0.5)
			(island_removal_mode 0)
		)
		(polygon
			(pts
				(arc
					(start 432.734466 -227.271326)
					(mid 432.749345 -227.307247)
					(end 432.785266 -227.322126)
				)
				(arc
					(start 434.184806 -227.322126)
					(mid 434.220727 -227.307247)
					(end 434.235606 -227.271326)
				)
				(arc
					(start 434.235606 -226.862386)
					(mid 434.220727 -226.826465)
					(end 434.184806 -226.811586)
				)
				(arc
					(start 432.785266 -226.811586)
					(mid 432.749345 -226.826465)
					(end 432.734466 -226.862386)
				)
			)
		)
	)
	(zone
		(layers "In1.Cu" "In2.Cu")
		(hatch none 0.5)
		(connect_pads
			(clearance 0)
		)
		(min_thickness 0.25)
		(keepout
			(tracks not_allowed)
			(vias allowed)
			(pads allowed)
			(copperpour not_allowed)
			(footprints allowed)
		)
		(placement
			(enabled no)
			(sheetname "")
		)
		(fill yes
			(thermal_gap 0.5)
			(thermal_bridge_width 0.5)
			(island_removal_mode 0)
		)
		(polygon
			(pts
				(arc
					(start 270.417798 -237.471458)
					(mid 270.432677 -237.507379)
					(end 270.468598 -237.522258)
				)
				(arc
					(start 271.868138 -237.522258)
					(mid 271.904059 -237.507379)
					(end 271.918938 -237.471458)
				)
				(arc
					(start 271.918938 -237.062518)
					(mid 271.904059 -237.026597)
					(end 271.868138 -237.011718)
				)
				(arc
					(start 270.468598 -237.011718)
					(mid 270.432677 -237.026597)
					(end 270.417798 -237.062518)
				)
			)
		)
	)
	(zone
		(layers "In1.Cu" "In2.Cu")
		(hatch none 0.5)
		(connect_pads
			(clearance 0)
		)
		(min_thickness 0.25)
		(keepout
			(tracks not_allowed)
			(vias allowed)
			(pads allowed)
			(copperpour not_allowed)
			(footprints allowed)
		)
		(placement
			(enabled no)
			(sheetname "")
		)
		(fill yes
			(thermal_gap 0.5)
			(thermal_bridge_width 0.5)
			(island_removal_mode 0)
		)
		(polygon
			(pts
				(arc
					(start 207.425798 -197.521322)
					(mid 207.440677 -197.557243)
					(end 207.476598 -197.572122)
				)
				(arc
					(start 208.876138 -197.572122)
					(mid 208.912059 -197.557243)
					(end 208.926938 -197.521322)
				)
				(arc
					(start 208.926938 -197.112382)
					(mid 208.912059 -197.076461)
					(end 208.876138 -197.061582)
				)
				(arc
					(start 207.476598 -197.061582)
					(mid 207.440677 -197.076461)
					(end 207.425798 -197.112382)
				)
			)
		)
	)
	(zone
		(layers "In1.Cu" "In2.Cu")
		(hatch none 0.5)
		(connect_pads
			(clearance 0)
		)
		(min_thickness 0.25)
		(keepout
			(tracks not_allowed)
			(vias allowed)
			(pads allowed)
			(copperpour not_allowed)
			(footprints allowed)
		)
		(placement
			(enabled no)
			(sheetname "")
		)
		(fill yes
			(thermal_gap 0.5)
			(thermal_bridge_width 0.5)
			(island_removal_mode 0)
		)
		(polygon
			(pts
				(arc
					(start 255.330198 -288.471356)
					(mid 255.345077 -288.507277)
					(end 255.380998 -288.522156)
				)
				(arc
					(start 256.780538 -288.522156)
					(mid 256.816459 -288.507277)
					(end 256.831338 -288.471356)
				)
				(arc
					(start 256.831338 -288.062416)
					(mid 256.816459 -288.026495)
					(end 256.780538 -288.011616)
				)
				(arc
					(start 255.380998 -288.011616)
					(mid 255.345077 -288.026495)
					(end 255.330198 -288.062416)
				)
			)
		)
	)
	(zone
		(layers "In1.Cu" "In2.Cu")
		(hatch none 0.5)
		(connect_pads
			(clearance 0)
		)
		(min_thickness 0.25)
		(keepout
			(tracks not_allowed)
			(vias allowed)
			(pads allowed)
			(copperpour not_allowed)
			(footprints allowed)
		)
		(placement
			(enabled no)
			(sheetname "")
		)
		(fill yes
			(thermal_gap 0.5)
			(thermal_bridge_width 0.5)
			(island_removal_mode 0)
		)
		(polygon
			(pts
				(arc
					(start 49.209198 -209.421476)
					(mid 49.224077 -209.457397)
					(end 49.259998 -209.472276)
				)
				(arc
					(start 50.659538 -209.472276)
					(mid 50.695459 -209.457397)
					(end 50.710338 -209.421476)
				)
				(arc
					(start 50.710338 -209.012536)
					(mid 50.695459 -208.976615)
					(end 50.659538 -208.961736)
				)
				(arc
					(start 49.259998 -208.961736)
					(mid 49.224077 -208.976615)
					(end 49.209198 -209.012536)
				)
			)
		)
	)
	(zone
		(layers "In1.Cu" "In2.Cu")
		(hatch none 0.5)
		(connect_pads
			(clearance 0)
		)
		(min_thickness 0.25)
		(keepout
			(tracks not_allowed)
			(vias allowed)
			(pads allowed)
			(copperpour not_allowed)
			(footprints allowed)
		)
		(placement
			(enabled no)
			(sheetname "")
		)
		(fill yes
			(thermal_gap 0.5)
			(thermal_bridge_width 0.5)
			(island_removal_mode 0)
		)
		(polygon
			(pts
				(arc
					(start 447.822066 -240.871502)
					(mid 447.836945 -240.907423)
					(end 447.872866 -240.922302)
				)
				(arc
					(start 449.272406 -240.922302)
					(mid 449.308327 -240.907423)
					(end 449.323206 -240.871502)
				)
				(arc
					(start 449.323206 -240.462562)
					(mid 449.308327 -240.426641)
					(end 449.272406 -240.411762)
				)
				(arc
					(start 447.872866 -240.411762)
					(mid 447.836945 -240.426641)
					(end 447.822066 -240.462562)
				)
			)
		)
	)
	(zone
		(layers "In1.Cu" "In2.Cu")
		(hatch none 0.5)
		(connect_pads
			(clearance 0)
		)
		(min_thickness 0.25)
		(keepout
			(tracks not_allowed)
			(vias allowed)
			(pads allowed)
			(copperpour not_allowed)
			(footprints allowed)
		)
		(placement
			(enabled no)
			(sheetname "")
		)
		(fill yes
			(thermal_gap 0.5)
			(thermal_bridge_width 0.5)
			(island_removal_mode 0)
		)
		(polygon
			(pts
				(arc
					(start 26.577798 -240.871502)
					(mid 26.592677 -240.907423)
					(end 26.628598 -240.922302)
				)
				(arc
					(start 28.028138 -240.922302)
					(mid 28.064059 -240.907423)
					(end 28.078938 -240.871502)
				)
				(arc
					(start 28.078938 -240.462562)
					(mid 28.064059 -240.426641)
					(end 28.028138 -240.411762)
				)
				(arc
					(start 26.628598 -240.411762)
					(mid 26.592677 -240.426641)
					(end 26.577798 -240.462562)
				)
			)
		)
	)
	(zone
		(layers "In1.Cu" "In2.Cu")
		(hatch none 0.5)
		(connect_pads
			(clearance 0)
		)
		(min_thickness 0.25)
		(keepout
			(tracks not_allowed)
			(vias allowed)
			(pads allowed)
			(copperpour not_allowed)
			(footprints allowed)
		)
		(placement
			(enabled no)
			(sheetname "")
		)
		(fill yes
			(thermal_gap 0.5)
			(thermal_bridge_width 0.5)
			(island_removal_mode 0)
		)
		(polygon
			(pts
				(arc
					(start 11.490198 -306.32146)
					(mid 11.505077 -306.357381)
					(end 11.540998 -306.37226)
				)
				(arc
					(start 12.940538 -306.37226)
					(mid 12.976459 -306.357381)
					(end 12.991338 -306.32146)
				)
				(arc
					(start 12.991338 -305.91252)
					(mid 12.976459 -305.876599)
					(end 12.940538 -305.86172)
				)
				(arc
					(start 11.540998 -305.86172)
					(mid 11.505077 -305.876599)
					(end 11.490198 -305.91252)
				)
			)
		)
	)
	(zone
		(layers "In1.Cu" "In2.Cu")
		(hatch none 0.5)
		(connect_pads
			(clearance 0)
		)
		(min_thickness 0.25)
		(keepout
			(tracks not_allowed)
			(vias allowed)
			(pads allowed)
			(copperpour not_allowed)
			(footprints allowed)
		)
		(placement
			(enabled no)
			(sheetname "")
		)
		(fill yes
			(thermal_gap 0.5)
			(thermal_bridge_width 0.5)
			(island_removal_mode 0)
		)
		(polygon
			(pts
				(arc
					(start 297.149266 -270.621506)
					(mid 297.164145 -270.657427)
					(end 297.200066 -270.672306)
				)
				(arc
					(start 298.599606 -270.672306)
					(mid 298.635527 -270.657427)
					(end 298.650406 -270.621506)
				)
				(arc
					(start 298.650406 -270.212566)
					(mid 298.635527 -270.176645)
					(end 298.599606 -270.161766)
				)
				(arc
					(start 297.200066 -270.161766)
					(mid 297.164145 -270.176645)
					(end 297.149266 -270.212566)
				)
			)
		)
	)
	(zone
		(layers "In1.Cu" "In2.Cu")
		(hatch none 0.5)
		(connect_pads
			(clearance 0)
		)
		(min_thickness 0.25)
		(keepout
			(tracks not_allowed)
			(vias allowed)
			(pads allowed)
			(copperpour not_allowed)
			(footprints allowed)
		)
		(placement
			(enabled no)
			(sheetname "")
		)
		(fill yes
			(thermal_gap 0.5)
			(thermal_bridge_width 0.5)
			(island_removal_mode 0)
		)
		(polygon
			(pts
				(arc
					(start 22.47773 -286.771334)
					(mid 22.492609 -286.807255)
					(end 22.52853 -286.822134)
				)
				(arc
					(start 23.92807 -286.822134)
					(mid 23.963991 -286.807255)
					(end 23.97887 -286.771334)
				)
				(arc
					(start 23.97887 -286.362394)
					(mid 23.963991 -286.326473)
					(end 23.92807 -286.311594)
				)
				(arc
					(start 22.52853 -286.311594)
					(mid 22.492609 -286.326473)
					(end 22.47773 -286.362394)
				)
			)
		)
	)
	(zone
		(layers "In1.Cu" "In2.Cu")
		(hatch none 0.5)
		(connect_pads
			(clearance 0)
		)
		(min_thickness 0.25)
		(keepout
			(tracks not_allowed)
			(vias allowed)
			(pads allowed)
			(copperpour not_allowed)
			(footprints allowed)
		)
		(placement
			(enabled no)
			(sheetname "")
		)
		(fill yes
			(thermal_gap 0.5)
			(thermal_bridge_width 0.5)
			(island_removal_mode 0)
		)
		(polygon
			(pts
				(arc
					(start 177.250598 -205.171548)
					(mid 177.265477 -205.207469)
					(end 177.301398 -205.222348)
				)
				(arc
					(start 178.700938 -205.222348)
					(mid 178.736859 -205.207469)
					(end 178.751738 -205.171548)
				)
				(arc
					(start 178.751738 -204.762608)
					(mid 178.736859 -204.726687)
					(end 178.700938 -204.711808)
				)
				(arc
					(start 177.301398 -204.711808)
					(mid 177.265477 -204.726687)
					(end 177.250598 -204.762608)
				)
			)
		)
	)
	(zone
		(layers "In1.Cu" "In2.Cu")
		(hatch none 0.5)
		(connect_pads
			(clearance 0)
		)
		(min_thickness 0.25)
		(keepout
			(tracks not_allowed)
			(vias allowed)
			(pads allowed)
			(copperpour not_allowed)
			(footprints allowed)
		)
		(placement
			(enabled no)
			(sheetname "")
		)
		(fill yes
			(thermal_gap 0.5)
			(thermal_bridge_width 0.5)
			(island_removal_mode 0)
		)
		(polygon
			(pts
				(arc
					(start 173.15053 -244.271292)
					(mid 173.165409 -244.307213)
					(end 173.20133 -244.322092)
				)
				(arc
					(start 174.60087 -244.322092)
					(mid 174.636791 -244.307213)
					(end 174.65167 -244.271292)
				)
				(arc
					(start 174.65167 -243.862352)
					(mid 174.636791 -243.826431)
					(end 174.60087 -243.811552)
				)
				(arc
					(start 173.20133 -243.811552)
					(mid 173.165409 -243.826431)
					(end 173.15053 -243.862352)
				)
			)
		)
	)
	(zone
		(layers "In1.Cu" "In2.Cu")
		(hatch none 0.5)
		(connect_pads
			(clearance 0)
		)
		(min_thickness 0.25)
		(keepout
			(tracks not_allowed)
			(vias allowed)
			(pads allowed)
			(copperpour not_allowed)
			(footprints allowed)
		)
		(placement
			(enabled no)
			(sheetname "")
		)
		(fill yes
			(thermal_gap 0.5)
			(thermal_bridge_width 0.5)
			(island_removal_mode 0)
		)
		(polygon
			(pts
				(arc
					(start 413.546798 -217.071448)
					(mid 413.561677 -217.107369)
					(end 413.597598 -217.122248)
				)
				(arc
					(start 414.997138 -217.122248)
					(mid 415.033059 -217.107369)
					(end 415.047938 -217.071448)
				)
				(arc
					(start 415.047938 -216.662508)
					(mid 415.033059 -216.626587)
					(end 414.997138 -216.611708)
				)
				(arc
					(start 413.597598 -216.611708)
					(mid 413.561677 -216.626587)
					(end 413.546798 -216.662508)
				)
			)
		)
	)
	(zone
		(layers "In1.Cu" "In2.Cu")
		(hatch none 0.5)
		(connect_pads
			(clearance 0)
		)
		(min_thickness 0.25)
		(keepout
			(tracks not_allowed)
			(vias allowed)
			(pads allowed)
			(copperpour not_allowed)
			(footprints allowed)
		)
		(placement
			(enabled no)
			(sheetname "")
		)
		(fill yes
			(thermal_gap 0.5)
			(thermal_bridge_width 0.5)
			(island_removal_mode 0)
		)
		(polygon
			(pts
				(arc
					(start 410.103066 -203.471526)
					(mid 410.117945 -203.507447)
					(end 410.153866 -203.522326)
				)
				(arc
					(start 411.553406 -203.522326)
					(mid 411.589327 -203.507447)
					(end 411.604206 -203.471526)
				)
				(arc
					(start 411.604206 -203.062586)
					(mid 411.589327 -203.026665)
					(end 411.553406 -203.011786)
				)
				(arc
					(start 410.153866 -203.011786)
					(mid 410.117945 -203.026665)
					(end 410.103066 -203.062586)
				)
			)
		)
	)
	(zone
		(layers "In1.Cu" "In2.Cu")
		(hatch none 0.5)
		(connect_pads
			(clearance 0)
		)
		(min_thickness 0.25)
		(keepout
			(tracks not_allowed)
			(vias allowed)
			(pads allowed)
			(copperpour not_allowed)
			(footprints allowed)
		)
		(placement
			(enabled no)
			(sheetname "")
		)
		(fill yes
			(thermal_gap 0.5)
			(thermal_bridge_width 0.5)
			(island_removal_mode 0)
		)
		(polygon
			(pts
				(arc
					(start 458.809598 -274.871434)
					(mid 458.824477 -274.907355)
					(end 458.860398 -274.922234)
				)
				(arc
					(start 460.259938 -274.922234)
					(mid 460.295859 -274.907355)
					(end 460.310738 -274.871434)
				)
				(arc
					(start 460.310738 -274.462494)
					(mid 460.295859 -274.426573)
					(end 460.259938 -274.411694)
				)
				(arc
					(start 458.860398 -274.411694)
					(mid 458.824477 -274.426573)
					(end 458.809598 -274.462494)
				)
			)
		)
	)
	(zone
		(layers "In1.Cu" "In2.Cu")
		(hatch none 0.5)
		(connect_pads
			(clearance 0)
		)
		(min_thickness 0.25)
		(keepout
			(tracks not_allowed)
			(vias allowed)
			(pads allowed)
			(copperpour not_allowed)
			(footprints allowed)
		)
		(placement
			(enabled no)
			(sheetname "")
		)
		(fill yes
			(thermal_gap 0.5)
			(thermal_bridge_width 0.5)
			(island_removal_mode 0)
		)
		(polygon
			(pts
				(arc
					(start 199.881998 -276.571456)
					(mid 199.896877 -276.607377)
					(end 199.932798 -276.622256)
				)
				(arc
					(start 201.332338 -276.622256)
					(mid 201.368259 -276.607377)
					(end 201.383138 -276.571456)
				)
				(arc
					(start 201.383138 -276.162516)
					(mid 201.368259 -276.126595)
					(end 201.332338 -276.111716)
				)
				(arc
					(start 199.932798 -276.111716)
					(mid 199.896877 -276.126595)
					(end 199.881998 -276.162516)
				)
			)
		)
	)
	(zone
		(layers "In1.Cu" "In2.Cu")
		(hatch none 0.5)
		(connect_pads
			(clearance 0)
		)
		(min_thickness 0.25)
		(keepout
			(tracks not_allowed)
			(vias allowed)
			(pads allowed)
			(copperpour not_allowed)
			(footprints allowed)
		)
		(placement
			(enabled no)
			(sheetname "")
		)
		(fill yes
			(thermal_gap 0.5)
			(thermal_bridge_width 0.5)
			(island_removal_mode 0)
		)
		(polygon
			(pts
				(arc
					(start 37.56533 -268.071346)
					(mid 37.580209 -268.107267)
					(end 37.61613 -268.122146)
				)
				(arc
					(start 39.01567 -268.122146)
					(mid 39.051591 -268.107267)
					(end 39.06647 -268.071346)
				)
				(arc
					(start 39.06647 -267.662406)
					(mid 39.051591 -267.626485)
					(end 39.01567 -267.611606)
				)
				(arc
					(start 37.61613 -267.611606)
					(mid 37.580209 -267.626485)
					(end 37.56533 -267.662406)
				)
			)
		)
	)
	(zone
		(layers "In1.Cu" "In2.Cu")
		(hatch none 0.5)
		(connect_pads
			(clearance 0)
		)
		(min_thickness 0.25)
		(keepout
			(tracks not_allowed)
			(vias allowed)
			(pads allowed)
			(copperpour not_allowed)
			(footprints allowed)
		)
		(placement
			(enabled no)
			(sheetname "")
		)
		(fill yes
			(thermal_gap 0.5)
			(thermal_bridge_width 0.5)
			(island_removal_mode 0)
		)
		(polygon
			(pts
				(arc
					(start 173.15053 -196.671438)
					(mid 173.165409 -196.707359)
					(end 173.20133 -196.722238)
				)
				(arc
					(start 174.60087 -196.722238)
					(mid 174.636791 -196.707359)
					(end 174.65167 -196.671438)
				)
				(arc
					(start 174.65167 -196.262498)
					(mid 174.636791 -196.226577)
					(end 174.60087 -196.211698)
				)
				(arc
					(start 173.20133 -196.211698)
					(mid 173.165409 -196.226577)
					(end 173.15053 -196.262498)
				)
			)
		)
	)
	(zone
		(layers "In1.Cu" "In2.Cu")
		(hatch none 0.5)
		(connect_pads
			(clearance 0)
		)
		(min_thickness 0.25)
		(keepout
			(tracks not_allowed)
			(vias allowed)
			(pads allowed)
			(copperpour not_allowed)
			(footprints allowed)
		)
		(placement
			(enabled no)
			(sheetname "")
		)
		(fill yes
			(thermal_gap 0.5)
			(thermal_bridge_width 0.5)
			(island_removal_mode 0)
		)
		(polygon
			(pts
				(arc
					(start 162.162998 -287.621472)
					(mid 162.177877 -287.657393)
					(end 162.213798 -287.672272)
				)
				(arc
					(start 163.613338 -287.672272)
					(mid 163.649259 -287.657393)
					(end 163.664138 -287.621472)
				)
				(arc
					(start 163.664138 -287.212532)
					(mid 163.649259 -287.176611)
					(end 163.613338 -287.161732)
				)
				(arc
					(start 162.213798 -287.161732)
					(mid 162.177877 -287.176611)
					(end 162.162998 -287.212532)
				)
			)
		)
	)
	(zone
		(layers "In1.Cu" "In2.Cu")
		(hatch none 0.5)
		(connect_pads
			(clearance 0)
		)
		(min_thickness 0.25)
		(keepout
			(tracks not_allowed)
			(vias allowed)
			(pads allowed)
			(copperpour not_allowed)
			(footprints allowed)
		)
		(placement
			(enabled no)
			(sheetname "")
		)
		(fill yes
			(thermal_gap 0.5)
			(thermal_bridge_width 0.5)
			(island_removal_mode 0)
		)
		(polygon
			(pts
				(arc
					(start 210.86953 -196.671438)
					(mid 210.884409 -196.707359)
					(end 210.92033 -196.722238)
				)
				(arc
					(start 212.31987 -196.722238)
					(mid 212.355791 -196.707359)
					(end 212.37067 -196.671438)
				)
				(arc
					(start 212.37067 -196.262498)
					(mid 212.355791 -196.226577)
					(end 212.31987 -196.211698)
				)
				(arc
					(start 210.92033 -196.211698)
					(mid 210.884409 -196.226577)
					(end 210.86953 -196.262498)
				)
			)
		)
	)
	(zone
		(layers "In1.Cu" "In2.Cu")
		(hatch none 0.5)
		(connect_pads
			(clearance 0)
		)
		(min_thickness 0.25)
		(keepout
			(tracks not_allowed)
			(vias allowed)
			(pads allowed)
			(copperpour not_allowed)
			(footprints allowed)
		)
		(placement
			(enabled no)
			(sheetname "")
		)
		(fill yes
			(thermal_gap 0.5)
			(thermal_bridge_width 0.5)
			(island_removal_mode 0)
		)
		(polygon
			(pts
				(arc
					(start 270.417798 -230.67137)
					(mid 270.432677 -230.707291)
					(end 270.468598 -230.72217)
				)
				(arc
					(start 271.868138 -230.72217)
					(mid 271.904059 -230.707291)
					(end 271.918938 -230.67137)
				)
				(arc
					(start 271.918938 -230.26243)
					(mid 271.904059 -230.226509)
					(end 271.868138 -230.21163)
				)
				(arc
					(start 270.468598 -230.21163)
					(mid 270.432677 -230.226509)
					(end 270.417798 -230.26243)
				)
			)
		)
	)
	(zone
		(layers "In1.Cu" "In2.Cu")
		(hatch none 0.5)
		(connect_pads
			(clearance 0)
		)
		(min_thickness 0.25)
		(keepout
			(tracks not_allowed)
			(vias allowed)
			(pads allowed)
			(copperpour not_allowed)
			(footprints allowed)
		)
		(placement
			(enabled no)
			(sheetname "")
		)
		(fill yes
			(thermal_gap 0.5)
			(thermal_bridge_width 0.5)
			(island_removal_mode 0)
		)
		(polygon
			(pts
				(arc
					(start 262.873998 -282.521406)
					(mid 262.888877 -282.557327)
					(end 262.924798 -282.572206)
				)
				(arc
					(start 264.324338 -282.572206)
					(mid 264.360259 -282.557327)
					(end 264.375138 -282.521406)
				)
				(arc
					(start 264.375138 -282.112466)
					(mid 264.360259 -282.076545)
					(end 264.324338 -282.061666)
				)
				(arc
					(start 262.924798 -282.061666)
					(mid 262.888877 -282.076545)
					(end 262.873998 -282.112466)
				)
			)
		)
	)
	(zone
		(layers "In1.Cu" "In2.Cu")
		(hatch none 0.5)
		(connect_pads
			(clearance 0)
		)
		(min_thickness 0.25)
		(keepout
			(tracks not_allowed)
			(vias allowed)
			(pads allowed)
			(copperpour not_allowed)
			(footprints allowed)
		)
		(placement
			(enabled no)
			(sheetname "")
		)
		(fill yes
			(thermal_gap 0.5)
			(thermal_bridge_width 0.5)
			(island_removal_mode 0)
		)
		(polygon
			(pts
				(arc
					(start 14.93393 -259.57149)
					(mid 14.948809 -259.607411)
					(end 14.98473 -259.62229)
				)
				(arc
					(start 16.38427 -259.62229)
					(mid 16.420191 -259.607411)
					(end 16.43507 -259.57149)
				)
				(arc
					(start 16.43507 -259.16255)
					(mid 16.420191 -259.126629)
					(end 16.38427 -259.11175)
				)
				(arc
					(start 14.98473 -259.11175)
					(mid 14.948809 -259.126629)
					(end 14.93393 -259.16255)
				)
			)
		)
	)
	(zone
		(layers "In1.Cu" "In2.Cu")
		(hatch none 0.5)
		(connect_pads
			(clearance 0)
		)
		(min_thickness 0.25)
		(keepout
			(tracks not_allowed)
			(vias allowed)
			(pads allowed)
			(copperpour not_allowed)
			(footprints allowed)
		)
		(placement
			(enabled no)
			(sheetname "")
		)
		(fill yes
			(thermal_gap 0.5)
			(thermal_bridge_width 0.5)
			(island_removal_mode 0)
		)
		(polygon
			(pts
				(arc
					(start 455.365866 -268.921484)
					(mid 455.380745 -268.957405)
					(end 455.416666 -268.972284)
				)
				(arc
					(start 456.816206 -268.972284)
					(mid 456.852127 -268.957405)
					(end 456.867006 -268.921484)
				)
				(arc
					(start 456.867006 -268.512544)
					(mid 456.852127 -268.476623)
					(end 456.816206 -268.461744)
				)
				(arc
					(start 455.416666 -268.461744)
					(mid 455.380745 -268.476623)
					(end 455.365866 -268.512544)
				)
			)
		)
	)
	(zone
		(layers "In1.Cu" "In2.Cu")
		(hatch none 0.5)
		(connect_pads
			(clearance 0)
		)
		(min_thickness 0.25)
		(keepout
			(tracks not_allowed)
			(vias allowed)
			(pads allowed)
			(copperpour not_allowed)
			(footprints allowed)
		)
		(placement
			(enabled no)
			(sheetname "")
		)
		(fill yes
			(thermal_gap 0.5)
			(thermal_bridge_width 0.5)
			(island_removal_mode 0)
		)
		(polygon
			(pts
				(arc
					(start 262.873998 -290.171378)
					(mid 262.888877 -290.207299)
					(end 262.924798 -290.222178)
				)
				(arc
					(start 264.324338 -290.222178)
					(mid 264.360259 -290.207299)
					(end 264.375138 -290.171378)
				)
				(arc
					(start 264.375138 -289.762438)
					(mid 264.360259 -289.726517)
					(end 264.324338 -289.711638)
				)
				(arc
					(start 262.924798 -289.711638)
					(mid 262.888877 -289.726517)
					(end 262.873998 -289.762438)
				)
			)
		)
	)
	(zone
		(layers "In1.Cu" "In2.Cu")
		(hatch none 0.5)
		(connect_pads
			(clearance 0)
		)
		(min_thickness 0.25)
		(keepout
			(tracks not_allowed)
			(vias allowed)
			(pads allowed)
			(copperpour not_allowed)
			(footprints allowed)
		)
		(placement
			(enabled no)
			(sheetname "")
		)
		(fill yes
			(thermal_gap 0.5)
			(thermal_bridge_width 0.5)
			(island_removal_mode 0)
		)
		(polygon
			(pts
				(arc
					(start 180.69433 -210.27136)
					(mid 180.709209 -210.307281)
					(end 180.74513 -210.32216)
				)
				(arc
					(start 182.14467 -210.32216)
					(mid 182.180591 -210.307281)
					(end 182.19547 -210.27136)
				)
				(arc
					(start 182.19547 -209.86242)
					(mid 182.180591 -209.826499)
					(end 182.14467 -209.81162)
				)
				(arc
					(start 180.74513 -209.81162)
					(mid 180.709209 -209.826499)
					(end 180.69433 -209.86242)
				)
			)
		)
	)
	(zone
		(layers "In1.Cu" "In2.Cu")
		(hatch none 0.5)
		(connect_pads
			(clearance 0)
		)
		(min_thickness 0.25)
		(keepout
			(tracks not_allowed)
			(vias allowed)
			(pads allowed)
			(copperpour not_allowed)
			(footprints allowed)
		)
		(placement
			(enabled no)
			(sheetname "")
		)
		(fill yes
			(thermal_gap 0.5)
			(thermal_bridge_width 0.5)
			(island_removal_mode 0)
		)
		(polygon
			(pts
				(arc
					(start 259.430266 -209.421476)
					(mid 259.445145 -209.457397)
					(end 259.481066 -209.472276)
				)
				(arc
					(start 260.880606 -209.472276)
					(mid 260.916527 -209.457397)
					(end 260.931406 -209.421476)
				)
				(arc
					(start 260.931406 -209.012536)
					(mid 260.916527 -208.976615)
					(end 260.880606 -208.961736)
				)
				(arc
					(start 259.481066 -208.961736)
					(mid 259.445145 -208.976615)
					(end 259.430266 -209.012536)
				)
			)
		)
	)
	(zone
		(layers "In1.Cu" "In2.Cu")
		(hatch none 0.5)
		(connect_pads
			(clearance 0)
		)
		(min_thickness 0.25)
		(keepout
			(tracks not_allowed)
			(vias allowed)
			(pads allowed)
			(copperpour not_allowed)
			(footprints allowed)
		)
		(placement
			(enabled no)
			(sheetname "")
		)
		(fill yes
			(thermal_gap 0.5)
			(thermal_bridge_width 0.5)
			(island_removal_mode 0)
		)
		(polygon
			(pts
				(arc
					(start 41.665398 -302.921416)
					(mid 41.680277 -302.957337)
					(end 41.716198 -302.972216)
				)
				(arc
					(start 43.115738 -302.972216)
					(mid 43.151659 -302.957337)
					(end 43.166538 -302.921416)
				)
				(arc
					(start 43.166538 -302.512476)
					(mid 43.151659 -302.476555)
					(end 43.115738 -302.461676)
				)
				(arc
					(start 41.716198 -302.461676)
					(mid 41.680277 -302.476555)
					(end 41.665398 -302.512476)
				)
			)
		)
	)
	(zone
		(layers "In1.Cu" "In2.Cu")
		(hatch none 0.5)
		(connect_pads
			(clearance 0)
		)
		(min_thickness 0.25)
		(keepout
			(tracks not_allowed)
			(vias allowed)
			(pads allowed)
			(copperpour not_allowed)
			(footprints allowed)
		)
		(placement
			(enabled no)
			(sheetname "")
		)
		(fill yes
			(thermal_gap 0.5)
			(thermal_bridge_width 0.5)
			(island_removal_mode 0)
		)
		(polygon
			(pts
				(arc
					(start 255.330198 -271.47139)
					(mid 255.345077 -271.507311)
					(end 255.380998 -271.52219)
				)
				(arc
					(start 256.780538 -271.52219)
					(mid 256.816459 -271.507311)
					(end 256.831338 -271.47139)
				)
				(arc
					(start 256.831338 -271.06245)
					(mid 256.816459 -271.026529)
					(end 256.780538 -271.01165)
				)
				(arc
					(start 255.380998 -271.01165)
					(mid 255.345077 -271.026529)
					(end 255.330198 -271.06245)
				)
			)
		)
	)
	(zone
		(layers "In1.Cu" "In2.Cu")
		(hatch none 0.5)
		(connect_pads
			(clearance 0)
		)
		(min_thickness 0.25)
		(keepout
			(tracks not_allowed)
			(vias allowed)
			(pads allowed)
			(copperpour not_allowed)
			(footprints allowed)
		)
		(placement
			(enabled no)
			(sheetname "")
		)
		(fill yes
			(thermal_gap 0.5)
			(thermal_bridge_width 0.5)
			(island_removal_mode 0)
		)
		(polygon
			(pts
				(arc
					(start 165.60673 -308.871366)
					(mid 165.621609 -308.907287)
					(end 165.65753 -308.922166)
				)
				(arc
					(start 167.05707 -308.922166)
					(mid 167.092991 -308.907287)
					(end 167.10787 -308.871366)
				)
				(arc
					(start 167.10787 -308.462426)
					(mid 167.092991 -308.426505)
					(end 167.05707 -308.411626)
				)
				(arc
					(start 165.65753 -308.411626)
					(mid 165.621609 -308.426505)
					(end 165.60673 -308.462426)
				)
			)
		)
	)
	(zone
		(layers "In1.Cu" "In2.Cu")
		(hatch none 0.5)
		(connect_pads
			(clearance 0)
		)
		(min_thickness 0.25)
		(keepout
			(tracks not_allowed)
			(vias allowed)
			(pads allowed)
			(copperpour not_allowed)
			(footprints allowed)
		)
		(placement
			(enabled no)
			(sheetname "")
		)
		(fill yes
			(thermal_gap 0.5)
			(thermal_bridge_width 0.5)
			(island_removal_mode 0)
		)
		(polygon
			(pts
				(arc
					(start 312.236866 -274.871434)
					(mid 312.251745 -274.907355)
					(end 312.287666 -274.922234)
				)
				(arc
					(start 313.687206 -274.922234)
					(mid 313.723127 -274.907355)
					(end 313.738006 -274.871434)
				)
				(arc
					(start 313.738006 -274.462494)
					(mid 313.723127 -274.426573)
					(end 313.687206 -274.411694)
				)
				(arc
					(start 312.287666 -274.411694)
					(mid 312.251745 -274.426573)
					(end 312.236866 -274.462494)
				)
			)
		)
	)
	(zone
		(layers "In1.Cu" "In2.Cu")
		(hatch none 0.5)
		(connect_pads
			(clearance 0)
		)
		(min_thickness 0.25)
		(keepout
			(tracks not_allowed)
			(vias allowed)
			(pads allowed)
			(copperpour not_allowed)
			(footprints allowed)
		)
		(placement
			(enabled no)
			(sheetname "")
		)
		(fill yes
			(thermal_gap 0.5)
			(thermal_bridge_width 0.5)
			(island_removal_mode 0)
		)
		(polygon
			(pts
				(arc
					(start 455.365866 -270.621506)
					(mid 455.380745 -270.657427)
					(end 455.416666 -270.672306)
				)
				(arc
					(start 456.816206 -270.672306)
					(mid 456.852127 -270.657427)
					(end 456.867006 -270.621506)
				)
				(arc
					(start 456.867006 -270.212566)
					(mid 456.852127 -270.176645)
					(end 456.816206 -270.161766)
				)
				(arc
					(start 455.416666 -270.161766)
					(mid 455.380745 -270.176645)
					(end 455.365866 -270.212566)
				)
			)
		)
	)
	(zone
		(layers "In1.Cu" "In2.Cu")
		(hatch none 0.5)
		(connect_pads
			(clearance 0)
		)
		(min_thickness 0.25)
		(keepout
			(tracks not_allowed)
			(vias allowed)
			(pads allowed)
			(copperpour not_allowed)
			(footprints allowed)
		)
		(placement
			(enabled no)
			(sheetname "")
		)
		(fill yes
			(thermal_gap 0.5)
			(thermal_bridge_width 0.5)
			(island_removal_mode 0)
		)
		(polygon
			(pts
				(arc
					(start 52.65293 -316.521338)
					(mid 52.667809 -316.557259)
					(end 52.70373 -316.572138)
				)
				(arc
					(start 54.10327 -316.572138)
					(mid 54.139191 -316.557259)
					(end 54.15407 -316.521338)
				)
				(arc
					(start 54.15407 -316.112398)
					(mid 54.139191 -316.076477)
					(end 54.10327 -316.061598)
				)
				(arc
					(start 52.70373 -316.061598)
					(mid 52.667809 -316.076477)
					(end 52.65293 -316.112398)
				)
			)
		)
	)
	(zone
		(layers "In1.Cu" "In2.Cu")
		(hatch none 0.5)
		(connect_pads
			(clearance 0)
		)
		(min_thickness 0.25)
		(keepout
			(tracks not_allowed)
			(vias allowed)
			(pads allowed)
			(copperpour not_allowed)
			(footprints allowed)
		)
		(placement
			(enabled no)
			(sheetname "")
		)
		(fill yes
			(thermal_gap 0.5)
			(thermal_bridge_width 0.5)
			(island_removal_mode 0)
		)
		(polygon
			(pts
				(arc
					(start 300.592998 -252.771402)
					(mid 300.607877 -252.807323)
					(end 300.643798 -252.822202)
				)
				(arc
					(start 302.043338 -252.822202)
					(mid 302.079259 -252.807323)
					(end 302.094138 -252.771402)
				)
				(arc
					(start 302.094138 -252.362462)
					(mid 302.079259 -252.326541)
					(end 302.043338 -252.311662)
				)
				(arc
					(start 300.643798 -252.311662)
					(mid 300.607877 -252.326541)
					(end 300.592998 -252.362462)
				)
			)
		)
	)
	(zone
		(layers "In1.Cu" "In2.Cu")
		(hatch none 0.5)
		(connect_pads
			(clearance 0)
		)
		(min_thickness 0.25)
		(keepout
			(tracks not_allowed)
			(vias allowed)
			(pads allowed)
			(copperpour not_allowed)
			(footprints allowed)
		)
		(placement
			(enabled no)
			(sheetname "")
		)
		(fill yes
			(thermal_gap 0.5)
			(thermal_bridge_width 0.5)
			(island_removal_mode 0)
		)
		(polygon
			(pts
				(arc
					(start 440.278266 -201.771504)
					(mid 440.293145 -201.807425)
					(end 440.329066 -201.822304)
				)
				(arc
					(start 441.728606 -201.822304)
					(mid 441.764527 -201.807425)
					(end 441.779406 -201.771504)
				)
				(arc
					(start 441.779406 -201.362564)
					(mid 441.764527 -201.326643)
					(end 441.728606 -201.311764)
				)
				(arc
					(start 440.329066 -201.311764)
					(mid 440.293145 -201.326643)
					(end 440.278266 -201.362564)
				)
			)
		)
	)
	(zone
		(layers "In1.Cu" "In2.Cu")
		(hatch none 0.5)
		(connect_pads
			(clearance 0)
		)
		(min_thickness 0.25)
		(keepout
			(tracks not_allowed)
			(vias allowed)
			(pads allowed)
			(copperpour not_allowed)
			(footprints allowed)
		)
		(placement
			(enabled no)
			(sheetname "")
		)
		(fill yes
			(thermal_gap 0.5)
			(thermal_bridge_width 0.5)
			(island_removal_mode 0)
		)
		(polygon
			(pts
				(arc
					(start 308.136798 -299.521372)
					(mid 308.151677 -299.557293)
					(end 308.187598 -299.572172)
				)
				(arc
					(start 309.587138 -299.572172)
					(mid 309.623059 -299.557293)
					(end 309.637938 -299.521372)
				)
				(arc
					(start 309.637938 -299.112432)
					(mid 309.623059 -299.076511)
					(end 309.587138 -299.061632)
				)
				(arc
					(start 308.187598 -299.061632)
					(mid 308.151677 -299.076511)
					(end 308.136798 -299.112432)
				)
			)
		)
	)
	(zone
		(layers "In1.Cu" "In2.Cu")
		(hatch none 0.5)
		(connect_pads
			(clearance 0)
		)
		(min_thickness 0.25)
		(keepout
			(tracks not_allowed)
			(vias allowed)
			(pads allowed)
			(copperpour not_allowed)
			(footprints allowed)
		)
		(placement
			(enabled no)
			(sheetname "")
		)
		(fill yes
			(thermal_gap 0.5)
			(thermal_bridge_width 0.5)
			(island_removal_mode 0)
		)
		(polygon
			(pts
				(arc
					(start 207.425798 -220.471492)
					(mid 207.440677 -220.507413)
					(end 207.476598 -220.522292)
				)
				(arc
					(start 208.876138 -220.522292)
					(mid 208.912059 -220.507413)
					(end 208.926938 -220.471492)
				)
				(arc
					(start 208.926938 -220.062552)
					(mid 208.912059 -220.026631)
					(end 208.876138 -220.011752)
				)
				(arc
					(start 207.476598 -220.011752)
					(mid 207.440677 -220.026631)
					(end 207.425798 -220.062552)
				)
			)
		)
	)
	(zone
		(layers "In1.Cu" "In2.Cu")
		(hatch none 0.5)
		(connect_pads
			(clearance 0)
		)
		(min_thickness 0.25)
		(keepout
			(tracks not_allowed)
			(vias allowed)
			(pads allowed)
			(copperpour not_allowed)
			(footprints allowed)
		)
		(placement
			(enabled no)
			(sheetname "")
		)
		(fill yes
			(thermal_gap 0.5)
			(thermal_bridge_width 0.5)
			(island_removal_mode 0)
		)
		(polygon
			(pts
				(arc
					(start 285.505398 -275.721318)
					(mid 285.520277 -275.757239)
					(end 285.556198 -275.772118)
				)
				(arc
					(start 286.955738 -275.772118)
					(mid 286.991659 -275.757239)
					(end 287.006538 -275.721318)
				)
				(arc
					(start 287.006538 -275.312378)
					(mid 286.991659 -275.276457)
					(end 286.955738 -275.261578)
				)
				(arc
					(start 285.556198 -275.261578)
					(mid 285.520277 -275.276457)
					(end 285.505398 -275.312378)
				)
			)
		)
	)
	(zone
		(layers "In1.Cu" "In2.Cu")
		(hatch none 0.5)
		(connect_pads
			(clearance 0)
		)
		(min_thickness 0.25)
		(keepout
			(tracks not_allowed)
			(vias allowed)
			(pads allowed)
			(copperpour not_allowed)
			(footprints allowed)
		)
		(placement
			(enabled no)
			(sheetname "")
		)
		(fill yes
			(thermal_gap 0.5)
			(thermal_bridge_width 0.5)
			(island_removal_mode 0)
		)
		(polygon
			(pts
				(arc
					(start 64.296798 -263.821418)
					(mid 64.311677 -263.857339)
					(end 64.347598 -263.872218)
				)
				(arc
					(start 65.747138 -263.872218)
					(mid 65.783059 -263.857339)
					(end 65.797938 -263.821418)
				)
				(arc
					(start 65.797938 -263.412478)
					(mid 65.783059 -263.376557)
					(end 65.747138 -263.361678)
				)
				(arc
					(start 64.347598 -263.361678)
					(mid 64.311677 -263.376557)
					(end 64.296798 -263.412478)
				)
			)
		)
	)
	(zone
		(layers "In1.Cu" "In2.Cu")
		(hatch none 0.5)
		(connect_pads
			(clearance 0)
		)
		(min_thickness 0.25)
		(keepout
			(tracks not_allowed)
			(vias allowed)
			(pads allowed)
			(copperpour not_allowed)
			(footprints allowed)
		)
		(placement
			(enabled no)
			(sheetname "")
		)
		(fill yes
			(thermal_gap 0.5)
			(thermal_bridge_width 0.5)
			(island_removal_mode 0)
		)
		(polygon
			(pts
				(arc
					(start 413.546798 -243.421408)
					(mid 413.561677 -243.457329)
					(end 413.597598 -243.472208)
				)
				(arc
					(start 414.997138 -243.472208)
					(mid 415.033059 -243.457329)
					(end 415.047938 -243.421408)
				)
				(arc
					(start 415.047938 -243.012468)
					(mid 415.033059 -242.976547)
					(end 414.997138 -242.961668)
				)
				(arc
					(start 413.597598 -242.961668)
					(mid 413.561677 -242.976547)
					(end 413.546798 -243.012468)
				)
			)
		)
	)
	(zone
		(layers "In1.Cu" "In2.Cu")
		(hatch none 0.5)
		(connect_pads
			(clearance 0)
		)
		(min_thickness 0.25)
		(keepout
			(tracks not_allowed)
			(vias allowed)
			(pads allowed)
			(copperpour not_allowed)
			(footprints allowed)
		)
		(placement
			(enabled no)
			(sheetname "")
		)
		(fill yes
			(thermal_gap 0.5)
			(thermal_bridge_width 0.5)
			(island_removal_mode 0)
		)
		(polygon
			(pts
				(arc
					(start 195.78193 -261.271512)
					(mid 195.796809 -261.307433)
					(end 195.83273 -261.322312)
				)
				(arc
					(start 197.23227 -261.322312)
					(mid 197.268191 -261.307433)
					(end 197.28307 -261.271512)
				)
				(arc
					(start 197.28307 -260.862572)
					(mid 197.268191 -260.826651)
					(end 197.23227 -260.811772)
				)
				(arc
					(start 195.83273 -260.811772)
					(mid 195.796809 -260.826651)
					(end 195.78193 -260.862572)
				)
			)
		)
	)
	(zone
		(layers "In1.Cu" "In2.Cu")
		(hatch none 0.5)
		(connect_pads
			(clearance 0)
		)
		(min_thickness 0.25)
		(keepout
			(tracks not_allowed)
			(vias allowed)
			(pads allowed)
			(copperpour not_allowed)
			(footprints allowed)
		)
		(placement
			(enabled no)
			(sheetname "")
		)
		(fill yes
			(thermal_gap 0.5)
			(thermal_bridge_width 0.5)
			(island_removal_mode 0)
		)
		(polygon
			(pts
				(arc
					(start 428.634398 -303.7713)
					(mid 428.649277 -303.807221)
					(end 428.685198 -303.8221)
				)
				(arc
					(start 430.084738 -303.8221)
					(mid 430.120659 -303.807221)
					(end 430.135538 -303.7713)
				)
				(arc
					(start 430.135538 -303.36236)
					(mid 430.120659 -303.326439)
					(end 430.084738 -303.31156)
				)
				(arc
					(start 428.685198 -303.31156)
					(mid 428.649277 -303.326439)
					(end 428.634398 -303.36236)
				)
			)
		)
	)
	(zone
		(layers "In1.Cu" "In2.Cu")
		(hatch none 0.5)
		(connect_pads
			(clearance 0)
		)
		(min_thickness 0.25)
		(keepout
			(tracks not_allowed)
			(vias allowed)
			(pads allowed)
			(copperpour not_allowed)
			(footprints allowed)
		)
		(placement
			(enabled no)
			(sheetname "")
		)
		(fill yes
			(thermal_gap 0.5)
			(thermal_bridge_width 0.5)
			(island_removal_mode 0)
		)
		(polygon
			(pts
				(arc
					(start 417.646866 -228.121464)
					(mid 417.661745 -228.157385)
					(end 417.697666 -228.172264)
				)
				(arc
					(start 419.097206 -228.172264)
					(mid 419.133127 -228.157385)
					(end 419.148006 -228.121464)
				)
				(arc
					(start 419.148006 -227.712524)
					(mid 419.133127 -227.676603)
					(end 419.097206 -227.661724)
				)
				(arc
					(start 417.697666 -227.661724)
					(mid 417.661745 -227.676603)
					(end 417.646866 -227.712524)
				)
			)
		)
	)
	(zone
		(layers "In1.Cu" "In2.Cu")
		(hatch none 0.5)
		(connect_pads
			(clearance 0)
		)
		(min_thickness 0.25)
		(keepout
			(tracks not_allowed)
			(vias allowed)
			(pads allowed)
			(copperpour not_allowed)
			(footprints allowed)
		)
		(placement
			(enabled no)
			(sheetname "")
		)
		(fill yes
			(thermal_gap 0.5)
			(thermal_bridge_width 0.5)
			(island_removal_mode 0)
		)
		(polygon
			(pts
				(arc
					(start 266.974066 -229.821486)
					(mid 266.988945 -229.857407)
					(end 267.024866 -229.872286)
				)
				(arc
					(start 268.424406 -229.872286)
					(mid 268.460327 -229.857407)
					(end 268.475206 -229.821486)
				)
				(arc
					(start 268.475206 -229.412546)
					(mid 268.460327 -229.376625)
					(end 268.424406 -229.361746)
				)
				(arc
					(start 267.024866 -229.361746)
					(mid 266.988945 -229.376625)
					(end 266.974066 -229.412546)
				)
			)
		)
	)
	(zone
		(layers "In1.Cu" "In2.Cu")
		(hatch none 0.5)
		(connect_pads
			(clearance 0)
		)
		(min_thickness 0.25)
		(keepout
			(tracks not_allowed)
			(vias allowed)
			(pads allowed)
			(copperpour not_allowed)
			(footprints allowed)
		)
		(placement
			(enabled no)
			(sheetname "")
		)
		(fill yes
			(thermal_gap 0.5)
			(thermal_bridge_width 0.5)
			(island_removal_mode 0)
		)
		(polygon
			(pts
				(arc
					(start 203.32573 -200.071482)
					(mid 203.340609 -200.107403)
					(end 203.37653 -200.122282)
				)
				(arc
					(start 204.77607 -200.122282)
					(mid 204.811991 -200.107403)
					(end 204.82687 -200.071482)
				)
				(arc
					(start 204.82687 -199.662542)
					(mid 204.811991 -199.626621)
					(end 204.77607 -199.611742)
				)
				(arc
					(start 203.37653 -199.611742)
					(mid 203.340609 -199.626621)
					(end 203.32573 -199.662542)
				)
			)
		)
	)
	(zone
		(layers "In1.Cu" "In2.Cu")
		(hatch none 0.5)
		(connect_pads
			(clearance 0)
		)
		(min_thickness 0.25)
		(keepout
			(tracks not_allowed)
			(vias allowed)
			(pads allowed)
			(copperpour not_allowed)
			(footprints allowed)
		)
		(placement
			(enabled no)
			(sheetname "")
		)
		(fill yes
			(thermal_gap 0.5)
			(thermal_bridge_width 0.5)
			(island_removal_mode 0)
		)
		(polygon
			(pts
				(arc
					(start 259.430266 -293.571422)
					(mid 259.445145 -293.607343)
					(end 259.481066 -293.622222)
				)
				(arc
					(start 260.880606 -293.622222)
					(mid 260.916527 -293.607343)
					(end 260.931406 -293.571422)
				)
				(arc
					(start 260.931406 -293.162482)
					(mid 260.916527 -293.126561)
					(end 260.880606 -293.111682)
				)
				(arc
					(start 259.481066 -293.111682)
					(mid 259.445145 -293.126561)
					(end 259.430266 -293.162482)
				)
			)
		)
	)
	(zone
		(layers "In1.Cu" "In2.Cu")
		(hatch none 0.5)
		(connect_pads
			(clearance 0)
		)
		(min_thickness 0.25)
		(keepout
			(tracks not_allowed)
			(vias allowed)
			(pads allowed)
			(copperpour not_allowed)
			(footprints allowed)
		)
		(placement
			(enabled no)
			(sheetname "")
		)
		(fill yes
			(thermal_gap 0.5)
			(thermal_bridge_width 0.5)
			(island_removal_mode 0)
		)
		(polygon
			(pts
				(arc
					(start 440.278266 -222.171514)
					(mid 440.293145 -222.207435)
					(end 440.329066 -222.222314)
				)
				(arc
					(start 441.728606 -222.222314)
					(mid 441.764527 -222.207435)
					(end 441.779406 -222.171514)
				)
				(arc
					(start 441.779406 -221.762574)
					(mid 441.764527 -221.726653)
					(end 441.728606 -221.711774)
				)
				(arc
					(start 440.329066 -221.711774)
					(mid 440.293145 -221.726653)
					(end 440.278266 -221.762574)
				)
			)
		)
	)
	(zone
		(layers "In1.Cu" "In2.Cu")
		(hatch none 0.5)
		(connect_pads
			(clearance 0)
		)
		(min_thickness 0.25)
		(keepout
			(tracks not_allowed)
			(vias allowed)
			(pads allowed)
			(copperpour not_allowed)
			(footprints allowed)
		)
		(placement
			(enabled no)
			(sheetname "")
		)
		(fill yes
			(thermal_gap 0.5)
			(thermal_bridge_width 0.5)
			(island_removal_mode 0)
		)
		(polygon
			(pts
				(arc
					(start 289.605466 -211.121498)
					(mid 289.620345 -211.157419)
					(end 289.656266 -211.172298)
				)
				(arc
					(start 291.055806 -211.172298)
					(mid 291.091727 -211.157419)
					(end 291.106606 -211.121498)
				)
				(arc
					(start 291.106606 -210.712558)
					(mid 291.091727 -210.676637)
					(end 291.055806 -210.661758)
				)
				(arc
					(start 289.656266 -210.661758)
					(mid 289.620345 -210.676637)
					(end 289.605466 -210.712558)
				)
			)
		)
	)
	(zone
		(layers "In1.Cu" "In2.Cu")
		(hatch none 0.5)
		(connect_pads
			(clearance 0)
		)
		(min_thickness 0.25)
		(keepout
			(tracks not_allowed)
			(vias allowed)
			(pads allowed)
			(copperpour not_allowed)
			(footprints allowed)
		)
		(placement
			(enabled no)
			(sheetname "")
		)
		(fill yes
			(thermal_gap 0.5)
			(thermal_bridge_width 0.5)
			(island_removal_mode 0)
		)
		(polygon
			(pts
				(arc
					(start 277.961598 -232.371392)
					(mid 277.976477 -232.407313)
					(end 278.012398 -232.422192)
				)
				(arc
					(start 279.411938 -232.422192)
					(mid 279.447859 -232.407313)
					(end 279.462738 -232.371392)
				)
				(arc
					(start 279.462738 -231.962452)
					(mid 279.447859 -231.926531)
					(end 279.411938 -231.911652)
				)
				(arc
					(start 278.012398 -231.911652)
					(mid 277.976477 -231.926531)
					(end 277.961598 -231.962452)
				)
			)
		)
	)
	(zone
		(layers "In1.Cu" "In2.Cu")
		(hatch none 0.5)
		(connect_pads
			(clearance 0)
		)
		(min_thickness 0.25)
		(keepout
			(tracks not_allowed)
			(vias allowed)
			(pads allowed)
			(copperpour not_allowed)
			(footprints allowed)
		)
		(placement
			(enabled no)
			(sheetname "")
		)
		(fill yes
			(thermal_gap 0.5)
			(thermal_bridge_width 0.5)
			(island_removal_mode 0)
		)
		(polygon
			(pts
				(arc
					(start 277.961598 -198.37146)
					(mid 277.976477 -198.407381)
					(end 278.012398 -198.42226)
				)
				(arc
					(start 279.411938 -198.42226)
					(mid 279.447859 -198.407381)
					(end 279.462738 -198.37146)
				)
				(arc
					(start 279.462738 -197.96252)
					(mid 279.447859 -197.926599)
					(end 279.411938 -197.91172)
				)
				(arc
					(start 278.012398 -197.91172)
					(mid 277.976477 -197.926599)
					(end 277.961598 -197.96252)
				)
			)
		)
	)
	(zone
		(layers "In1.Cu" "In2.Cu")
		(hatch none 0.5)
		(connect_pads
			(clearance 0)
		)
		(min_thickness 0.25)
		(keepout
			(tracks not_allowed)
			(vias allowed)
			(pads allowed)
			(copperpour not_allowed)
			(footprints allowed)
		)
		(placement
			(enabled no)
			(sheetname "")
		)
		(fill yes
			(thermal_gap 0.5)
			(thermal_bridge_width 0.5)
			(island_removal_mode 0)
		)
		(polygon
			(pts
				(arc
					(start 169.706798 -214.521542)
					(mid 169.721677 -214.557463)
					(end 169.757598 -214.572342)
				)
				(arc
					(start 171.157138 -214.572342)
					(mid 171.193059 -214.557463)
					(end 171.207938 -214.521542)
				)
				(arc
					(start 171.207938 -214.112602)
					(mid 171.193059 -214.076681)
					(end 171.157138 -214.061802)
				)
				(arc
					(start 169.757598 -214.061802)
					(mid 169.721677 -214.076681)
					(end 169.706798 -214.112602)
				)
			)
		)
	)
	(zone
		(layers "In1.Cu" "In2.Cu")
		(hatch none 0.5)
		(connect_pads
			(clearance 0)
		)
		(min_thickness 0.25)
		(keepout
			(tracks not_allowed)
			(vias allowed)
			(pads allowed)
			(copperpour not_allowed)
			(footprints allowed)
		)
		(placement
			(enabled no)
			(sheetname "")
		)
		(fill yes
			(thermal_gap 0.5)
			(thermal_bridge_width 0.5)
			(island_removal_mode 0)
		)
		(polygon
			(pts
				(arc
					(start 19.033998 -229.821486)
					(mid 19.048877 -229.857407)
					(end 19.084798 -229.872286)
				)
				(arc
					(start 20.484338 -229.872286)
					(mid 20.520259 -229.857407)
					(end 20.535138 -229.821486)
				)
				(arc
					(start 20.535138 -229.412546)
					(mid 20.520259 -229.376625)
					(end 20.484338 -229.361746)
				)
				(arc
					(start 19.084798 -229.361746)
					(mid 19.048877 -229.376625)
					(end 19.033998 -229.412546)
				)
			)
		)
	)
	(zone
		(layers "In1.Cu" "In2.Cu")
		(hatch none 0.5)
		(connect_pads
			(clearance 0)
		)
		(min_thickness 0.25)
		(keepout
			(tracks not_allowed)
			(vias allowed)
			(pads allowed)
			(copperpour not_allowed)
			(footprints allowed)
		)
		(placement
			(enabled no)
			(sheetname "")
		)
		(fill yes
			(thermal_gap 0.5)
			(thermal_bridge_width 0.5)
			(island_removal_mode 0)
		)
		(polygon
			(pts
				(arc
					(start 184.794398 -225.571304)
					(mid 184.809277 -225.607225)
					(end 184.845198 -225.622104)
				)
				(arc
					(start 186.244738 -225.622104)
					(mid 186.280659 -225.607225)
					(end 186.295538 -225.571304)
				)
				(arc
					(start 186.295538 -225.162364)
					(mid 186.280659 -225.126443)
					(end 186.244738 -225.111564)
				)
				(arc
					(start 184.845198 -225.111564)
					(mid 184.809277 -225.126443)
					(end 184.794398 -225.162364)
				)
			)
		)
	)
	(zone
		(layers "In1.Cu" "In2.Cu")
		(hatch none 0.5)
		(connect_pads
			(clearance 0)
		)
		(min_thickness 0.25)
		(keepout
			(tracks not_allowed)
			(vias allowed)
			(pads allowed)
			(copperpour not_allowed)
			(footprints allowed)
		)
		(placement
			(enabled no)
			(sheetname "")
		)
		(fill yes
			(thermal_gap 0.5)
			(thermal_bridge_width 0.5)
			(island_removal_mode 0)
		)
		(polygon
			(pts
				(arc
					(start 60.19673 -269.771368)
					(mid 60.211609 -269.807289)
					(end 60.24753 -269.822168)
				)
				(arc
					(start 61.64707 -269.822168)
					(mid 61.682991 -269.807289)
					(end 61.69787 -269.771368)
				)
				(arc
					(start 61.69787 -269.362428)
					(mid 61.682991 -269.326507)
					(end 61.64707 -269.311628)
				)
				(arc
					(start 60.24753 -269.311628)
					(mid 60.211609 -269.326507)
					(end 60.19673 -269.362428)
				)
			)
		)
	)
	(zone
		(layers "In1.Cu" "In2.Cu")
		(hatch none 0.5)
		(connect_pads
			(clearance 0)
		)
		(min_thickness 0.25)
		(keepout
			(tracks not_allowed)
			(vias allowed)
			(pads allowed)
			(copperpour not_allowed)
			(footprints allowed)
		)
		(placement
			(enabled no)
			(sheetname "")
		)
		(fill yes
			(thermal_gap 0.5)
			(thermal_bridge_width 0.5)
			(island_removal_mode 0)
		)
		(polygon
			(pts
				(arc
					(start 300.592998 -316.521338)
					(mid 300.607877 -316.557259)
					(end 300.643798 -316.572138)
				)
				(arc
					(start 302.043338 -316.572138)
					(mid 302.079259 -316.557259)
					(end 302.094138 -316.521338)
				)
				(arc
					(start 302.094138 -316.112398)
					(mid 302.079259 -316.076477)
					(end 302.043338 -316.061598)
				)
				(arc
					(start 300.643798 -316.061598)
					(mid 300.607877 -316.076477)
					(end 300.592998 -316.112398)
				)
			)
		)
	)
	(zone
		(layers "In1.Cu" "In2.Cu")
		(hatch none 0.5)
		(connect_pads
			(clearance 0)
		)
		(min_thickness 0.25)
		(keepout
			(tracks not_allowed)
			(vias allowed)
			(pads allowed)
			(copperpour not_allowed)
			(footprints allowed)
		)
		(placement
			(enabled no)
			(sheetname "")
		)
		(fill yes
			(thermal_gap 0.5)
			(thermal_bridge_width 0.5)
			(island_removal_mode 0)
		)
		(polygon
			(pts
				(arc
					(start 421.090598 -271.47139)
					(mid 421.105477 -271.507311)
					(end 421.141398 -271.52219)
				)
				(arc
					(start 422.540938 -271.52219)
					(mid 422.576859 -271.507311)
					(end 422.591738 -271.47139)
				)
				(arc
					(start 422.591738 -271.06245)
					(mid 422.576859 -271.026529)
					(end 422.540938 -271.01165)
				)
				(arc
					(start 421.141398 -271.01165)
					(mid 421.105477 -271.026529)
					(end 421.090598 -271.06245)
				)
			)
		)
	)
	(zone
		(layers "In1.Cu" "In2.Cu")
		(hatch none 0.5)
		(connect_pads
			(clearance 0)
		)
		(min_thickness 0.25)
		(keepout
			(tracks not_allowed)
			(vias allowed)
			(pads allowed)
			(copperpour not_allowed)
			(footprints allowed)
		)
		(placement
			(enabled no)
			(sheetname "")
		)
		(fill yes
			(thermal_gap 0.5)
			(thermal_bridge_width 0.5)
			(island_removal_mode 0)
		)
		(polygon
			(pts
				(arc
					(start 413.546798 -210.27136)
					(mid 413.561677 -210.307281)
					(end 413.597598 -210.32216)
				)
				(arc
					(start 414.997138 -210.32216)
					(mid 415.033059 -210.307281)
					(end 415.047938 -210.27136)
				)
				(arc
					(start 415.047938 -209.86242)
					(mid 415.033059 -209.826499)
					(end 414.997138 -209.81162)
				)
				(arc
					(start 413.597598 -209.81162)
					(mid 413.561677 -209.826499)
					(end 413.546798 -209.86242)
				)
			)
		)
	)
	(zone
		(layers "In1.Cu" "In2.Cu")
		(hatch none 0.5)
		(connect_pads
			(clearance 0)
		)
		(min_thickness 0.25)
		(keepout
			(tracks not_allowed)
			(vias allowed)
			(pads allowed)
			(copperpour not_allowed)
			(footprints allowed)
		)
		(placement
			(enabled no)
			(sheetname "")
		)
		(fill yes
			(thermal_gap 0.5)
			(thermal_bridge_width 0.5)
			(island_removal_mode 0)
		)
		(polygon
			(pts
				(arc
					(start 162.162998 -197.521322)
					(mid 162.177877 -197.557243)
					(end 162.213798 -197.572122)
				)
				(arc
					(start 163.613338 -197.572122)
					(mid 163.649259 -197.557243)
					(end 163.664138 -197.521322)
				)
				(arc
					(start 163.664138 -197.112382)
					(mid 163.649259 -197.076461)
					(end 163.613338 -197.061582)
				)
				(arc
					(start 162.213798 -197.061582)
					(mid 162.177877 -197.076461)
					(end 162.162998 -197.112382)
				)
			)
		)
	)
	(zone
		(layers "In1.Cu" "In2.Cu")
		(hatch none 0.5)
		(connect_pads
			(clearance 0)
		)
		(min_thickness 0.25)
		(keepout
			(tracks not_allowed)
			(vias allowed)
			(pads allowed)
			(copperpour not_allowed)
			(footprints allowed)
		)
		(placement
			(enabled no)
			(sheetname "")
		)
		(fill yes
			(thermal_gap 0.5)
			(thermal_bridge_width 0.5)
			(island_removal_mode 0)
		)
		(polygon
			(pts
				(arc
					(start 417.646866 -298.671488)
					(mid 417.661745 -298.707409)
					(end 417.697666 -298.722288)
				)
				(arc
					(start 419.097206 -298.722288)
					(mid 419.133127 -298.707409)
					(end 419.148006 -298.671488)
				)
				(arc
					(start 419.148006 -298.262548)
					(mid 419.133127 -298.226627)
					(end 419.097206 -298.211748)
				)
				(arc
					(start 417.697666 -298.211748)
					(mid 417.661745 -298.226627)
					(end 417.646866 -298.262548)
				)
			)
		)
	)
	(zone
		(layers "In1.Cu" "In2.Cu")
		(hatch none 0.5)
		(connect_pads
			(clearance 0)
		)
		(min_thickness 0.25)
		(keepout
			(tracks not_allowed)
			(vias allowed)
			(pads allowed)
			(copperpour not_allowed)
			(footprints allowed)
		)
		(placement
			(enabled no)
			(sheetname "")
		)
		(fill yes
			(thermal_gap 0.5)
			(thermal_bridge_width 0.5)
			(island_removal_mode 0)
		)
		(polygon
			(pts
				(arc
					(start 195.78193 -237.471458)
					(mid 195.796809 -237.507379)
					(end 195.83273 -237.522258)
				)
				(arc
					(start 197.23227 -237.522258)
					(mid 197.268191 -237.507379)
					(end 197.28307 -237.471458)
				)
				(arc
					(start 197.28307 -237.062518)
					(mid 197.268191 -237.026597)
					(end 197.23227 -237.011718)
				)
				(arc
					(start 195.83273 -237.011718)
					(mid 195.796809 -237.026597)
					(end 195.78193 -237.062518)
				)
			)
		)
	)
	(zone
		(layers "In1.Cu" "In2.Cu")
		(hatch none 0.5)
		(connect_pads
			(clearance 0)
		)
		(min_thickness 0.25)
		(keepout
			(tracks not_allowed)
			(vias allowed)
			(pads allowed)
			(copperpour not_allowed)
			(footprints allowed)
		)
		(placement
			(enabled no)
			(sheetname "")
		)
		(fill yes
			(thermal_gap 0.5)
			(thermal_bridge_width 0.5)
			(island_removal_mode 0)
		)
		(polygon
			(pts
				(arc
					(start 45.10913 -210.27136)
					(mid 45.124009 -210.307281)
					(end 45.15993 -210.32216)
				)
				(arc
					(start 46.55947 -210.32216)
					(mid 46.595391 -210.307281)
					(end 46.61027 -210.27136)
				)
				(arc
					(start 46.61027 -209.86242)
					(mid 46.595391 -209.826499)
					(end 46.55947 -209.81162)
				)
				(arc
					(start 45.15993 -209.81162)
					(mid 45.124009 -209.826499)
					(end 45.10913 -209.86242)
				)
			)
		)
	)
	(zone
		(layers "In1.Cu" "In2.Cu")
		(hatch none 0.5)
		(connect_pads
			(clearance 0)
		)
		(min_thickness 0.25)
		(keepout
			(tracks not_allowed)
			(vias allowed)
			(pads allowed)
			(copperpour not_allowed)
			(footprints allowed)
		)
		(placement
			(enabled no)
			(sheetname "")
		)
		(fill yes
			(thermal_gap 0.5)
			(thermal_bridge_width 0.5)
			(island_removal_mode 0)
		)
		(polygon
			(pts
				(arc
					(start 413.546798 -241.721386)
					(mid 413.561677 -241.757307)
					(end 413.597598 -241.772186)
				)
				(arc
					(start 414.997138 -241.772186)
					(mid 415.033059 -241.757307)
					(end 415.047938 -241.721386)
				)
				(arc
					(start 415.047938 -241.312446)
					(mid 415.033059 -241.276525)
					(end 414.997138 -241.261646)
				)
				(arc
					(start 413.597598 -241.261646)
					(mid 413.561677 -241.276525)
					(end 413.546798 -241.312446)
				)
			)
		)
	)
	(zone
		(layers "In1.Cu" "In2.Cu")
		(hatch none 0.5)
		(connect_pads
			(clearance 0)
		)
		(min_thickness 0.25)
		(keepout
			(tracks not_allowed)
			(vias allowed)
			(pads allowed)
			(copperpour not_allowed)
			(footprints allowed)
		)
		(placement
			(enabled no)
			(sheetname "")
		)
		(fill yes
			(thermal_gap 0.5)
			(thermal_bridge_width 0.5)
			(island_removal_mode 0)
		)
		(polygon
			(pts
				(arc
					(start 297.149266 -237.471458)
					(mid 297.164145 -237.507379)
					(end 297.200066 -237.522258)
				)
				(arc
					(start 298.599606 -237.522258)
					(mid 298.635527 -237.507379)
					(end 298.650406 -237.471458)
				)
				(arc
					(start 298.650406 -237.062518)
					(mid 298.635527 -237.026597)
					(end 298.599606 -237.011718)
				)
				(arc
					(start 297.200066 -237.011718)
					(mid 297.164145 -237.026597)
					(end 297.149266 -237.062518)
				)
			)
		)
	)
	(zone
		(layers "In1.Cu" "In2.Cu")
		(hatch none 0.5)
		(connect_pads
			(clearance 0)
		)
		(min_thickness 0.25)
		(keepout
			(tracks not_allowed)
			(vias allowed)
			(pads allowed)
			(copperpour not_allowed)
			(footprints allowed)
		)
		(placement
			(enabled no)
			(sheetname "")
		)
		(fill yes
			(thermal_gap 0.5)
			(thermal_bridge_width 0.5)
			(island_removal_mode 0)
		)
		(polygon
			(pts
				(arc
					(start 436.178198 -312.27141)
					(mid 436.193077 -312.307331)
					(end 436.228998 -312.32221)
				)
				(arc
					(start 437.628538 -312.32221)
					(mid 437.664459 -312.307331)
					(end 437.679338 -312.27141)
				)
				(arc
					(start 437.679338 -311.86247)
					(mid 437.664459 -311.826549)
					(end 437.628538 -311.81167)
				)
				(arc
					(start 436.228998 -311.81167)
					(mid 436.193077 -311.826549)
					(end 436.178198 -311.86247)
				)
			)
		)
	)
	(zone
		(layers "In1.Cu" "In2.Cu")
		(hatch none 0.5)
		(connect_pads
			(clearance 0)
		)
		(min_thickness 0.25)
		(keepout
			(tracks not_allowed)
			(vias allowed)
			(pads allowed)
			(copperpour not_allowed)
			(footprints allowed)
		)
		(placement
			(enabled no)
			(sheetname "")
		)
		(fill yes
			(thermal_gap 0.5)
			(thermal_bridge_width 0.5)
			(island_removal_mode 0)
		)
		(polygon
			(pts
				(arc
					(start 177.250598 -300.37151)
					(mid 177.265477 -300.407431)
					(end 177.301398 -300.42231)
				)
				(arc
					(start 178.700938 -300.42231)
					(mid 178.736859 -300.407431)
					(end 178.751738 -300.37151)
				)
				(arc
					(start 178.751738 -299.96257)
					(mid 178.736859 -299.926649)
					(end 178.700938 -299.91177)
				)
				(arc
					(start 177.301398 -299.91177)
					(mid 177.265477 -299.926649)
					(end 177.250598 -299.96257)
				)
			)
		)
	)
	(zone
		(layers "In1.Cu" "In2.Cu")
		(hatch none 0.5)
		(connect_pads
			(clearance 0)
		)
		(min_thickness 0.25)
		(keepout
			(tracks not_allowed)
			(vias allowed)
			(pads allowed)
			(copperpour not_allowed)
			(footprints allowed)
		)
		(placement
			(enabled no)
			(sheetname "")
		)
		(fill yes
			(thermal_gap 0.5)
			(thermal_bridge_width 0.5)
			(island_removal_mode 0)
		)
		(polygon
			(pts
				(arc
					(start 451.265798 -247.671336)
					(mid 451.280677 -247.707257)
					(end 451.316598 -247.722136)
				)
				(arc
					(start 452.716138 -247.722136)
					(mid 452.752059 -247.707257)
					(end 452.766938 -247.671336)
				)
				(arc
					(start 452.766938 -247.262396)
					(mid 452.752059 -247.226475)
					(end 452.716138 -247.211596)
				)
				(arc
					(start 451.316598 -247.211596)
					(mid 451.280677 -247.226475)
					(end 451.265798 -247.262396)
				)
			)
		)
	)
	(zone
		(layers "In1.Cu" "In2.Cu")
		(hatch none 0.5)
		(connect_pads
			(clearance 0)
		)
		(min_thickness 0.25)
		(keepout
			(tracks not_allowed)
			(vias allowed)
			(pads allowed)
			(copperpour not_allowed)
			(footprints allowed)
		)
		(placement
			(enabled no)
			(sheetname "")
		)
		(fill yes
			(thermal_gap 0.5)
			(thermal_bridge_width 0.5)
			(island_removal_mode 0)
		)
		(polygon
			(pts
				(arc
					(start 266.974066 -308.021482)
					(mid 266.988945 -308.057403)
					(end 267.024866 -308.072282)
				)
				(arc
					(start 268.424406 -308.072282)
					(mid 268.460327 -308.057403)
					(end 268.475206 -308.021482)
				)
				(arc
					(start 268.475206 -307.612542)
					(mid 268.460327 -307.576621)
					(end 268.424406 -307.561742)
				)
				(arc
					(start 267.024866 -307.561742)
					(mid 266.988945 -307.576621)
					(end 266.974066 -307.612542)
				)
			)
		)
	)
	(zone
		(layers "In1.Cu" "In2.Cu")
		(hatch none 0.5)
		(connect_pads
			(clearance 0)
		)
		(min_thickness 0.25)
		(keepout
			(tracks not_allowed)
			(vias allowed)
			(pads allowed)
			(copperpour not_allowed)
			(footprints allowed)
		)
		(placement
			(enabled no)
			(sheetname "")
		)
		(fill yes
			(thermal_gap 0.5)
			(thermal_bridge_width 0.5)
			(island_removal_mode 0)
		)
		(polygon
			(pts
				(arc
					(start 285.505398 -244.271292)
					(mid 285.520277 -244.307213)
					(end 285.556198 -244.322092)
				)
				(arc
					(start 286.955738 -244.322092)
					(mid 286.991659 -244.307213)
					(end 287.006538 -244.271292)
				)
				(arc
					(start 287.006538 -243.862352)
					(mid 286.991659 -243.826431)
					(end 286.955738 -243.811552)
				)
				(arc
					(start 285.556198 -243.811552)
					(mid 285.520277 -243.826431)
					(end 285.505398 -243.862352)
				)
			)
		)
	)
	(zone
		(layers "In1.Cu" "In2.Cu")
		(hatch none 0.5)
		(connect_pads
			(clearance 0)
		)
		(min_thickness 0.25)
		(keepout
			(tracks not_allowed)
			(vias allowed)
			(pads allowed)
			(copperpour not_allowed)
			(footprints allowed)
		)
		(placement
			(enabled no)
			(sheetname "")
		)
		(fill yes
			(thermal_gap 0.5)
			(thermal_bridge_width 0.5)
			(island_removal_mode 0)
		)
		(polygon
			(pts
				(arc
					(start 285.505398 -200.921366)
					(mid 285.520277 -200.957287)
					(end 285.556198 -200.972166)
				)
				(arc
					(start 286.955738 -200.972166)
					(mid 286.991659 -200.957287)
					(end 287.006538 -200.921366)
				)
				(arc
					(start 287.006538 -200.512426)
					(mid 286.991659 -200.476505)
					(end 286.955738 -200.461626)
				)
				(arc
					(start 285.556198 -200.461626)
					(mid 285.520277 -200.476505)
					(end 285.505398 -200.512426)
				)
			)
		)
	)
	(zone
		(layers "In1.Cu" "In2.Cu")
		(hatch none 0.5)
		(connect_pads
			(clearance 0)
		)
		(min_thickness 0.25)
		(keepout
			(tracks not_allowed)
			(vias allowed)
			(pads allowed)
			(copperpour not_allowed)
			(footprints allowed)
		)
		(placement
			(enabled no)
			(sheetname "")
		)
		(fill yes
			(thermal_gap 0.5)
			(thermal_bridge_width 0.5)
			(island_removal_mode 0)
		)
		(polygon
			(pts
				(arc
					(start 19.033998 -276.571456)
					(mid 19.048877 -276.607377)
					(end 19.084798 -276.622256)
				)
				(arc
					(start 20.484338 -276.622256)
					(mid 20.520259 -276.607377)
					(end 20.535138 -276.571456)
				)
				(arc
					(start 20.535138 -276.162516)
					(mid 20.520259 -276.126595)
					(end 20.484338 -276.111716)
				)
				(arc
					(start 19.084798 -276.111716)
					(mid 19.048877 -276.126595)
					(end 19.033998 -276.162516)
				)
			)
		)
	)
	(zone
		(layers "In1.Cu" "In2.Cu")
		(hatch none 0.5)
		(connect_pads
			(clearance 0)
		)
		(min_thickness 0.25)
		(keepout
			(tracks not_allowed)
			(vias allowed)
			(pads allowed)
			(copperpour not_allowed)
			(footprints allowed)
		)
		(placement
			(enabled no)
			(sheetname "")
		)
		(fill yes
			(thermal_gap 0.5)
			(thermal_bridge_width 0.5)
			(island_removal_mode 0)
		)
		(polygon
			(pts
				(arc
					(start 277.961598 -240.021364)
					(mid 277.976477 -240.057285)
					(end 278.012398 -240.072164)
				)
				(arc
					(start 279.411938 -240.072164)
					(mid 279.447859 -240.057285)
					(end 279.462738 -240.021364)
				)
				(arc
					(start 279.462738 -239.612424)
					(mid 279.447859 -239.576503)
					(end 279.411938 -239.561624)
				)
				(arc
					(start 278.012398 -239.561624)
					(mid 277.976477 -239.576503)
					(end 277.961598 -239.612424)
				)
			)
		)
	)
	(zone
		(layers "In1.Cu" "In2.Cu")
		(hatch none 0.5)
		(connect_pads
			(clearance 0)
		)
		(min_thickness 0.25)
		(keepout
			(tracks not_allowed)
			(vias allowed)
			(pads allowed)
			(copperpour not_allowed)
			(footprints allowed)
		)
		(placement
			(enabled no)
			(sheetname "")
		)
		(fill yes
			(thermal_gap 0.5)
			(thermal_bridge_width 0.5)
			(island_removal_mode 0)
		)
		(polygon
			(pts
				(arc
					(start 192.338198 -312.27141)
					(mid 192.353077 -312.307331)
					(end 192.388998 -312.32221)
				)
				(arc
					(start 193.788538 -312.32221)
					(mid 193.824459 -312.307331)
					(end 193.839338 -312.27141)
				)
				(arc
					(start 193.839338 -311.86247)
					(mid 193.824459 -311.826549)
					(end 193.788538 -311.81167)
				)
				(arc
					(start 192.388998 -311.81167)
					(mid 192.353077 -311.826549)
					(end 192.338198 -311.86247)
				)
			)
		)
	)
	(zone
		(layers "In1.Cu" "In2.Cu")
		(hatch none 0.5)
		(connect_pads
			(clearance 0)
		)
		(min_thickness 0.25)
		(keepout
			(tracks not_allowed)
			(vias allowed)
			(pads allowed)
			(copperpour not_allowed)
			(footprints allowed)
		)
		(placement
			(enabled no)
			(sheetname "")
		)
		(fill yes
			(thermal_gap 0.5)
			(thermal_bridge_width 0.5)
			(island_removal_mode 0)
		)
		(polygon
			(pts
				(arc
					(start 56.752998 -263.821418)
					(mid 56.767877 -263.857339)
					(end 56.803798 -263.872218)
				)
				(arc
					(start 58.203338 -263.872218)
					(mid 58.239259 -263.857339)
					(end 58.254138 -263.821418)
				)
				(arc
					(start 58.254138 -263.412478)
					(mid 58.239259 -263.376557)
					(end 58.203338 -263.361678)
				)
				(arc
					(start 56.803798 -263.361678)
					(mid 56.767877 -263.376557)
					(end 56.752998 -263.412478)
				)
			)
		)
	)
	(zone
		(layers "In1.Cu" "In2.Cu")
		(hatch none 0.5)
		(connect_pads
			(clearance 0)
		)
		(min_thickness 0.25)
		(keepout
			(tracks not_allowed)
			(vias allowed)
			(pads allowed)
			(copperpour not_allowed)
			(footprints allowed)
		)
		(placement
			(enabled no)
			(sheetname "")
		)
		(fill yes
			(thermal_gap 0.5)
			(thermal_bridge_width 0.5)
			(island_removal_mode 0)
		)
		(polygon
			(pts
				(arc
					(start 410.103066 -211.121498)
					(mid 410.117945 -211.157419)
					(end 410.153866 -211.172298)
				)
				(arc
					(start 411.553406 -211.172298)
					(mid 411.589327 -211.157419)
					(end 411.604206 -211.121498)
				)
				(arc
					(start 411.604206 -210.712558)
					(mid 411.589327 -210.676637)
					(end 411.553406 -210.661758)
				)
				(arc
					(start 410.153866 -210.661758)
					(mid 410.117945 -210.676637)
					(end 410.103066 -210.712558)
				)
			)
		)
	)
	(zone
		(layers "In1.Cu" "In2.Cu")
		(hatch none 0.5)
		(connect_pads
			(clearance 0)
		)
		(min_thickness 0.25)
		(keepout
			(tracks not_allowed)
			(vias allowed)
			(pads allowed)
			(copperpour not_allowed)
			(footprints allowed)
		)
		(placement
			(enabled no)
			(sheetname "")
		)
		(fill yes
			(thermal_gap 0.5)
			(thermal_bridge_width 0.5)
			(island_removal_mode 0)
		)
		(polygon
			(pts
				(arc
					(start 417.646866 -240.871502)
					(mid 417.661745 -240.907423)
					(end 417.697666 -240.922302)
				)
				(arc
					(start 419.097206 -240.922302)
					(mid 419.133127 -240.907423)
					(end 419.148006 -240.871502)
				)
				(arc
					(start 419.148006 -240.462562)
					(mid 419.133127 -240.426641)
					(end 419.097206 -240.411762)
				)
				(arc
					(start 417.697666 -240.411762)
					(mid 417.661745 -240.426641)
					(end 417.646866 -240.462562)
				)
			)
		)
	)
	(zone
		(layers "In1.Cu" "In2.Cu")
		(hatch none 0.5)
		(connect_pads
			(clearance 0)
		)
		(min_thickness 0.25)
		(keepout
			(tracks not_allowed)
			(vias allowed)
			(pads allowed)
			(copperpour not_allowed)
			(footprints allowed)
		)
		(placement
			(enabled no)
			(sheetname "")
		)
		(fill yes
			(thermal_gap 0.5)
			(thermal_bridge_width 0.5)
			(island_removal_mode 0)
		)
		(polygon
			(pts
				(arc
					(start 49.209198 -302.921416)
					(mid 49.224077 -302.957337)
					(end 49.259998 -302.972216)
				)
				(arc
					(start 50.659538 -302.972216)
					(mid 50.695459 -302.957337)
					(end 50.710338 -302.921416)
				)
				(arc
					(start 50.710338 -302.512476)
					(mid 50.695459 -302.476555)
					(end 50.659538 -302.461676)
				)
				(arc
					(start 49.259998 -302.461676)
					(mid 49.224077 -302.476555)
					(end 49.209198 -302.512476)
				)
			)
		)
	)
	(zone
		(layers "In1.Cu" "In2.Cu")
		(hatch none 0.5)
		(connect_pads
			(clearance 0)
		)
		(min_thickness 0.25)
		(keepout
			(tracks not_allowed)
			(vias allowed)
			(pads allowed)
			(copperpour not_allowed)
			(footprints allowed)
		)
		(placement
			(enabled no)
			(sheetname "")
		)
		(fill yes
			(thermal_gap 0.5)
			(thermal_bridge_width 0.5)
			(island_removal_mode 0)
		)
		(polygon
			(pts
				(arc
					(start 52.65293 -228.121464)
					(mid 52.667809 -228.157385)
					(end 52.70373 -228.172264)
				)
				(arc
					(start 54.10327 -228.172264)
					(mid 54.139191 -228.157385)
					(end 54.15407 -228.121464)
				)
				(arc
					(start 54.15407 -227.712524)
					(mid 54.139191 -227.676603)
					(end 54.10327 -227.661724)
				)
				(arc
					(start 52.70373 -227.661724)
					(mid 52.667809 -227.676603)
					(end 52.65293 -227.712524)
				)
			)
		)
	)
	(zone
		(layers "In1.Cu" "In2.Cu")
		(hatch none 0.5)
		(connect_pads
			(clearance 0)
		)
		(min_thickness 0.25)
		(keepout
			(tracks not_allowed)
			(vias allowed)
			(pads allowed)
			(copperpour not_allowed)
			(footprints allowed)
		)
		(placement
			(enabled no)
			(sheetname "")
		)
		(fill yes
			(thermal_gap 0.5)
			(thermal_bridge_width 0.5)
			(island_removal_mode 0)
		)
		(polygon
			(pts
				(arc
					(start 432.734466 -200.071482)
					(mid 432.749345 -200.107403)
					(end 432.785266 -200.122282)
				)
				(arc
					(start 434.184806 -200.122282)
					(mid 434.220727 -200.107403)
					(end 434.235606 -200.071482)
				)
				(arc
					(start 434.235606 -199.662542)
					(mid 434.220727 -199.626621)
					(end 434.184806 -199.611742)
				)
				(arc
					(start 432.785266 -199.611742)
					(mid 432.749345 -199.626621)
					(end 432.734466 -199.662542)
				)
			)
		)
	)
	(zone
		(layers "In1.Cu" "In2.Cu")
		(hatch none 0.5)
		(connect_pads
			(clearance 0)
		)
		(min_thickness 0.25)
		(keepout
			(tracks not_allowed)
			(vias allowed)
			(pads allowed)
			(copperpour not_allowed)
			(footprints allowed)
		)
		(placement
			(enabled no)
			(sheetname "")
		)
		(fill yes
			(thermal_gap 0.5)
			(thermal_bridge_width 0.5)
			(island_removal_mode 0)
		)
		(polygon
			(pts
				(arc
					(start 207.425798 -313.971432)
					(mid 207.440677 -314.007353)
					(end 207.476598 -314.022232)
				)
				(arc
					(start 208.876138 -314.022232)
					(mid 208.912059 -314.007353)
					(end 208.926938 -313.971432)
				)
				(arc
					(start 208.926938 -313.562492)
					(mid 208.912059 -313.526571)
					(end 208.876138 -313.511692)
				)
				(arc
					(start 207.476598 -313.511692)
					(mid 207.440677 -313.526571)
					(end 207.425798 -313.562492)
				)
			)
		)
	)
	(zone
		(layers "In1.Cu" "In2.Cu")
		(hatch none 0.5)
		(connect_pads
			(clearance 0)
		)
		(min_thickness 0.25)
		(keepout
			(tracks not_allowed)
			(vias allowed)
			(pads allowed)
			(copperpour not_allowed)
			(footprints allowed)
		)
		(placement
			(enabled no)
			(sheetname "")
		)
		(fill yes
			(thermal_gap 0.5)
			(thermal_bridge_width 0.5)
			(island_removal_mode 0)
		)
		(polygon
			(pts
				(arc
					(start 41.665398 -205.171548)
					(mid 41.680277 -205.207469)
					(end 41.716198 -205.222348)
				)
				(arc
					(start 43.115738 -205.222348)
					(mid 43.151659 -205.207469)
					(end 43.166538 -205.171548)
				)
				(arc
					(start 43.166538 -204.762608)
					(mid 43.151659 -204.726687)
					(end 43.115738 -204.711808)
				)
				(arc
					(start 41.716198 -204.711808)
					(mid 41.680277 -204.726687)
					(end 41.665398 -204.762608)
				)
			)
		)
	)
	(zone
		(layers "In1.Cu" "In2.Cu")
		(hatch none 0.5)
		(connect_pads
			(clearance 0)
		)
		(min_thickness 0.25)
		(keepout
			(tracks not_allowed)
			(vias allowed)
			(pads allowed)
			(copperpour not_allowed)
			(footprints allowed)
		)
		(placement
			(enabled no)
			(sheetname "")
		)
		(fill yes
			(thermal_gap 0.5)
			(thermal_bridge_width 0.5)
			(island_removal_mode 0)
		)
		(polygon
			(pts
				(arc
					(start 188.23813 -299.521372)
					(mid 188.253009 -299.557293)
					(end 188.28893 -299.572172)
				)
				(arc
					(start 189.68847 -299.572172)
					(mid 189.724391 -299.557293)
					(end 189.73927 -299.521372)
				)
				(arc
					(start 189.73927 -299.112432)
					(mid 189.724391 -299.076511)
					(end 189.68847 -299.061632)
				)
				(arc
					(start 188.28893 -299.061632)
					(mid 188.253009 -299.076511)
					(end 188.23813 -299.112432)
				)
			)
		)
	)
	(zone
		(layers "In1.Cu" "In2.Cu")
		(hatch none 0.5)
		(connect_pads
			(clearance 0)
		)
		(min_thickness 0.25)
		(keepout
			(tracks not_allowed)
			(vias allowed)
			(pads allowed)
			(copperpour not_allowed)
			(footprints allowed)
		)
		(placement
			(enabled no)
			(sheetname "")
		)
		(fill yes
			(thermal_gap 0.5)
			(thermal_bridge_width 0.5)
			(island_removal_mode 0)
		)
		(polygon
			(pts
				(arc
					(start 26.577798 -237.471458)
					(mid 26.592677 -237.507379)
					(end 26.628598 -237.522258)
				)
				(arc
					(start 28.028138 -237.522258)
					(mid 28.064059 -237.507379)
					(end 28.078938 -237.471458)
				)
				(arc
					(start 28.078938 -237.062518)
					(mid 28.064059 -237.026597)
					(end 28.028138 -237.011718)
				)
				(arc
					(start 26.628598 -237.011718)
					(mid 26.592677 -237.026597)
					(end 26.577798 -237.062518)
				)
			)
		)
	)
	(zone
		(layers "In1.Cu" "In2.Cu")
		(hatch none 0.5)
		(connect_pads
			(clearance 0)
		)
		(min_thickness 0.25)
		(keepout
			(tracks not_allowed)
			(vias allowed)
			(pads allowed)
			(copperpour not_allowed)
			(footprints allowed)
		)
		(placement
			(enabled no)
			(sheetname "")
		)
		(fill yes
			(thermal_gap 0.5)
			(thermal_bridge_width 0.5)
			(island_removal_mode 0)
		)
		(polygon
			(pts
				(arc
					(start 425.190666 -312.27141)
					(mid 425.205545 -312.307331)
					(end 425.241466 -312.32221)
				)
				(arc
					(start 426.641006 -312.32221)
					(mid 426.676927 -312.307331)
					(end 426.691806 -312.27141)
				)
				(arc
					(start 426.691806 -311.86247)
					(mid 426.676927 -311.826549)
					(end 426.641006 -311.81167)
				)
				(arc
					(start 425.241466 -311.81167)
					(mid 425.205545 -311.826549)
					(end 425.190666 -311.86247)
				)
			)
		)
	)
	(zone
		(layers "In1.Cu" "In2.Cu")
		(hatch none 0.5)
		(connect_pads
			(clearance 0)
		)
		(min_thickness 0.25)
		(keepout
			(tracks not_allowed)
			(vias allowed)
			(pads allowed)
			(copperpour not_allowed)
			(footprints allowed)
		)
		(placement
			(enabled no)
			(sheetname "")
		)
		(fill yes
			(thermal_gap 0.5)
			(thermal_bridge_width 0.5)
			(island_removal_mode 0)
		)
		(polygon
			(pts
				(arc
					(start 45.10913 -308.871366)
					(mid 45.124009 -308.907287)
					(end 45.15993 -308.922166)
				)
				(arc
					(start 46.55947 -308.922166)
					(mid 46.595391 -308.907287)
					(end 46.61027 -308.871366)
				)
				(arc
					(start 46.61027 -308.462426)
					(mid 46.595391 -308.426505)
					(end 46.55947 -308.411626)
				)
				(arc
					(start 45.15993 -308.411626)
					(mid 45.124009 -308.426505)
					(end 45.10913 -308.462426)
				)
			)
		)
	)
	(zone
		(layers "In1.Cu" "In2.Cu")
		(hatch none 0.5)
		(connect_pads
			(clearance 0)
		)
		(min_thickness 0.25)
		(keepout
			(tracks not_allowed)
			(vias allowed)
			(pads allowed)
			(copperpour not_allowed)
			(footprints allowed)
		)
		(placement
			(enabled no)
			(sheetname "")
		)
		(fill yes
			(thermal_gap 0.5)
			(thermal_bridge_width 0.5)
			(island_removal_mode 0)
		)
		(polygon
			(pts
				(arc
					(start 64.296798 -270.621506)
					(mid 64.311677 -270.657427)
					(end 64.347598 -270.672306)
				)
				(arc
					(start 65.747138 -270.672306)
					(mid 65.783059 -270.657427)
					(end 65.797938 -270.621506)
				)
				(arc
					(start 65.797938 -270.212566)
					(mid 65.783059 -270.176645)
					(end 65.747138 -270.161766)
				)
				(arc
					(start 64.347598 -270.161766)
					(mid 64.311677 -270.176645)
					(end 64.296798 -270.212566)
				)
			)
		)
	)
	(zone
		(layers "In1.Cu" "In2.Cu")
		(hatch none 0.5)
		(connect_pads
			(clearance 0)
		)
		(min_thickness 0.25)
		(keepout
			(tracks not_allowed)
			(vias allowed)
			(pads allowed)
			(copperpour not_allowed)
			(footprints allowed)
		)
		(placement
			(enabled no)
			(sheetname "")
		)
		(fill yes
			(thermal_gap 0.5)
			(thermal_bridge_width 0.5)
			(island_removal_mode 0)
		)
		(polygon
			(pts
				(arc
					(start 184.794398 -293.571422)
					(mid 184.809277 -293.607343)
					(end 184.845198 -293.622222)
				)
				(arc
					(start 186.244738 -293.622222)
					(mid 186.280659 -293.607343)
					(end 186.295538 -293.571422)
				)
				(arc
					(start 186.295538 -293.162482)
					(mid 186.280659 -293.126561)
					(end 186.244738 -293.111682)
				)
				(arc
					(start 184.845198 -293.111682)
					(mid 184.809277 -293.126561)
					(end 184.794398 -293.162482)
				)
			)
		)
	)
	(zone
		(layers "In1.Cu" "In2.Cu")
		(hatch none 0.5)
		(connect_pads
			(clearance 0)
		)
		(min_thickness 0.25)
		(keepout
			(tracks not_allowed)
			(vias allowed)
			(pads allowed)
			(copperpour not_allowed)
			(footprints allowed)
		)
		(placement
			(enabled no)
			(sheetname "")
		)
		(fill yes
			(thermal_gap 0.5)
			(thermal_bridge_width 0.5)
			(island_removal_mode 0)
		)
		(polygon
			(pts
				(arc
					(start 199.881998 -283.371544)
					(mid 199.896877 -283.407465)
					(end 199.932798 -283.422344)
				)
				(arc
					(start 201.332338 -283.422344)
					(mid 201.368259 -283.407465)
					(end 201.383138 -283.371544)
				)
				(arc
					(start 201.383138 -282.962604)
					(mid 201.368259 -282.926683)
					(end 201.332338 -282.911804)
				)
				(arc
					(start 199.932798 -282.911804)
					(mid 199.896877 -282.926683)
					(end 199.881998 -282.962604)
				)
			)
		)
	)
	(zone
		(layers "In1.Cu" "In2.Cu")
		(hatch none 0.5)
		(connect_pads
			(clearance 0)
		)
		(min_thickness 0.25)
		(keepout
			(tracks not_allowed)
			(vias allowed)
			(pads allowed)
			(copperpour not_allowed)
			(footprints allowed)
		)
		(placement
			(enabled no)
			(sheetname "")
		)
		(fill yes
			(thermal_gap 0.5)
			(thermal_bridge_width 0.5)
			(island_removal_mode 0)
		)
		(polygon
			(pts
				(arc
					(start 165.60673 -249.371358)
					(mid 165.621609 -249.407279)
					(end 165.65753 -249.422158)
				)
				(arc
					(start 167.05707 -249.422158)
					(mid 167.092991 -249.407279)
					(end 167.10787 -249.371358)
				)
				(arc
					(start 167.10787 -248.962418)
					(mid 167.092991 -248.926497)
					(end 167.05707 -248.911618)
				)
				(arc
					(start 165.65753 -248.911618)
					(mid 165.621609 -248.926497)
					(end 165.60673 -248.962418)
				)
			)
		)
	)
	(zone
		(layers "In1.Cu" "In2.Cu")
		(hatch none 0.5)
		(connect_pads
			(clearance 0)
		)
		(min_thickness 0.25)
		(keepout
			(tracks not_allowed)
			(vias allowed)
			(pads allowed)
			(copperpour not_allowed)
			(footprints allowed)
		)
		(placement
			(enabled no)
			(sheetname "")
		)
		(fill yes
			(thermal_gap 0.5)
			(thermal_bridge_width 0.5)
			(island_removal_mode 0)
		)
		(polygon
			(pts
				(arc
					(start 312.236866 -222.171514)
					(mid 312.251745 -222.207435)
					(end 312.287666 -222.222314)
				)
				(arc
					(start 313.687206 -222.222314)
					(mid 313.723127 -222.207435)
					(end 313.738006 -222.171514)
				)
				(arc
					(start 313.738006 -221.762574)
					(mid 313.723127 -221.726653)
					(end 313.687206 -221.711774)
				)
				(arc
					(start 312.287666 -221.711774)
					(mid 312.251745 -221.726653)
					(end 312.236866 -221.762574)
				)
			)
		)
	)
	(zone
		(layers "In1.Cu" "In2.Cu")
		(hatch none 0.5)
		(connect_pads
			(clearance 0)
		)
		(min_thickness 0.25)
		(keepout
			(tracks not_allowed)
			(vias allowed)
			(pads allowed)
			(copperpour not_allowed)
			(footprints allowed)
		)
		(placement
			(enabled no)
			(sheetname "")
		)
		(fill yes
			(thermal_gap 0.5)
			(thermal_bridge_width 0.5)
			(island_removal_mode 0)
		)
		(polygon
			(pts
				(arc
					(start 203.32573 -259.57149)
					(mid 203.340609 -259.607411)
					(end 203.37653 -259.62229)
				)
				(arc
					(start 204.77607 -259.62229)
					(mid 204.811991 -259.607411)
					(end 204.82687 -259.57149)
				)
				(arc
					(start 204.82687 -259.16255)
					(mid 204.811991 -259.126629)
					(end 204.77607 -259.11175)
				)
				(arc
					(start 203.37653 -259.11175)
					(mid 203.340609 -259.126629)
					(end 203.32573 -259.16255)
				)
			)
		)
	)
	(zone
		(layers "In1.Cu" "In2.Cu")
		(hatch none 0.5)
		(connect_pads
			(clearance 0)
		)
		(min_thickness 0.25)
		(keepout
			(tracks not_allowed)
			(vias allowed)
			(pads allowed)
			(copperpour not_allowed)
			(footprints allowed)
		)
		(placement
			(enabled no)
			(sheetname "")
		)
		(fill yes
			(thermal_gap 0.5)
			(thermal_bridge_width 0.5)
			(island_removal_mode 0)
		)
		(polygon
			(pts
				(arc
					(start 417.646866 -211.121498)
					(mid 417.661745 -211.157419)
					(end 417.697666 -211.172298)
				)
				(arc
					(start 419.097206 -211.172298)
					(mid 419.133127 -211.157419)
					(end 419.148006 -211.121498)
				)
				(arc
					(start 419.148006 -210.712558)
					(mid 419.133127 -210.676637)
					(end 419.097206 -210.661758)
				)
				(arc
					(start 417.697666 -210.661758)
					(mid 417.661745 -210.676637)
					(end 417.646866 -210.712558)
				)
			)
		)
	)
	(zone
		(layers "In1.Cu" "In2.Cu")
		(hatch none 0.5)
		(connect_pads
			(clearance 0)
		)
		(min_thickness 0.25)
		(keepout
			(tracks not_allowed)
			(vias allowed)
			(pads allowed)
			(copperpour not_allowed)
			(footprints allowed)
		)
		(placement
			(enabled no)
			(sheetname "")
		)
		(fill yes
			(thermal_gap 0.5)
			(thermal_bridge_width 0.5)
			(island_removal_mode 0)
		)
		(polygon
			(pts
				(arc
					(start 49.209198 -208.571338)
					(mid 49.224077 -208.607259)
					(end 49.259998 -208.622138)
				)
				(arc
					(start 50.659538 -208.622138)
					(mid 50.695459 -208.607259)
					(end 50.710338 -208.571338)
				)
				(arc
					(start 50.710338 -208.162398)
					(mid 50.695459 -208.126477)
					(end 50.659538 -208.111598)
				)
				(arc
					(start 49.259998 -208.111598)
					(mid 49.224077 -208.126477)
					(end 49.209198 -208.162398)
				)
			)
		)
	)
	(zone
		(layers "In1.Cu" "In2.Cu")
		(hatch none 0.5)
		(connect_pads
			(clearance 0)
		)
		(min_thickness 0.25)
		(keepout
			(tracks not_allowed)
			(vias allowed)
			(pads allowed)
			(copperpour not_allowed)
			(footprints allowed)
		)
		(placement
			(enabled no)
			(sheetname "")
		)
		(fill yes
			(thermal_gap 0.5)
			(thermal_bridge_width 0.5)
			(island_removal_mode 0)
		)
		(polygon
			(pts
				(arc
					(start 289.605466 -306.32146)
					(mid 289.620345 -306.357381)
					(end 289.656266 -306.37226)
				)
				(arc
					(start 291.055806 -306.37226)
					(mid 291.091727 -306.357381)
					(end 291.106606 -306.32146)
				)
				(arc
					(start 291.106606 -305.91252)
					(mid 291.091727 -305.876599)
					(end 291.055806 -305.86172)
				)
				(arc
					(start 289.656266 -305.86172)
					(mid 289.620345 -305.876599)
					(end 289.605466 -305.91252)
				)
			)
		)
	)
	(zone
		(layers "In1.Cu" "In2.Cu")
		(hatch none 0.5)
		(connect_pads
			(clearance 0)
		)
		(min_thickness 0.25)
		(keepout
			(tracks not_allowed)
			(vias allowed)
			(pads allowed)
			(copperpour not_allowed)
			(footprints allowed)
		)
		(placement
			(enabled no)
			(sheetname "")
		)
		(fill yes
			(thermal_gap 0.5)
			(thermal_bridge_width 0.5)
			(island_removal_mode 0)
		)
		(polygon
			(pts
				(arc
					(start 19.033998 -268.921484)
					(mid 19.048877 -268.957405)
					(end 19.084798 -268.972284)
				)
				(arc
					(start 20.484338 -268.972284)
					(mid 20.520259 -268.957405)
					(end 20.535138 -268.921484)
				)
				(arc
					(start 20.535138 -268.512544)
					(mid 20.520259 -268.476623)
					(end 20.484338 -268.461744)
				)
				(arc
					(start 19.084798 -268.461744)
					(mid 19.048877 -268.476623)
					(end 19.033998 -268.512544)
				)
			)
		)
	)
	(zone
		(layers "In1.Cu" "In2.Cu")
		(hatch none 0.5)
		(connect_pads
			(clearance 0)
		)
		(min_thickness 0.25)
		(keepout
			(tracks not_allowed)
			(vias allowed)
			(pads allowed)
			(copperpour not_allowed)
			(footprints allowed)
		)
		(placement
			(enabled no)
			(sheetname "")
		)
		(fill yes
			(thermal_gap 0.5)
			(thermal_bridge_width 0.5)
			(island_removal_mode 0)
		)
		(polygon
			(pts
				(arc
					(start 195.78193 -316.521338)
					(mid 195.796809 -316.557259)
					(end 195.83273 -316.572138)
				)
				(arc
					(start 197.23227 -316.572138)
					(mid 197.268191 -316.557259)
					(end 197.28307 -316.521338)
				)
				(arc
					(start 197.28307 -316.112398)
					(mid 197.268191 -316.076477)
					(end 197.23227 -316.061598)
				)
				(arc
					(start 195.83273 -316.061598)
					(mid 195.796809 -316.076477)
					(end 195.78193 -316.112398)
				)
			)
		)
	)
	(zone
		(layers "In1.Cu" "In2.Cu")
		(hatch none 0.5)
		(connect_pads
			(clearance 0)
		)
		(min_thickness 0.25)
		(keepout
			(tracks not_allowed)
			(vias allowed)
			(pads allowed)
			(copperpour not_allowed)
			(footprints allowed)
		)
		(placement
			(enabled no)
			(sheetname "")
		)
		(fill yes
			(thermal_gap 0.5)
			(thermal_bridge_width 0.5)
			(island_removal_mode 0)
		)
		(polygon
			(pts
				(arc
					(start 45.10913 -314.821316)
					(mid 45.124009 -314.857237)
					(end 45.15993 -314.872116)
				)
				(arc
					(start 46.55947 -314.872116)
					(mid 46.595391 -314.857237)
					(end 46.61027 -314.821316)
				)
				(arc
					(start 46.61027 -314.412376)
					(mid 46.595391 -314.376455)
					(end 46.55947 -314.361576)
				)
				(arc
					(start 45.15993 -314.361576)
					(mid 45.124009 -314.376455)
					(end 45.10913 -314.412376)
				)
			)
		)
	)
	(zone
		(layers "In1.Cu" "In2.Cu")
		(hatch none 0.5)
		(connect_pads
			(clearance 0)
		)
		(min_thickness 0.25)
		(keepout
			(tracks not_allowed)
			(vias allowed)
			(pads allowed)
			(copperpour not_allowed)
			(footprints allowed)
		)
		(placement
			(enabled no)
			(sheetname "")
		)
		(fill yes
			(thermal_gap 0.5)
			(thermal_bridge_width 0.5)
			(island_removal_mode 0)
		)
		(polygon
			(pts
				(arc
					(start 199.881998 -296.971466)
					(mid 199.896877 -297.007387)
					(end 199.932798 -297.022266)
				)
				(arc
					(start 201.332338 -297.022266)
					(mid 201.368259 -297.007387)
					(end 201.383138 -296.971466)
				)
				(arc
					(start 201.383138 -296.562526)
					(mid 201.368259 -296.526605)
					(end 201.332338 -296.511726)
				)
				(arc
					(start 199.932798 -296.511726)
					(mid 199.896877 -296.526605)
					(end 199.881998 -296.562526)
				)
			)
		)
	)
	(zone
		(layers "In1.Cu" "In2.Cu")
		(hatch none 0.5)
		(connect_pads
			(clearance 0)
		)
		(min_thickness 0.25)
		(keepout
			(tracks not_allowed)
			(vias allowed)
			(pads allowed)
			(copperpour not_allowed)
			(footprints allowed)
		)
		(placement
			(enabled no)
			(sheetname "")
		)
		(fill yes
			(thermal_gap 0.5)
			(thermal_bridge_width 0.5)
			(island_removal_mode 0)
		)
		(polygon
			(pts
				(arc
					(start 207.425798 -262.121396)
					(mid 207.440677 -262.157317)
					(end 207.476598 -262.172196)
				)
				(arc
					(start 208.876138 -262.172196)
					(mid 208.912059 -262.157317)
					(end 208.926938 -262.121396)
				)
				(arc
					(start 208.926938 -261.712456)
					(mid 208.912059 -261.676535)
					(end 208.876138 -261.661656)
				)
				(arc
					(start 207.476598 -261.661656)
					(mid 207.440677 -261.676535)
					(end 207.425798 -261.712456)
				)
			)
		)
	)
	(zone
		(layers "In1.Cu" "In2.Cu")
		(hatch none 0.5)
		(connect_pads
			(clearance 0)
		)
		(min_thickness 0.25)
		(keepout
			(tracks not_allowed)
			(vias allowed)
			(pads allowed)
			(copperpour not_allowed)
			(footprints allowed)
		)
		(placement
			(enabled no)
			(sheetname "")
		)
		(fill yes
			(thermal_gap 0.5)
			(thermal_bridge_width 0.5)
			(island_removal_mode 0)
		)
		(polygon
			(pts
				(arc
					(start 37.56533 -282.521406)
					(mid 37.580209 -282.557327)
					(end 37.61613 -282.572206)
				)
				(arc
					(start 39.01567 -282.572206)
					(mid 39.051591 -282.557327)
					(end 39.06647 -282.521406)
				)
				(arc
					(start 39.06647 -282.112466)
					(mid 39.051591 -282.076545)
					(end 39.01567 -282.061666)
				)
				(arc
					(start 37.61613 -282.061666)
					(mid 37.580209 -282.076545)
					(end 37.56533 -282.112466)
				)
			)
		)
	)
	(zone
		(layers "In1.Cu" "In2.Cu")
		(hatch none 0.5)
		(connect_pads
			(clearance 0)
		)
		(min_thickness 0.25)
		(keepout
			(tracks not_allowed)
			(vias allowed)
			(pads allowed)
			(copperpour not_allowed)
			(footprints allowed)
		)
		(placement
			(enabled no)
			(sheetname "")
		)
		(fill yes
			(thermal_gap 0.5)
			(thermal_bridge_width 0.5)
			(island_removal_mode 0)
		)
		(polygon
			(pts
				(arc
					(start 259.430266 -208.571338)
					(mid 259.445145 -208.607259)
					(end 259.481066 -208.622138)
				)
				(arc
					(start 260.880606 -208.622138)
					(mid 260.916527 -208.607259)
					(end 260.931406 -208.571338)
				)
				(arc
					(start 260.931406 -208.162398)
					(mid 260.916527 -208.126477)
					(end 260.880606 -208.111598)
				)
				(arc
					(start 259.481066 -208.111598)
					(mid 259.445145 -208.126477)
					(end 259.430266 -208.162398)
				)
			)
		)
	)
	(zone
		(layers "In1.Cu" "In2.Cu")
		(hatch none 0.5)
		(connect_pads
			(clearance 0)
		)
		(min_thickness 0.25)
		(keepout
			(tracks not_allowed)
			(vias allowed)
			(pads allowed)
			(copperpour not_allowed)
			(footprints allowed)
		)
		(placement
			(enabled no)
			(sheetname "")
		)
		(fill yes
			(thermal_gap 0.5)
			(thermal_bridge_width 0.5)
			(island_removal_mode 0)
		)
		(polygon
			(pts
				(arc
					(start 19.033998 -283.371544)
					(mid 19.048877 -283.407465)
					(end 19.084798 -283.422344)
				)
				(arc
					(start 20.484338 -283.422344)
					(mid 20.520259 -283.407465)
					(end 20.535138 -283.371544)
				)
				(arc
					(start 20.535138 -282.962604)
					(mid 20.520259 -282.926683)
					(end 20.484338 -282.911804)
				)
				(arc
					(start 19.084798 -282.911804)
					(mid 19.048877 -282.926683)
					(end 19.033998 -282.962604)
				)
			)
		)
	)
	(zone
		(layers "In1.Cu" "In2.Cu")
		(hatch none 0.5)
		(connect_pads
			(clearance 0)
		)
		(min_thickness 0.25)
		(keepout
			(tracks not_allowed)
			(vias allowed)
			(pads allowed)
			(copperpour not_allowed)
			(footprints allowed)
		)
		(placement
			(enabled no)
			(sheetname "")
		)
		(fill yes
			(thermal_gap 0.5)
			(thermal_bridge_width 0.5)
			(island_removal_mode 0)
		)
		(polygon
			(pts
				(arc
					(start 458.809598 -299.521372)
					(mid 458.824477 -299.557293)
					(end 458.860398 -299.572172)
				)
				(arc
					(start 460.259938 -299.572172)
					(mid 460.295859 -299.557293)
					(end 460.310738 -299.521372)
				)
				(arc
					(start 460.310738 -299.112432)
					(mid 460.295859 -299.076511)
					(end 460.259938 -299.061632)
				)
				(arc
					(start 458.860398 -299.061632)
					(mid 458.824477 -299.076511)
					(end 458.809598 -299.112432)
				)
			)
		)
	)
	(zone
		(layers "In1.Cu" "In2.Cu")
		(hatch none 0.5)
		(connect_pads
			(clearance 0)
		)
		(min_thickness 0.25)
		(keepout
			(tracks not_allowed)
			(vias allowed)
			(pads allowed)
			(copperpour not_allowed)
			(footprints allowed)
		)
		(placement
			(enabled no)
			(sheetname "")
		)
		(fill yes
			(thermal_gap 0.5)
			(thermal_bridge_width 0.5)
			(island_removal_mode 0)
		)
		(polygon
			(pts
				(arc
					(start 297.149266 -287.621472)
					(mid 297.164145 -287.657393)
					(end 297.200066 -287.672272)
				)
				(arc
					(start 298.599606 -287.672272)
					(mid 298.635527 -287.657393)
					(end 298.650406 -287.621472)
				)
				(arc
					(start 298.650406 -287.212532)
					(mid 298.635527 -287.176611)
					(end 298.599606 -287.161732)
				)
				(arc
					(start 297.200066 -287.161732)
					(mid 297.164145 -287.176611)
					(end 297.149266 -287.212532)
				)
			)
		)
	)
	(zone
		(layers "In1.Cu" "In2.Cu")
		(hatch none 0.5)
		(connect_pads
			(clearance 0)
		)
		(min_thickness 0.25)
		(keepout
			(tracks not_allowed)
			(vias allowed)
			(pads allowed)
			(copperpour not_allowed)
			(footprints allowed)
		)
		(placement
			(enabled no)
			(sheetname "")
		)
		(fill yes
			(thermal_gap 0.5)
			(thermal_bridge_width 0.5)
			(island_removal_mode 0)
		)
		(polygon
			(pts
				(arc
					(start 52.65293 -314.821316)
					(mid 52.667809 -314.857237)
					(end 52.70373 -314.872116)
				)
				(arc
					(start 54.10327 -314.872116)
					(mid 54.139191 -314.857237)
					(end 54.15407 -314.821316)
				)
				(arc
					(start 54.15407 -314.412376)
					(mid 54.139191 -314.376455)
					(end 54.10327 -314.361576)
				)
				(arc
					(start 52.70373 -314.361576)
					(mid 52.667809 -314.376455)
					(end 52.65293 -314.412376)
				)
			)
		)
	)
	(zone
		(layers "In1.Cu" "In2.Cu")
		(hatch none 0.5)
		(connect_pads
			(clearance 0)
		)
		(min_thickness 0.25)
		(keepout
			(tracks not_allowed)
			(vias allowed)
			(pads allowed)
			(copperpour not_allowed)
			(footprints allowed)
		)
		(placement
			(enabled no)
			(sheetname "")
		)
		(fill yes
			(thermal_gap 0.5)
			(thermal_bridge_width 0.5)
			(island_removal_mode 0)
		)
		(polygon
			(pts
				(arc
					(start 37.56533 -313.121294)
					(mid 37.580209 -313.157215)
					(end 37.61613 -313.172094)
				)
				(arc
					(start 39.01567 -313.172094)
					(mid 39.051591 -313.157215)
					(end 39.06647 -313.121294)
				)
				(arc
					(start 39.06647 -312.712354)
					(mid 39.051591 -312.676433)
					(end 39.01567 -312.661554)
				)
				(arc
					(start 37.61613 -312.661554)
					(mid 37.580209 -312.676433)
					(end 37.56533 -312.712354)
				)
			)
		)
	)
	(zone
		(layers "In1.Cu" "In2.Cu")
		(hatch none 0.5)
		(connect_pads
			(clearance 0)
		)
		(min_thickness 0.25)
		(keepout
			(tracks not_allowed)
			(vias allowed)
			(pads allowed)
			(copperpour not_allowed)
			(footprints allowed)
		)
		(placement
			(enabled no)
			(sheetname "")
		)
		(fill yes
			(thermal_gap 0.5)
			(thermal_bridge_width 0.5)
			(island_removal_mode 0)
		)
		(polygon
			(pts
				(arc
					(start 56.752998 -237.471458)
					(mid 56.767877 -237.507379)
					(end 56.803798 -237.522258)
				)
				(arc
					(start 58.203338 -237.522258)
					(mid 58.239259 -237.507379)
					(end 58.254138 -237.471458)
				)
				(arc
					(start 58.254138 -237.062518)
					(mid 58.239259 -237.026597)
					(end 58.203338 -237.011718)
				)
				(arc
					(start 56.803798 -237.011718)
					(mid 56.767877 -237.026597)
					(end 56.752998 -237.062518)
				)
			)
		)
	)
	(zone
		(layers "In1.Cu" "In2.Cu")
		(hatch none 0.5)
		(connect_pads
			(clearance 0)
		)
		(min_thickness 0.25)
		(keepout
			(tracks not_allowed)
			(vias allowed)
			(pads allowed)
			(copperpour not_allowed)
			(footprints allowed)
		)
		(placement
			(enabled no)
			(sheetname "")
		)
		(fill yes
			(thermal_gap 0.5)
			(thermal_bridge_width 0.5)
			(island_removal_mode 0)
		)
		(polygon
			(pts
				(arc
					(start 425.190666 -250.221496)
					(mid 425.205545 -250.257417)
					(end 425.241466 -250.272296)
				)
				(arc
					(start 426.641006 -250.272296)
					(mid 426.676927 -250.257417)
					(end 426.691806 -250.221496)
				)
				(arc
					(start 426.691806 -249.812556)
					(mid 426.676927 -249.776635)
					(end 426.641006 -249.761756)
				)
				(arc
					(start 425.241466 -249.761756)
					(mid 425.205545 -249.776635)
					(end 425.190666 -249.812556)
				)
			)
		)
	)
	(zone
		(layers "In1.Cu" "In2.Cu")
		(hatch none 0.5)
		(connect_pads
			(clearance 0)
		)
		(min_thickness 0.25)
		(keepout
			(tracks not_allowed)
			(vias allowed)
			(pads allowed)
			(copperpour not_allowed)
			(footprints allowed)
		)
		(placement
			(enabled no)
			(sheetname "")
		)
		(fill yes
			(thermal_gap 0.5)
			(thermal_bridge_width 0.5)
			(island_removal_mode 0)
		)
		(polygon
			(pts
				(arc
					(start 214.969598 -312.27141)
					(mid 214.984477 -312.307331)
					(end 215.020398 -312.32221)
				)
				(arc
					(start 216.419938 -312.32221)
					(mid 216.455859 -312.307331)
					(end 216.470738 -312.27141)
				)
				(arc
					(start 216.470738 -311.86247)
					(mid 216.455859 -311.826549)
					(end 216.419938 -311.81167)
				)
				(arc
					(start 215.020398 -311.81167)
					(mid 214.984477 -311.826549)
					(end 214.969598 -311.86247)
				)
			)
		)
	)
	(zone
		(layers "In1.Cu" "In2.Cu")
		(hatch none 0.5)
		(connect_pads
			(clearance 0)
		)
		(min_thickness 0.25)
		(keepout
			(tracks not_allowed)
			(vias allowed)
			(pads allowed)
			(copperpour not_allowed)
			(footprints allowed)
		)
		(placement
			(enabled no)
			(sheetname "")
		)
		(fill yes
			(thermal_gap 0.5)
			(thermal_bridge_width 0.5)
			(island_removal_mode 0)
		)
		(polygon
			(pts
				(arc
					(start 60.19673 -217.071448)
					(mid 60.211609 -217.107369)
					(end 60.24753 -217.122248)
				)
				(arc
					(start 61.64707 -217.122248)
					(mid 61.682991 -217.107369)
					(end 61.69787 -217.071448)
				)
				(arc
					(start 61.69787 -216.662508)
					(mid 61.682991 -216.626587)
					(end 61.64707 -216.611708)
				)
				(arc
					(start 60.24753 -216.611708)
					(mid 60.211609 -216.626587)
					(end 60.19673 -216.662508)
				)
			)
		)
	)
	(zone
		(layers "In1.Cu" "In2.Cu")
		(hatch none 0.5)
		(connect_pads
			(clearance 0)
		)
		(min_thickness 0.25)
		(keepout
			(tracks not_allowed)
			(vias allowed)
			(pads allowed)
			(copperpour not_allowed)
			(footprints allowed)
		)
		(placement
			(enabled no)
			(sheetname "")
		)
		(fill yes
			(thermal_gap 0.5)
			(thermal_bridge_width 0.5)
			(island_removal_mode 0)
		)
		(polygon
			(pts
				(arc
					(start 60.19673 -198.37146)
					(mid 60.211609 -198.407381)
					(end 60.24753 -198.42226)
				)
				(arc
					(start 61.64707 -198.42226)
					(mid 61.682991 -198.407381)
					(end 61.69787 -198.37146)
				)
				(arc
					(start 61.69787 -197.96252)
					(mid 61.682991 -197.926599)
					(end 61.64707 -197.91172)
				)
				(arc
					(start 60.24753 -197.91172)
					(mid 60.211609 -197.926599)
					(end 60.19673 -197.96252)
				)
			)
		)
	)
	(zone
		(layers "In1.Cu" "In2.Cu")
		(hatch none 0.5)
		(connect_pads
			(clearance 0)
		)
		(min_thickness 0.25)
		(keepout
			(tracks not_allowed)
			(vias allowed)
			(pads allowed)
			(copperpour not_allowed)
			(footprints allowed)
		)
		(placement
			(enabled no)
			(sheetname "")
		)
		(fill yes
			(thermal_gap 0.5)
			(thermal_bridge_width 0.5)
			(island_removal_mode 0)
		)
		(polygon
			(pts
				(arc
					(start 432.734466 -276.571456)
					(mid 432.749345 -276.607377)
					(end 432.785266 -276.622256)
				)
				(arc
					(start 434.184806 -276.622256)
					(mid 434.220727 -276.607377)
					(end 434.235606 -276.571456)
				)
				(arc
					(start 434.235606 -276.162516)
					(mid 434.220727 -276.126595)
					(end 434.184806 -276.111716)
				)
				(arc
					(start 432.785266 -276.111716)
					(mid 432.749345 -276.126595)
					(end 432.734466 -276.162516)
				)
			)
		)
	)
	(zone
		(layers "In1.Cu" "In2.Cu")
		(hatch none 0.5)
		(connect_pads
			(clearance 0)
		)
		(min_thickness 0.25)
		(keepout
			(tracks not_allowed)
			(vias allowed)
			(pads allowed)
			(copperpour not_allowed)
			(footprints allowed)
		)
		(placement
			(enabled no)
			(sheetname "")
		)
		(fill yes
			(thermal_gap 0.5)
			(thermal_bridge_width 0.5)
			(island_removal_mode 0)
		)
		(polygon
			(pts
				(arc
					(start 56.752998 -279.9715)
					(mid 56.767877 -280.007421)
					(end 56.803798 -280.0223)
				)
				(arc
					(start 58.203338 -280.0223)
					(mid 58.239259 -280.007421)
					(end 58.254138 -279.9715)
				)
				(arc
					(start 58.254138 -279.56256)
					(mid 58.239259 -279.526639)
					(end 58.203338 -279.51176)
				)
				(arc
					(start 56.803798 -279.51176)
					(mid 56.767877 -279.526639)
					(end 56.752998 -279.56256)
				)
			)
		)
	)
	(zone
		(layers "In1.Cu" "In2.Cu")
		(hatch none 0.5)
		(connect_pads
			(clearance 0)
		)
		(min_thickness 0.25)
		(keepout
			(tracks not_allowed)
			(vias allowed)
			(pads allowed)
			(copperpour not_allowed)
			(footprints allowed)
		)
		(placement
			(enabled no)
			(sheetname "")
		)
		(fill yes
			(thermal_gap 0.5)
			(thermal_bridge_width 0.5)
			(island_removal_mode 0)
		)
		(polygon
			(pts
				(arc
					(start 282.061666 -300.37151)
					(mid 282.076545 -300.407431)
					(end 282.112466 -300.42231)
				)
				(arc
					(start 283.512006 -300.42231)
					(mid 283.547927 -300.407431)
					(end 283.562806 -300.37151)
				)
				(arc
					(start 283.562806 -299.96257)
					(mid 283.547927 -299.926649)
					(end 283.512006 -299.91177)
				)
				(arc
					(start 282.112466 -299.91177)
					(mid 282.076545 -299.926649)
					(end 282.061666 -299.96257)
				)
			)
		)
	)
	(zone
		(layers "In1.Cu" "In2.Cu")
		(hatch none 0.5)
		(connect_pads
			(clearance 0)
		)
		(min_thickness 0.25)
		(keepout
			(tracks not_allowed)
			(vias allowed)
			(pads allowed)
			(copperpour not_allowed)
			(footprints allowed)
		)
		(placement
			(enabled no)
			(sheetname "")
		)
		(fill yes
			(thermal_gap 0.5)
			(thermal_bridge_width 0.5)
			(island_removal_mode 0)
		)
		(polygon
			(pts
				(arc
					(start 458.809598 -217.071448)
					(mid 458.824477 -217.107369)
					(end 458.860398 -217.122248)
				)
				(arc
					(start 460.259938 -217.122248)
					(mid 460.295859 -217.107369)
					(end 460.310738 -217.071448)
				)
				(arc
					(start 460.310738 -216.662508)
					(mid 460.295859 -216.626587)
					(end 460.259938 -216.611708)
				)
				(arc
					(start 458.860398 -216.611708)
					(mid 458.824477 -216.626587)
					(end 458.809598 -216.662508)
				)
			)
		)
	)
	(zone
		(layers "In1.Cu" "In2.Cu")
		(hatch none 0.5)
		(connect_pads
			(clearance 0)
		)
		(min_thickness 0.25)
		(keepout
			(tracks not_allowed)
			(vias allowed)
			(pads allowed)
			(copperpour not_allowed)
			(footprints allowed)
		)
		(placement
			(enabled no)
			(sheetname "")
		)
		(fill yes
			(thermal_gap 0.5)
			(thermal_bridge_width 0.5)
			(island_removal_mode 0)
		)
		(polygon
			(pts
				(arc
					(start 14.93393 -198.37146)
					(mid 14.948809 -198.407381)
					(end 14.98473 -198.42226)
				)
				(arc
					(start 16.38427 -198.42226)
					(mid 16.420191 -198.407381)
					(end 16.43507 -198.37146)
				)
				(arc
					(start 16.43507 -197.96252)
					(mid 16.420191 -197.926599)
					(end 16.38427 -197.91172)
				)
				(arc
					(start 14.98473 -197.91172)
					(mid 14.948809 -197.926599)
					(end 14.93393 -197.96252)
				)
			)
		)
	)
	(zone
		(layers "In1.Cu" "In2.Cu")
		(hatch none 0.5)
		(connect_pads
			(clearance 0)
		)
		(min_thickness 0.25)
		(keepout
			(tracks not_allowed)
			(vias allowed)
			(pads allowed)
			(copperpour not_allowed)
			(footprints allowed)
		)
		(placement
			(enabled no)
			(sheetname "")
		)
		(fill yes
			(thermal_gap 0.5)
			(thermal_bridge_width 0.5)
			(island_removal_mode 0)
		)
		(polygon
			(pts
				(arc
					(start 406.002998 -207.721454)
					(mid 406.017877 -207.757375)
					(end 406.053798 -207.772254)
				)
				(arc
					(start 407.453338 -207.772254)
					(mid 407.489259 -207.757375)
					(end 407.504138 -207.721454)
				)
				(arc
					(start 407.504138 -207.312514)
					(mid 407.489259 -207.276593)
					(end 407.453338 -207.261714)
				)
				(arc
					(start 406.053798 -207.261714)
					(mid 406.017877 -207.276593)
					(end 406.002998 -207.312514)
				)
			)
		)
	)
	(zone
		(layers "In1.Cu" "In2.Cu")
		(hatch none 0.5)
		(connect_pads
			(clearance 0)
		)
		(min_thickness 0.25)
		(keepout
			(tracks not_allowed)
			(vias allowed)
			(pads allowed)
			(copperpour not_allowed)
			(footprints allowed)
		)
		(placement
			(enabled no)
			(sheetname "")
		)
		(fill yes
			(thermal_gap 0.5)
			(thermal_bridge_width 0.5)
			(island_removal_mode 0)
		)
		(polygon
			(pts
				(arc
					(start 406.002998 -259.57149)
					(mid 406.017877 -259.607411)
					(end 406.053798 -259.62229)
				)
				(arc
					(start 407.453338 -259.62229)
					(mid 407.489259 -259.607411)
					(end 407.504138 -259.57149)
				)
				(arc
					(start 407.504138 -259.16255)
					(mid 407.489259 -259.126629)
					(end 407.453338 -259.11175)
				)
				(arc
					(start 406.053798 -259.11175)
					(mid 406.017877 -259.126629)
					(end 406.002998 -259.16255)
				)
			)
		)
	)
	(zone
		(layers "In1.Cu" "In2.Cu")
		(hatch none 0.5)
		(connect_pads
			(clearance 0)
		)
		(min_thickness 0.25)
		(keepout
			(tracks not_allowed)
			(vias allowed)
			(pads allowed)
			(copperpour not_allowed)
			(footprints allowed)
		)
		(placement
			(enabled no)
			(sheetname "")
		)
		(fill yes
			(thermal_gap 0.5)
			(thermal_bridge_width 0.5)
			(island_removal_mode 0)
		)
		(polygon
			(pts
				(arc
					(start 34.121598 -231.521508)
					(mid 34.136477 -231.557429)
					(end 34.172398 -231.572308)
				)
				(arc
					(start 35.571938 -231.572308)
					(mid 35.607859 -231.557429)
					(end 35.622738 -231.521508)
				)
				(arc
					(start 35.622738 -231.112568)
					(mid 35.607859 -231.076647)
					(end 35.571938 -231.061768)
				)
				(arc
					(start 34.172398 -231.061768)
					(mid 34.136477 -231.076647)
					(end 34.121598 -231.112568)
				)
			)
		)
	)
	(zone
		(layers "In1.Cu" "In2.Cu")
		(hatch none 0.5)
		(connect_pads
			(clearance 0)
		)
		(min_thickness 0.25)
		(keepout
			(tracks not_allowed)
			(vias allowed)
			(pads allowed)
			(copperpour not_allowed)
			(footprints allowed)
		)
		(placement
			(enabled no)
			(sheetname "")
		)
		(fill yes
			(thermal_gap 0.5)
			(thermal_bridge_width 0.5)
			(island_removal_mode 0)
		)
		(polygon
			(pts
				(arc
					(start 26.577798 -311.421526)
					(mid 26.592677 -311.457447)
					(end 26.628598 -311.472326)
				)
				(arc
					(start 28.028138 -311.472326)
					(mid 28.064059 -311.457447)
					(end 28.078938 -311.421526)
				)
				(arc
					(start 28.078938 -311.012586)
					(mid 28.064059 -310.976665)
					(end 28.028138 -310.961786)
				)
				(arc
					(start 26.628598 -310.961786)
					(mid 26.592677 -310.976665)
					(end 26.577798 -311.012586)
				)
			)
		)
	)
	(zone
		(layers "In1.Cu" "In2.Cu")
		(hatch none 0.5)
		(connect_pads
			(clearance 0)
		)
		(min_thickness 0.25)
		(keepout
			(tracks not_allowed)
			(vias allowed)
			(pads allowed)
			(copperpour not_allowed)
			(footprints allowed)
		)
		(placement
			(enabled no)
			(sheetname "")
		)
		(fill yes
			(thermal_gap 0.5)
			(thermal_bridge_width 0.5)
			(island_removal_mode 0)
		)
		(polygon
			(pts
				(arc
					(start 169.706798 -302.071532)
					(mid 169.721677 -302.107453)
					(end 169.757598 -302.122332)
				)
				(arc
					(start 171.157138 -302.122332)
					(mid 171.193059 -302.107453)
					(end 171.207938 -302.071532)
				)
				(arc
					(start 171.207938 -301.662592)
					(mid 171.193059 -301.626671)
					(end 171.157138 -301.611792)
				)
				(arc
					(start 169.757598 -301.611792)
					(mid 169.721677 -301.626671)
					(end 169.706798 -301.662592)
				)
			)
		)
	)
	(zone
		(layers "In1.Cu" "In2.Cu")
		(hatch none 0.5)
		(connect_pads
			(clearance 0)
		)
		(min_thickness 0.25)
		(keepout
			(tracks not_allowed)
			(vias allowed)
			(pads allowed)
			(copperpour not_allowed)
			(footprints allowed)
		)
		(placement
			(enabled no)
			(sheetname "")
		)
		(fill yes
			(thermal_gap 0.5)
			(thermal_bridge_width 0.5)
			(island_removal_mode 0)
		)
		(polygon
			(pts
				(arc
					(start 192.338198 -229.821486)
					(mid 192.353077 -229.857407)
					(end 192.388998 -229.872286)
				)
				(arc
					(start 193.788538 -229.872286)
					(mid 193.824459 -229.857407)
					(end 193.839338 -229.821486)
				)
				(arc
					(start 193.839338 -229.412546)
					(mid 193.824459 -229.376625)
					(end 193.788538 -229.361746)
				)
				(arc
					(start 192.388998 -229.361746)
					(mid 192.353077 -229.376625)
					(end 192.338198 -229.412546)
				)
			)
		)
	)
	(zone
		(layers "In1.Cu" "In2.Cu")
		(hatch none 0.5)
		(connect_pads
			(clearance 0)
		)
		(min_thickness 0.25)
		(keepout
			(tracks not_allowed)
			(vias allowed)
			(pads allowed)
			(copperpour not_allowed)
			(footprints allowed)
		)
		(placement
			(enabled no)
			(sheetname "")
		)
		(fill yes
			(thermal_gap 0.5)
			(thermal_bridge_width 0.5)
			(island_removal_mode 0)
		)
		(polygon
			(pts
				(arc
					(start 440.278266 -260.421374)
					(mid 440.293145 -260.457295)
					(end 440.329066 -260.472174)
				)
				(arc
					(start 441.728606 -260.472174)
					(mid 441.764527 -260.457295)
					(end 441.779406 -260.421374)
				)
				(arc
					(start 441.779406 -260.012434)
					(mid 441.764527 -259.976513)
					(end 441.728606 -259.961634)
				)
				(arc
					(start 440.329066 -259.961634)
					(mid 440.293145 -259.976513)
					(end 440.278266 -260.012434)
				)
			)
		)
	)
	(zone
		(layers "In1.Cu" "In2.Cu")
		(hatch none 0.5)
		(connect_pads
			(clearance 0)
		)
		(min_thickness 0.25)
		(keepout
			(tracks not_allowed)
			(vias allowed)
			(pads allowed)
			(copperpour not_allowed)
			(footprints allowed)
		)
		(placement
			(enabled no)
			(sheetname "")
		)
		(fill yes
			(thermal_gap 0.5)
			(thermal_bridge_width 0.5)
			(island_removal_mode 0)
		)
		(polygon
			(pts
				(arc
					(start 49.209198 -313.971432)
					(mid 49.224077 -314.007353)
					(end 49.259998 -314.022232)
				)
				(arc
					(start 50.659538 -314.022232)
					(mid 50.695459 -314.007353)
					(end 50.710338 -313.971432)
				)
				(arc
					(start 50.710338 -313.562492)
					(mid 50.695459 -313.526571)
					(end 50.659538 -313.511692)
				)
				(arc
					(start 49.259998 -313.511692)
					(mid 49.224077 -313.526571)
					(end 49.209198 -313.562492)
				)
			)
		)
	)
	(zone
		(layers "In1.Cu" "In2.Cu")
		(hatch none 0.5)
		(connect_pads
			(clearance 0)
		)
		(min_thickness 0.25)
		(keepout
			(tracks not_allowed)
			(vias allowed)
			(pads allowed)
			(copperpour not_allowed)
			(footprints allowed)
		)
		(placement
			(enabled no)
			(sheetname "")
		)
		(fill yes
			(thermal_gap 0.5)
			(thermal_bridge_width 0.5)
			(island_removal_mode 0)
		)
		(polygon
			(pts
				(arc
					(start 282.061666 -205.171548)
					(mid 282.076545 -205.207469)
					(end 282.112466 -205.222348)
				)
				(arc
					(start 283.512006 -205.222348)
					(mid 283.547927 -205.207469)
					(end 283.562806 -205.171548)
				)
				(arc
					(start 283.562806 -204.762608)
					(mid 283.547927 -204.726687)
					(end 283.512006 -204.711808)
				)
				(arc
					(start 282.112466 -204.711808)
					(mid 282.076545 -204.726687)
					(end 282.061666 -204.762608)
				)
			)
		)
	)
	(zone
		(layers "In1.Cu" "In2.Cu")
		(hatch none 0.5)
		(connect_pads
			(clearance 0)
		)
		(min_thickness 0.25)
		(keepout
			(tracks not_allowed)
			(vias allowed)
			(pads allowed)
			(copperpour not_allowed)
			(footprints allowed)
		)
		(placement
			(enabled no)
			(sheetname "")
		)
		(fill yes
			(thermal_gap 0.5)
			(thermal_bridge_width 0.5)
			(island_removal_mode 0)
		)
		(polygon
			(pts
				(arc
					(start 22.47773 -302.921416)
					(mid 22.492609 -302.957337)
					(end 22.52853 -302.972216)
				)
				(arc
					(start 23.92807 -302.972216)
					(mid 23.963991 -302.957337)
					(end 23.97887 -302.921416)
				)
				(arc
					(start 23.97887 -302.512476)
					(mid 23.963991 -302.476555)
					(end 23.92807 -302.461676)
				)
				(arc
					(start 22.52853 -302.461676)
					(mid 22.492609 -302.476555)
					(end 22.47773 -302.512476)
				)
			)
		)
	)
	(zone
		(layers "In1.Cu" "In2.Cu")
		(hatch none 0.5)
		(connect_pads
			(clearance 0)
		)
		(min_thickness 0.25)
		(keepout
			(tracks not_allowed)
			(vias allowed)
			(pads allowed)
			(copperpour not_allowed)
			(footprints allowed)
		)
		(placement
			(enabled no)
			(sheetname "")
		)
		(fill yes
			(thermal_gap 0.5)
			(thermal_bridge_width 0.5)
			(island_removal_mode 0)
		)
		(polygon
			(pts
				(arc
					(start 184.794398 -284.221428)
					(mid 184.809277 -284.257349)
					(end 184.845198 -284.272228)
				)
				(arc
					(start 186.244738 -284.272228)
					(mid 186.280659 -284.257349)
					(end 186.295538 -284.221428)
				)
				(arc
					(start 186.295538 -283.812488)
					(mid 186.280659 -283.776567)
					(end 186.244738 -283.761688)
				)
				(arc
					(start 184.845198 -283.761688)
					(mid 184.809277 -283.776567)
					(end 184.794398 -283.812488)
				)
			)
		)
	)
	(zone
		(layers "In1.Cu" "In2.Cu")
		(hatch none 0.5)
		(connect_pads
			(clearance 0)
		)
		(min_thickness 0.25)
		(keepout
			(tracks not_allowed)
			(vias allowed)
			(pads allowed)
			(copperpour not_allowed)
			(footprints allowed)
		)
		(placement
			(enabled no)
			(sheetname "")
		)
		(fill yes
			(thermal_gap 0.5)
			(thermal_bridge_width 0.5)
			(island_removal_mode 0)
		)
		(polygon
			(pts
				(arc
					(start 177.250598 -234.921298)
					(mid 177.265477 -234.957219)
					(end 177.301398 -234.972098)
				)
				(arc
					(start 178.700938 -234.972098)
					(mid 178.736859 -234.957219)
					(end 178.751738 -234.921298)
				)
				(arc
					(start 178.751738 -234.512358)
					(mid 178.736859 -234.476437)
					(end 178.700938 -234.461558)
				)
				(arc
					(start 177.301398 -234.461558)
					(mid 177.265477 -234.476437)
					(end 177.250598 -234.512358)
				)
			)
		)
	)
	(zone
		(layers "In1.Cu" "In2.Cu")
		(hatch none 0.5)
		(connect_pads
			(clearance 0)
		)
		(min_thickness 0.25)
		(keepout
			(tracks not_allowed)
			(vias allowed)
			(pads allowed)
			(copperpour not_allowed)
			(footprints allowed)
		)
		(placement
			(enabled no)
			(sheetname "")
		)
		(fill yes
			(thermal_gap 0.5)
			(thermal_bridge_width 0.5)
			(island_removal_mode 0)
		)
		(polygon
			(pts
				(arc
					(start 37.56533 -266.371324)
					(mid 37.580209 -266.407245)
					(end 37.61613 -266.422124)
				)
				(arc
					(start 39.01567 -266.422124)
					(mid 39.051591 -266.407245)
					(end 39.06647 -266.371324)
				)
				(arc
					(start 39.06647 -265.962384)
					(mid 39.051591 -265.926463)
					(end 39.01567 -265.911584)
				)
				(arc
					(start 37.61613 -265.911584)
					(mid 37.580209 -265.926463)
					(end 37.56533 -265.962384)
				)
			)
		)
	)
	(zone
		(layers "In1.Cu" "In2.Cu")
		(hatch none 0.5)
		(connect_pads
			(clearance 0)
		)
		(min_thickness 0.25)
		(keepout
			(tracks not_allowed)
			(vias allowed)
			(pads allowed)
			(copperpour not_allowed)
			(footprints allowed)
		)
		(placement
			(enabled no)
			(sheetname "")
		)
		(fill yes
			(thermal_gap 0.5)
			(thermal_bridge_width 0.5)
			(island_removal_mode 0)
		)
		(polygon
			(pts
				(arc
					(start 34.121598 -263.821418)
					(mid 34.136477 -263.857339)
					(end 34.172398 -263.872218)
				)
				(arc
					(start 35.571938 -263.872218)
					(mid 35.607859 -263.857339)
					(end 35.622738 -263.821418)
				)
				(arc
					(start 35.622738 -263.412478)
					(mid 35.607859 -263.376557)
					(end 35.571938 -263.361678)
				)
				(arc
					(start 34.172398 -263.361678)
					(mid 34.136477 -263.376557)
					(end 34.121598 -263.412478)
				)
			)
		)
	)
	(zone
		(layers "In1.Cu" "In2.Cu")
		(hatch none 0.5)
		(connect_pads
			(clearance 0)
		)
		(min_thickness 0.25)
		(keepout
			(tracks not_allowed)
			(vias allowed)
			(pads allowed)
			(copperpour not_allowed)
			(footprints allowed)
		)
		(placement
			(enabled no)
			(sheetname "")
		)
		(fill yes
			(thermal_gap 0.5)
			(thermal_bridge_width 0.5)
			(island_removal_mode 0)
		)
		(polygon
			(pts
				(arc
					(start 312.236866 -197.521322)
					(mid 312.251745 -197.557243)
					(end 312.287666 -197.572122)
				)
				(arc
					(start 313.687206 -197.572122)
					(mid 313.723127 -197.557243)
					(end 313.738006 -197.521322)
				)
				(arc
					(start 313.738006 -197.112382)
					(mid 313.723127 -197.076461)
					(end 313.687206 -197.061582)
				)
				(arc
					(start 312.287666 -197.061582)
					(mid 312.251745 -197.076461)
					(end 312.236866 -197.112382)
				)
			)
		)
	)
	(zone
		(layers "In1.Cu" "In2.Cu")
		(hatch none 0.5)
		(connect_pads
			(clearance 0)
		)
		(min_thickness 0.25)
		(keepout
			(tracks not_allowed)
			(vias allowed)
			(pads allowed)
			(copperpour not_allowed)
			(footprints allowed)
		)
		(placement
			(enabled no)
			(sheetname "")
		)
		(fill yes
			(thermal_gap 0.5)
			(thermal_bridge_width 0.5)
			(island_removal_mode 0)
		)
		(polygon
			(pts
				(arc
					(start 188.23813 -244.271292)
					(mid 188.253009 -244.307213)
					(end 188.28893 -244.322092)
				)
				(arc
					(start 189.68847 -244.322092)
					(mid 189.724391 -244.307213)
					(end 189.73927 -244.271292)
				)
				(arc
					(start 189.73927 -243.862352)
					(mid 189.724391 -243.826431)
					(end 189.68847 -243.811552)
				)
				(arc
					(start 188.28893 -243.811552)
					(mid 188.253009 -243.826431)
					(end 188.23813 -243.862352)
				)
			)
		)
	)
	(zone
		(layers "In1.Cu" "In2.Cu")
		(hatch none 0.5)
		(connect_pads
			(clearance 0)
		)
		(min_thickness 0.25)
		(keepout
			(tracks not_allowed)
			(vias allowed)
			(pads allowed)
			(copperpour not_allowed)
			(footprints allowed)
		)
		(placement
			(enabled no)
			(sheetname "")
		)
		(fill yes
			(thermal_gap 0.5)
			(thermal_bridge_width 0.5)
			(island_removal_mode 0)
		)
		(polygon
			(pts
				(arc
					(start 7.39013 -223.021398)
					(mid 7.405009 -223.057319)
					(end 7.44093 -223.072198)
				)
				(arc
					(start 8.84047 -223.072198)
					(mid 8.876391 -223.057319)
					(end 8.89127 -223.021398)
				)
				(arc
					(start 8.89127 -222.612458)
					(mid 8.876391 -222.576537)
					(end 8.84047 -222.561658)
				)
				(arc
					(start 7.44093 -222.561658)
					(mid 7.405009 -222.576537)
					(end 7.39013 -222.612458)
				)
			)
		)
	)
	(zone
		(layers "In1.Cu" "In2.Cu")
		(hatch none 0.5)
		(connect_pads
			(clearance 0)
		)
		(min_thickness 0.25)
		(keepout
			(tracks not_allowed)
			(vias allowed)
			(pads allowed)
			(copperpour not_allowed)
			(footprints allowed)
		)
		(placement
			(enabled no)
			(sheetname "")
		)
		(fill yes
			(thermal_gap 0.5)
			(thermal_bridge_width 0.5)
			(island_removal_mode 0)
		)
		(polygon
			(pts
				(arc
					(start 203.32573 -200.921366)
					(mid 203.340609 -200.957287)
					(end 203.37653 -200.972166)
				)
				(arc
					(start 204.77607 -200.972166)
					(mid 204.811991 -200.957287)
					(end 204.82687 -200.921366)
				)
				(arc
					(start 204.82687 -200.512426)
					(mid 204.811991 -200.476505)
					(end 204.77607 -200.461626)
				)
				(arc
					(start 203.37653 -200.461626)
					(mid 203.340609 -200.476505)
					(end 203.32573 -200.512426)
				)
			)
		)
	)
	(zone
		(layers "In1.Cu" "In2.Cu")
		(hatch none 0.5)
		(connect_pads
			(clearance 0)
		)
		(min_thickness 0.25)
		(keepout
			(tracks not_allowed)
			(vias allowed)
			(pads allowed)
			(copperpour not_allowed)
			(footprints allowed)
		)
		(placement
			(enabled no)
			(sheetname "")
		)
		(fill yes
			(thermal_gap 0.5)
			(thermal_bridge_width 0.5)
			(island_removal_mode 0)
		)
		(polygon
			(pts
				(arc
					(start 14.93393 -269.771368)
					(mid 14.948809 -269.807289)
					(end 14.98473 -269.822168)
				)
				(arc
					(start 16.38427 -269.822168)
					(mid 16.420191 -269.807289)
					(end 16.43507 -269.771368)
				)
				(arc
					(start 16.43507 -269.362428)
					(mid 16.420191 -269.326507)
					(end 16.38427 -269.311628)
				)
				(arc
					(start 14.98473 -269.311628)
					(mid 14.948809 -269.326507)
					(end 14.93393 -269.362428)
				)
			)
		)
	)
	(zone
		(layers "In1.Cu" "In2.Cu")
		(hatch none 0.5)
		(connect_pads
			(clearance 0)
		)
		(min_thickness 0.25)
		(keepout
			(tracks not_allowed)
			(vias allowed)
			(pads allowed)
			(copperpour not_allowed)
			(footprints allowed)
		)
		(placement
			(enabled no)
			(sheetname "")
		)
		(fill yes
			(thermal_gap 0.5)
			(thermal_bridge_width 0.5)
			(island_removal_mode 0)
		)
		(polygon
			(pts
				(arc
					(start 203.32573 -224.72142)
					(mid 203.340609 -224.757341)
					(end 203.37653 -224.77222)
				)
				(arc
					(start 204.77607 -224.77222)
					(mid 204.811991 -224.757341)
					(end 204.82687 -224.72142)
				)
				(arc
					(start 204.82687 -224.31248)
					(mid 204.811991 -224.276559)
					(end 204.77607 -224.26168)
				)
				(arc
					(start 203.37653 -224.26168)
					(mid 203.340609 -224.276559)
					(end 203.32573 -224.31248)
				)
			)
		)
	)
	(zone
		(layers "In1.Cu" "In2.Cu")
		(hatch none 0.5)
		(connect_pads
			(clearance 0)
		)
		(min_thickness 0.25)
		(keepout
			(tracks not_allowed)
			(vias allowed)
			(pads allowed)
			(copperpour not_allowed)
			(footprints allowed)
		)
		(placement
			(enabled no)
			(sheetname "")
		)
		(fill yes
			(thermal_gap 0.5)
			(thermal_bridge_width 0.5)
			(island_removal_mode 0)
		)
		(polygon
			(pts
				(arc
					(start 214.969598 -227.271326)
					(mid 214.984477 -227.307247)
					(end 215.020398 -227.322126)
				)
				(arc
					(start 216.419938 -227.322126)
					(mid 216.455859 -227.307247)
					(end 216.470738 -227.271326)
				)
				(arc
					(start 216.470738 -226.862386)
					(mid 216.455859 -226.826465)
					(end 216.419938 -226.811586)
				)
				(arc
					(start 215.020398 -226.811586)
					(mid 214.984477 -226.826465)
					(end 214.969598 -226.862386)
				)
			)
		)
	)
	(zone
		(layers "In1.Cu" "In2.Cu")
		(hatch none 0.5)
		(connect_pads
			(clearance 0)
		)
		(min_thickness 0.25)
		(keepout
			(tracks not_allowed)
			(vias allowed)
			(pads allowed)
			(copperpour not_allowed)
			(footprints allowed)
		)
		(placement
			(enabled no)
			(sheetname "")
		)
		(fill yes
			(thermal_gap 0.5)
			(thermal_bridge_width 0.5)
			(island_removal_mode 0)
		)
		(polygon
			(pts
				(arc
					(start 458.809598 -277.42134)
					(mid 458.824477 -277.457261)
					(end 458.860398 -277.47214)
				)
				(arc
					(start 460.259938 -277.47214)
					(mid 460.295859 -277.457261)
					(end 460.310738 -277.42134)
				)
				(arc
					(start 460.310738 -277.0124)
					(mid 460.295859 -276.976479)
					(end 460.259938 -276.9616)
				)
				(arc
					(start 458.860398 -276.9616)
					(mid 458.824477 -276.976479)
					(end 458.809598 -277.0124)
				)
			)
		)
	)
	(zone
		(layers "In1.Cu" "In2.Cu")
		(hatch none 0.5)
		(connect_pads
			(clearance 0)
		)
		(min_thickness 0.25)
		(keepout
			(tracks not_allowed)
			(vias allowed)
			(pads allowed)
			(copperpour not_allowed)
			(footprints allowed)
		)
		(placement
			(enabled no)
			(sheetname "")
		)
		(fill yes
			(thermal_gap 0.5)
			(thermal_bridge_width 0.5)
			(island_removal_mode 0)
		)
		(polygon
			(pts
				(arc
					(start 455.365866 -304.621438)
					(mid 455.380745 -304.657359)
					(end 455.416666 -304.672238)
				)
				(arc
					(start 456.816206 -304.672238)
					(mid 456.852127 -304.657359)
					(end 456.867006 -304.621438)
				)
				(arc
					(start 456.867006 -304.212498)
					(mid 456.852127 -304.176577)
					(end 456.816206 -304.161698)
				)
				(arc
					(start 455.416666 -304.161698)
					(mid 455.380745 -304.176577)
					(end 455.365866 -304.212498)
				)
			)
		)
	)
	(zone
		(layers "In1.Cu" "In2.Cu")
		(hatch none 0.5)
		(connect_pads
			(clearance 0)
		)
		(min_thickness 0.25)
		(keepout
			(tracks not_allowed)
			(vias allowed)
			(pads allowed)
			(copperpour not_allowed)
			(footprints allowed)
		)
		(placement
			(enabled no)
			(sheetname "")
		)
		(fill yes
			(thermal_gap 0.5)
			(thermal_bridge_width 0.5)
			(island_removal_mode 0)
		)
		(polygon
			(pts
				(arc
					(start 158.06293 -273.171412)
					(mid 158.077809 -273.207333)
					(end 158.11373 -273.222212)
				)
				(arc
					(start 159.51327 -273.222212)
					(mid 159.549191 -273.207333)
					(end 159.56407 -273.171412)
				)
				(arc
					(start 159.56407 -272.762472)
					(mid 159.549191 -272.726551)
					(end 159.51327 -272.711672)
				)
				(arc
					(start 158.11373 -272.711672)
					(mid 158.077809 -272.726551)
					(end 158.06293 -272.762472)
				)
			)
		)
	)
	(zone
		(layers "In1.Cu" "In2.Cu")
		(hatch none 0.5)
		(connect_pads
			(clearance 0)
		)
		(min_thickness 0.25)
		(keepout
			(tracks not_allowed)
			(vias allowed)
			(pads allowed)
			(copperpour not_allowed)
			(footprints allowed)
		)
		(placement
			(enabled no)
			(sheetname "")
		)
		(fill yes
			(thermal_gap 0.5)
			(thermal_bridge_width 0.5)
			(island_removal_mode 0)
		)
		(polygon
			(pts
				(arc
					(start 26.577798 -220.471492)
					(mid 26.592677 -220.507413)
					(end 26.628598 -220.522292)
				)
				(arc
					(start 28.028138 -220.522292)
					(mid 28.064059 -220.507413)
					(end 28.078938 -220.471492)
				)
				(arc
					(start 28.078938 -220.062552)
					(mid 28.064059 -220.026631)
					(end 28.028138 -220.011752)
				)
				(arc
					(start 26.628598 -220.011752)
					(mid 26.592677 -220.026631)
					(end 26.577798 -220.062552)
				)
			)
		)
	)
	(zone
		(layers "In1.Cu" "In2.Cu")
		(hatch none 0.5)
		(connect_pads
			(clearance 0)
		)
		(min_thickness 0.25)
		(keepout
			(tracks not_allowed)
			(vias allowed)
			(pads allowed)
			(copperpour not_allowed)
			(footprints allowed)
		)
		(placement
			(enabled no)
			(sheetname "")
		)
		(fill yes
			(thermal_gap 0.5)
			(thermal_bridge_width 0.5)
			(island_removal_mode 0)
		)
		(polygon
			(pts
				(arc
					(start 165.60673 -196.671438)
					(mid 165.621609 -196.707359)
					(end 165.65753 -196.722238)
				)
				(arc
					(start 167.05707 -196.722238)
					(mid 167.092991 -196.707359)
					(end 167.10787 -196.671438)
				)
				(arc
					(start 167.10787 -196.262498)
					(mid 167.092991 -196.226577)
					(end 167.05707 -196.211698)
				)
				(arc
					(start 165.65753 -196.211698)
					(mid 165.621609 -196.226577)
					(end 165.60673 -196.262498)
				)
			)
		)
	)
	(zone
		(layers "In1.Cu" "In2.Cu")
		(hatch none 0.5)
		(connect_pads
			(clearance 0)
		)
		(min_thickness 0.25)
		(keepout
			(tracks not_allowed)
			(vias allowed)
			(pads allowed)
			(copperpour not_allowed)
			(footprints allowed)
		)
		(placement
			(enabled no)
			(sheetname "")
		)
		(fill yes
			(thermal_gap 0.5)
			(thermal_bridge_width 0.5)
			(island_removal_mode 0)
		)
		(polygon
			(pts
				(arc
					(start 417.646866 -262.121396)
					(mid 417.661745 -262.157317)
					(end 417.697666 -262.172196)
				)
				(arc
					(start 419.097206 -262.172196)
					(mid 419.133127 -262.157317)
					(end 419.148006 -262.121396)
				)
				(arc
					(start 419.148006 -261.712456)
					(mid 419.133127 -261.676535)
					(end 419.097206 -261.661656)
				)
				(arc
					(start 417.697666 -261.661656)
					(mid 417.661745 -261.676535)
					(end 417.646866 -261.712456)
				)
			)
		)
	)
	(zone
		(layers "In1.Cu" "In2.Cu")
		(hatch none 0.5)
		(connect_pads
			(clearance 0)
		)
		(min_thickness 0.25)
		(keepout
			(tracks not_allowed)
			(vias allowed)
			(pads allowed)
			(copperpour not_allowed)
			(footprints allowed)
		)
		(placement
			(enabled no)
			(sheetname "")
		)
		(fill yes
			(thermal_gap 0.5)
			(thermal_bridge_width 0.5)
			(island_removal_mode 0)
		)
		(polygon
			(pts
				(arc
					(start 255.330198 -296.121328)
					(mid 255.345077 -296.157249)
					(end 255.380998 -296.172128)
				)
				(arc
					(start 256.780538 -296.172128)
					(mid 256.816459 -296.157249)
					(end 256.831338 -296.121328)
				)
				(arc
					(start 256.831338 -295.712388)
					(mid 256.816459 -295.676467)
					(end 256.780538 -295.661588)
				)
				(arc
					(start 255.380998 -295.661588)
					(mid 255.345077 -295.676467)
					(end 255.330198 -295.712388)
				)
			)
		)
	)
	(zone
		(layers "In1.Cu" "In2.Cu")
		(hatch none 0.5)
		(connect_pads
			(clearance 0)
		)
		(min_thickness 0.25)
		(keepout
			(tracks not_allowed)
			(vias allowed)
			(pads allowed)
			(copperpour not_allowed)
			(footprints allowed)
		)
		(placement
			(enabled no)
			(sheetname "")
		)
		(fill yes
			(thermal_gap 0.5)
			(thermal_bridge_width 0.5)
			(island_removal_mode 0)
		)
		(polygon
			(pts
				(arc
					(start 443.721998 -200.921366)
					(mid 443.736877 -200.957287)
					(end 443.772798 -200.972166)
				)
				(arc
					(start 445.172338 -200.972166)
					(mid 445.208259 -200.957287)
					(end 445.223138 -200.921366)
				)
				(arc
					(start 445.223138 -200.512426)
					(mid 445.208259 -200.476505)
					(end 445.172338 -200.461626)
				)
				(arc
					(start 443.772798 -200.461626)
					(mid 443.736877 -200.476505)
					(end 443.721998 -200.512426)
				)
			)
		)
	)
	(zone
		(layers "In1.Cu" "In2.Cu")
		(hatch none 0.5)
		(connect_pads
			(clearance 0)
		)
		(min_thickness 0.25)
		(keepout
			(tracks not_allowed)
			(vias allowed)
			(pads allowed)
			(copperpour not_allowed)
			(footprints allowed)
		)
		(placement
			(enabled no)
			(sheetname "")
		)
		(fill yes
			(thermal_gap 0.5)
			(thermal_bridge_width 0.5)
			(island_removal_mode 0)
		)
		(polygon
			(pts
				(arc
					(start 7.39013 -200.921366)
					(mid 7.405009 -200.957287)
					(end 7.44093 -200.972166)
				)
				(arc
					(start 8.84047 -200.972166)
					(mid 8.876391 -200.957287)
					(end 8.89127 -200.921366)
				)
				(arc
					(start 8.89127 -200.512426)
					(mid 8.876391 -200.476505)
					(end 8.84047 -200.461626)
				)
				(arc
					(start 7.44093 -200.461626)
					(mid 7.405009 -200.476505)
					(end 7.39013 -200.512426)
				)
			)
		)
	)
	(zone
		(layers "In1.Cu" "In2.Cu")
		(hatch none 0.5)
		(connect_pads
			(clearance 0)
		)
		(min_thickness 0.25)
		(keepout
			(tracks not_allowed)
			(vias allowed)
			(pads allowed)
			(copperpour not_allowed)
			(footprints allowed)
		)
		(placement
			(enabled no)
			(sheetname "")
		)
		(fill yes
			(thermal_gap 0.5)
			(thermal_bridge_width 0.5)
			(island_removal_mode 0)
		)
		(polygon
			(pts
				(arc
					(start 14.93393 -251.07138)
					(mid 14.948809 -251.107301)
					(end 14.98473 -251.12218)
				)
				(arc
					(start 16.38427 -251.12218)
					(mid 16.420191 -251.107301)
					(end 16.43507 -251.07138)
				)
				(arc
					(start 16.43507 -250.66244)
					(mid 16.420191 -250.626519)
					(end 16.38427 -250.61164)
				)
				(arc
					(start 14.98473 -250.61164)
					(mid 14.948809 -250.626519)
					(end 14.93393 -250.66244)
				)
			)
		)
	)
	(zone
		(layers "In1.Cu" "In2.Cu")
		(hatch none 0.5)
		(connect_pads
			(clearance 0)
		)
		(min_thickness 0.25)
		(keepout
			(tracks not_allowed)
			(vias allowed)
			(pads allowed)
			(copperpour not_allowed)
			(footprints allowed)
		)
		(placement
			(enabled no)
			(sheetname "")
		)
		(fill yes
			(thermal_gap 0.5)
			(thermal_bridge_width 0.5)
			(island_removal_mode 0)
		)
		(polygon
			(pts
				(arc
					(start 447.822066 -270.621506)
					(mid 447.836945 -270.657427)
					(end 447.872866 -270.672306)
				)
				(arc
					(start 449.272406 -270.672306)
					(mid 449.308327 -270.657427)
					(end 449.323206 -270.621506)
				)
				(arc
					(start 449.323206 -270.212566)
					(mid 449.308327 -270.176645)
					(end 449.272406 -270.161766)
				)
				(arc
					(start 447.872866 -270.161766)
					(mid 447.836945 -270.176645)
					(end 447.822066 -270.212566)
				)
			)
		)
	)
	(zone
		(layers "In1.Cu" "In2.Cu")
		(hatch none 0.5)
		(connect_pads
			(clearance 0)
		)
		(min_thickness 0.25)
		(keepout
			(tracks not_allowed)
			(vias allowed)
			(pads allowed)
			(copperpour not_allowed)
			(footprints allowed)
		)
		(placement
			(enabled no)
			(sheetname "")
		)
		(fill yes
			(thermal_gap 0.5)
			(thermal_bridge_width 0.5)
			(island_removal_mode 0)
		)
		(polygon
			(pts
				(arc
					(start 30.02153 -314.821316)
					(mid 30.036409 -314.857237)
					(end 30.07233 -314.872116)
				)
				(arc
					(start 31.47187 -314.872116)
					(mid 31.507791 -314.857237)
					(end 31.52267 -314.821316)
				)
				(arc
					(start 31.52267 -314.412376)
					(mid 31.507791 -314.376455)
					(end 31.47187 -314.361576)
				)
				(arc
					(start 30.07233 -314.361576)
					(mid 30.036409 -314.376455)
					(end 30.02153 -314.412376)
				)
			)
		)
	)
	(zone
		(layers "In1.Cu" "In2.Cu")
		(hatch none 0.5)
		(connect_pads
			(clearance 0)
		)
		(min_thickness 0.25)
		(keepout
			(tracks not_allowed)
			(vias allowed)
			(pads allowed)
			(copperpour not_allowed)
			(footprints allowed)
		)
		(placement
			(enabled no)
			(sheetname "")
		)
		(fill yes
			(thermal_gap 0.5)
			(thermal_bridge_width 0.5)
			(island_removal_mode 0)
		)
		(polygon
			(pts
				(arc
					(start 60.19673 -211.971382)
					(mid 60.211609 -212.007303)
					(end 60.24753 -212.022182)
				)
				(arc
					(start 61.64707 -212.022182)
					(mid 61.682991 -212.007303)
					(end 61.69787 -211.971382)
				)
				(arc
					(start 61.69787 -211.562442)
					(mid 61.682991 -211.526521)
					(end 61.64707 -211.511642)
				)
				(arc
					(start 60.24753 -211.511642)
					(mid 60.211609 -211.526521)
					(end 60.19673 -211.562442)
				)
			)
		)
	)
	(zone
		(layers "In1.Cu" "In2.Cu")
		(hatch none 0.5)
		(connect_pads
			(clearance 0)
		)
		(min_thickness 0.25)
		(keepout
			(tracks not_allowed)
			(vias allowed)
			(pads allowed)
			(copperpour not_allowed)
			(footprints allowed)
		)
		(placement
			(enabled no)
			(sheetname "")
		)
		(fill yes
			(thermal_gap 0.5)
			(thermal_bridge_width 0.5)
			(island_removal_mode 0)
		)
		(polygon
			(pts
				(arc
					(start 56.752998 -197.521322)
					(mid 56.767877 -197.557243)
					(end 56.803798 -197.572122)
				)
				(arc
					(start 58.203338 -197.572122)
					(mid 58.239259 -197.557243)
					(end 58.254138 -197.521322)
				)
				(arc
					(start 58.254138 -197.112382)
					(mid 58.239259 -197.076461)
					(end 58.203338 -197.061582)
				)
				(arc
					(start 56.803798 -197.061582)
					(mid 56.767877 -197.076461)
					(end 56.752998 -197.112382)
				)
			)
		)
	)
	(zone
		(layers "In1.Cu" "In2.Cu")
		(hatch none 0.5)
		(connect_pads
			(clearance 0)
		)
		(min_thickness 0.25)
		(keepout
			(tracks not_allowed)
			(vias allowed)
			(pads allowed)
			(copperpour not_allowed)
			(footprints allowed)
		)
		(placement
			(enabled no)
			(sheetname "")
		)
		(fill yes
			(thermal_gap 0.5)
			(thermal_bridge_width 0.5)
			(island_removal_mode 0)
		)
		(polygon
			(pts
				(arc
					(start 52.65293 -200.921366)
					(mid 52.667809 -200.957287)
					(end 52.70373 -200.972166)
				)
				(arc
					(start 54.10327 -200.972166)
					(mid 54.139191 -200.957287)
					(end 54.15407 -200.921366)
				)
				(arc
					(start 54.15407 -200.512426)
					(mid 54.139191 -200.476505)
					(end 54.10327 -200.461626)
				)
				(arc
					(start 52.70373 -200.461626)
					(mid 52.667809 -200.476505)
					(end 52.65293 -200.512426)
				)
			)
		)
	)
	(zone
		(layers "In1.Cu" "In2.Cu")
		(hatch none 0.5)
		(connect_pads
			(clearance 0)
		)
		(min_thickness 0.25)
		(keepout
			(tracks not_allowed)
			(vias allowed)
			(pads allowed)
			(copperpour not_allowed)
			(footprints allowed)
		)
		(placement
			(enabled no)
			(sheetname "")
		)
		(fill yes
			(thermal_gap 0.5)
			(thermal_bridge_width 0.5)
			(island_removal_mode 0)
		)
		(polygon
			(pts
				(arc
					(start 282.061666 -203.471526)
					(mid 282.076545 -203.507447)
					(end 282.112466 -203.522326)
				)
				(arc
					(start 283.512006 -203.522326)
					(mid 283.547927 -203.507447)
					(end 283.562806 -203.471526)
				)
				(arc
					(start 283.562806 -203.062586)
					(mid 283.547927 -203.026665)
					(end 283.512006 -203.011786)
				)
				(arc
					(start 282.112466 -203.011786)
					(mid 282.076545 -203.026665)
					(end 282.061666 -203.062586)
				)
			)
		)
	)
	(zone
		(layers "In1.Cu" "In2.Cu")
		(hatch none 0.5)
		(connect_pads
			(clearance 0)
		)
		(min_thickness 0.25)
		(keepout
			(tracks not_allowed)
			(vias allowed)
			(pads allowed)
			(copperpour not_allowed)
			(footprints allowed)
		)
		(placement
			(enabled no)
			(sheetname "")
		)
		(fill yes
			(thermal_gap 0.5)
			(thermal_bridge_width 0.5)
			(island_removal_mode 0)
		)
		(polygon
			(pts
				(arc
					(start 169.706798 -211.121498)
					(mid 169.721677 -211.157419)
					(end 169.757598 -211.172298)
				)
				(arc
					(start 171.157138 -211.172298)
					(mid 171.193059 -211.157419)
					(end 171.207938 -211.121498)
				)
				(arc
					(start 171.207938 -210.712558)
					(mid 171.193059 -210.676637)
					(end 171.157138 -210.661758)
				)
				(arc
					(start 169.757598 -210.661758)
					(mid 169.721677 -210.676637)
					(end 169.706798 -210.712558)
				)
			)
		)
	)
	(zone
		(layers "In1.Cu" "In2.Cu")
		(hatch none 0.5)
		(connect_pads
			(clearance 0)
		)
		(min_thickness 0.25)
		(keepout
			(tracks not_allowed)
			(vias allowed)
			(pads allowed)
			(copperpour not_allowed)
			(footprints allowed)
		)
		(placement
			(enabled no)
			(sheetname "")
		)
		(fill yes
			(thermal_gap 0.5)
			(thermal_bridge_width 0.5)
			(island_removal_mode 0)
		)
		(polygon
			(pts
				(arc
					(start 30.02153 -204.32141)
					(mid 30.036409 -204.357331)
					(end 30.07233 -204.37221)
				)
				(arc
					(start 31.47187 -204.37221)
					(mid 31.507791 -204.357331)
					(end 31.52267 -204.32141)
				)
				(arc
					(start 31.52267 -203.91247)
					(mid 31.507791 -203.876549)
					(end 31.47187 -203.86167)
				)
				(arc
					(start 30.07233 -203.86167)
					(mid 30.036409 -203.876549)
					(end 30.02153 -203.91247)
				)
			)
		)
	)
	(zone
		(layers "In1.Cu" "In2.Cu")
		(hatch none 0.5)
		(connect_pads
			(clearance 0)
		)
		(min_thickness 0.25)
		(keepout
			(tracks not_allowed)
			(vias allowed)
			(pads allowed)
			(copperpour not_allowed)
			(footprints allowed)
		)
		(placement
			(enabled no)
			(sheetname "")
		)
		(fill yes
			(thermal_gap 0.5)
			(thermal_bridge_width 0.5)
			(island_removal_mode 0)
		)
		(polygon
			(pts
				(arc
					(start 60.19673 -232.371392)
					(mid 60.211609 -232.407313)
					(end 60.24753 -232.422192)
				)
				(arc
					(start 61.64707 -232.422192)
					(mid 61.682991 -232.407313)
					(end 61.69787 -232.371392)
				)
				(arc
					(start 61.69787 -231.962452)
					(mid 61.682991 -231.926531)
					(end 61.64707 -231.911652)
				)
				(arc
					(start 60.24753 -231.911652)
					(mid 60.211609 -231.926531)
					(end 60.19673 -231.962452)
				)
			)
		)
	)
	(zone
		(layers "In1.Cu" "In2.Cu")
		(hatch none 0.5)
		(connect_pads
			(clearance 0)
		)
		(min_thickness 0.25)
		(keepout
			(tracks not_allowed)
			(vias allowed)
			(pads allowed)
			(copperpour not_allowed)
			(footprints allowed)
		)
		(placement
			(enabled no)
			(sheetname "")
		)
		(fill yes
			(thermal_gap 0.5)
			(thermal_bridge_width 0.5)
			(island_removal_mode 0)
		)
		(polygon
			(pts
				(arc
					(start 259.430266 -278.271478)
					(mid 259.445145 -278.307399)
					(end 259.481066 -278.322278)
				)
				(arc
					(start 260.880606 -278.322278)
					(mid 260.916527 -278.307399)
					(end 260.931406 -278.271478)
				)
				(arc
					(start 260.931406 -277.862538)
					(mid 260.916527 -277.826617)
					(end 260.880606 -277.811738)
				)
				(arc
					(start 259.481066 -277.811738)
					(mid 259.445145 -277.826617)
					(end 259.430266 -277.862538)
				)
			)
		)
	)
	(zone
		(layers "In1.Cu" "In2.Cu")
		(hatch none 0.5)
		(connect_pads
			(clearance 0)
		)
		(min_thickness 0.25)
		(keepout
			(tracks not_allowed)
			(vias allowed)
			(pads allowed)
			(copperpour not_allowed)
			(footprints allowed)
		)
		(placement
			(enabled no)
			(sheetname "")
		)
		(fill yes
			(thermal_gap 0.5)
			(thermal_bridge_width 0.5)
			(island_removal_mode 0)
		)
		(polygon
			(pts
				(arc
					(start 455.365866 -313.971432)
					(mid 455.380745 -314.007353)
					(end 455.416666 -314.022232)
				)
				(arc
					(start 456.816206 -314.022232)
					(mid 456.852127 -314.007353)
					(end 456.867006 -313.971432)
				)
				(arc
					(start 456.867006 -313.562492)
					(mid 456.852127 -313.526571)
					(end 456.816206 -313.511692)
				)
				(arc
					(start 455.416666 -313.511692)
					(mid 455.380745 -313.526571)
					(end 455.365866 -313.562492)
				)
			)
		)
	)
	(zone
		(layers "In1.Cu" "In2.Cu")
		(hatch none 0.5)
		(connect_pads
			(clearance 0)
		)
		(min_thickness 0.25)
		(keepout
			(tracks not_allowed)
			(vias allowed)
			(pads allowed)
			(copperpour not_allowed)
			(footprints allowed)
		)
		(placement
			(enabled no)
			(sheetname "")
		)
		(fill yes
			(thermal_gap 0.5)
			(thermal_bridge_width 0.5)
			(island_removal_mode 0)
		)
		(polygon
			(pts
				(arc
					(start 413.546798 -247.671336)
					(mid 413.561677 -247.707257)
					(end 413.597598 -247.722136)
				)
				(arc
					(start 414.997138 -247.722136)
					(mid 415.033059 -247.707257)
					(end 415.047938 -247.671336)
				)
				(arc
					(start 415.047938 -247.262396)
					(mid 415.033059 -247.226475)
					(end 414.997138 -247.211596)
				)
				(arc
					(start 413.597598 -247.211596)
					(mid 413.561677 -247.226475)
					(end 413.546798 -247.262396)
				)
			)
		)
	)
	(zone
		(layers "In1.Cu" "In2.Cu")
		(hatch none 0.5)
		(connect_pads
			(clearance 0)
		)
		(min_thickness 0.25)
		(keepout
			(tracks not_allowed)
			(vias allowed)
			(pads allowed)
			(copperpour not_allowed)
			(footprints allowed)
		)
		(placement
			(enabled no)
			(sheetname "")
		)
		(fill yes
			(thermal_gap 0.5)
			(thermal_bridge_width 0.5)
			(island_removal_mode 0)
		)
		(polygon
			(pts
				(arc
					(start 432.734466 -195.821554)
					(mid 432.749345 -195.857475)
					(end 432.785266 -195.872354)
				)
				(arc
					(start 434.184806 -195.872354)
					(mid 434.220727 -195.857475)
					(end 434.235606 -195.821554)
				)
				(arc
					(start 434.235606 -195.412614)
					(mid 434.220727 -195.376693)
					(end 434.184806 -195.361814)
				)
				(arc
					(start 432.785266 -195.361814)
					(mid 432.749345 -195.376693)
					(end 432.734466 -195.412614)
				)
			)
		)
	)
	(zone
		(layers "In1.Cu" "In2.Cu")
		(hatch none 0.5)
		(connect_pads
			(clearance 0)
		)
		(min_thickness 0.25)
		(keepout
			(tracks not_allowed)
			(vias allowed)
			(pads allowed)
			(copperpour not_allowed)
			(footprints allowed)
		)
		(placement
			(enabled no)
			(sheetname "")
		)
		(fill yes
			(thermal_gap 0.5)
			(thermal_bridge_width 0.5)
			(island_removal_mode 0)
		)
		(polygon
			(pts
				(arc
					(start 64.296798 -302.921416)
					(mid 64.311677 -302.957337)
					(end 64.347598 -302.972216)
				)
				(arc
					(start 65.747138 -302.972216)
					(mid 65.783059 -302.957337)
					(end 65.797938 -302.921416)
				)
				(arc
					(start 65.797938 -302.512476)
					(mid 65.783059 -302.476555)
					(end 65.747138 -302.461676)
				)
				(arc
					(start 64.347598 -302.461676)
					(mid 64.311677 -302.476555)
					(end 64.296798 -302.512476)
				)
			)
		)
	)
	(zone
		(layers "In1.Cu" "In2.Cu")
		(hatch none 0.5)
		(connect_pads
			(clearance 0)
		)
		(min_thickness 0.25)
		(keepout
			(tracks not_allowed)
			(vias allowed)
			(pads allowed)
			(copperpour not_allowed)
			(footprints allowed)
		)
		(placement
			(enabled no)
			(sheetname "")
		)
		(fill yes
			(thermal_gap 0.5)
			(thermal_bridge_width 0.5)
			(island_removal_mode 0)
		)
		(polygon
			(pts
				(arc
					(start 173.15053 -243.421408)
					(mid 173.165409 -243.457329)
					(end 173.20133 -243.472208)
				)
				(arc
					(start 174.60087 -243.472208)
					(mid 174.636791 -243.457329)
					(end 174.65167 -243.421408)
				)
				(arc
					(start 174.65167 -243.012468)
					(mid 174.636791 -242.976547)
					(end 174.60087 -242.961668)
				)
				(arc
					(start 173.20133 -242.961668)
					(mid 173.165409 -242.976547)
					(end 173.15053 -243.012468)
				)
			)
		)
	)
	(zone
		(layers "In1.Cu" "In2.Cu")
		(hatch none 0.5)
		(connect_pads
			(clearance 0)
		)
		(min_thickness 0.25)
		(keepout
			(tracks not_allowed)
			(vias allowed)
			(pads allowed)
			(copperpour not_allowed)
			(footprints allowed)
		)
		(placement
			(enabled no)
			(sheetname "")
		)
		(fill yes
			(thermal_gap 0.5)
			(thermal_bridge_width 0.5)
			(island_removal_mode 0)
		)
		(polygon
			(pts
				(arc
					(start 308.136798 -307.171344)
					(mid 308.151677 -307.207265)
					(end 308.187598 -307.222144)
				)
				(arc
					(start 309.587138 -307.222144)
					(mid 309.623059 -307.207265)
					(end 309.637938 -307.171344)
				)
				(arc
					(start 309.637938 -306.762404)
					(mid 309.623059 -306.726483)
					(end 309.587138 -306.711604)
				)
				(arc
					(start 308.187598 -306.711604)
					(mid 308.151677 -306.726483)
					(end 308.136798 -306.762404)
				)
			)
		)
	)
	(zone
		(layers "In1.Cu" "In2.Cu")
		(hatch none 0.5)
		(connect_pads
			(clearance 0)
		)
		(min_thickness 0.25)
		(keepout
			(tracks not_allowed)
			(vias allowed)
			(pads allowed)
			(copperpour not_allowed)
			(footprints allowed)
		)
		(placement
			(enabled no)
			(sheetname "")
		)
		(fill yes
			(thermal_gap 0.5)
			(thermal_bridge_width 0.5)
			(island_removal_mode 0)
		)
		(polygon
			(pts
				(arc
					(start 180.69433 -245.971314)
					(mid 180.709209 -246.007235)
					(end 180.74513 -246.022114)
				)
				(arc
					(start 182.14467 -246.022114)
					(mid 182.180591 -246.007235)
					(end 182.19547 -245.971314)
				)
				(arc
					(start 182.19547 -245.562374)
					(mid 182.180591 -245.526453)
					(end 182.14467 -245.511574)
				)
				(arc
					(start 180.74513 -245.511574)
					(mid 180.709209 -245.526453)
					(end 180.69433 -245.562374)
				)
			)
		)
	)
	(zone
		(layers "In1.Cu" "In2.Cu")
		(hatch none 0.5)
		(connect_pads
			(clearance 0)
		)
		(min_thickness 0.25)
		(keepout
			(tracks not_allowed)
			(vias allowed)
			(pads allowed)
			(copperpour not_allowed)
			(footprints allowed)
		)
		(placement
			(enabled no)
			(sheetname "")
		)
		(fill yes
			(thermal_gap 0.5)
			(thermal_bridge_width 0.5)
			(island_removal_mode 0)
		)
		(polygon
			(pts
				(arc
					(start 266.974066 -272.321528)
					(mid 266.988945 -272.357449)
					(end 267.024866 -272.372328)
				)
				(arc
					(start 268.424406 -272.372328)
					(mid 268.460327 -272.357449)
					(end 268.475206 -272.321528)
				)
				(arc
					(start 268.475206 -271.912588)
					(mid 268.460327 -271.876667)
					(end 268.424406 -271.861788)
				)
				(arc
					(start 267.024866 -271.861788)
					(mid 266.988945 -271.876667)
					(end 266.974066 -271.912588)
				)
			)
		)
	)
	(zone
		(layers "In1.Cu" "In2.Cu")
		(hatch none 0.5)
		(connect_pads
			(clearance 0)
		)
		(min_thickness 0.25)
		(keepout
			(tracks not_allowed)
			(vias allowed)
			(pads allowed)
			(copperpour not_allowed)
			(footprints allowed)
		)
		(placement
			(enabled no)
			(sheetname "")
		)
		(fill yes
			(thermal_gap 0.5)
			(thermal_bridge_width 0.5)
			(island_removal_mode 0)
		)
		(polygon
			(pts
				(arc
					(start 173.15053 -218.77147)
					(mid 173.165409 -218.807391)
					(end 173.20133 -218.82227)
				)
				(arc
					(start 174.60087 -218.82227)
					(mid 174.636791 -218.807391)
					(end 174.65167 -218.77147)
				)
				(arc
					(start 174.65167 -218.36253)
					(mid 174.636791 -218.326609)
					(end 174.60087 -218.31173)
				)
				(arc
					(start 173.20133 -218.31173)
					(mid 173.165409 -218.326609)
					(end 173.15053 -218.36253)
				)
			)
		)
	)
	(zone
		(layers "In1.Cu" "In2.Cu")
		(hatch none 0.5)
		(connect_pads
			(clearance 0)
		)
		(min_thickness 0.25)
		(keepout
			(tracks not_allowed)
			(vias allowed)
			(pads allowed)
			(copperpour not_allowed)
			(footprints allowed)
		)
		(placement
			(enabled no)
			(sheetname "")
		)
		(fill yes
			(thermal_gap 0.5)
			(thermal_bridge_width 0.5)
			(island_removal_mode 0)
		)
		(polygon
			(pts
				(arc
					(start 207.425798 -281.671522)
					(mid 207.440677 -281.707443)
					(end 207.476598 -281.722322)
				)
				(arc
					(start 208.876138 -281.722322)
					(mid 208.912059 -281.707443)
					(end 208.926938 -281.671522)
				)
				(arc
					(start 208.926938 -281.262582)
					(mid 208.912059 -281.226661)
					(end 208.876138 -281.211782)
				)
				(arc
					(start 207.476598 -281.211782)
					(mid 207.440677 -281.226661)
					(end 207.425798 -281.262582)
				)
			)
		)
	)
	(zone
		(layers "In1.Cu" "In2.Cu")
		(hatch none 0.5)
		(connect_pads
			(clearance 0)
		)
		(min_thickness 0.25)
		(keepout
			(tracks not_allowed)
			(vias allowed)
			(pads allowed)
			(copperpour not_allowed)
			(footprints allowed)
		)
		(placement
			(enabled no)
			(sheetname "")
		)
		(fill yes
			(thermal_gap 0.5)
			(thermal_bridge_width 0.5)
			(island_removal_mode 0)
		)
		(polygon
			(pts
				(arc
					(start 425.190666 -308.021482)
					(mid 425.205545 -308.057403)
					(end 425.241466 -308.072282)
				)
				(arc
					(start 426.641006 -308.072282)
					(mid 426.676927 -308.057403)
					(end 426.691806 -308.021482)
				)
				(arc
					(start 426.691806 -307.612542)
					(mid 426.676927 -307.576621)
					(end 426.641006 -307.561742)
				)
				(arc
					(start 425.241466 -307.561742)
					(mid 425.205545 -307.576621)
					(end 425.190666 -307.612542)
				)
			)
		)
	)
	(zone
		(layers "In1.Cu" "In2.Cu")
		(hatch none 0.5)
		(connect_pads
			(clearance 0)
		)
		(min_thickness 0.25)
		(keepout
			(tracks not_allowed)
			(vias allowed)
			(pads allowed)
			(copperpour not_allowed)
			(footprints allowed)
		)
		(placement
			(enabled no)
			(sheetname "")
		)
		(fill yes
			(thermal_gap 0.5)
			(thermal_bridge_width 0.5)
			(island_removal_mode 0)
		)
		(polygon
			(pts
				(arc
					(start 255.330198 -245.971314)
					(mid 255.345077 -246.007235)
					(end 255.380998 -246.022114)
				)
				(arc
					(start 256.780538 -246.022114)
					(mid 256.816459 -246.007235)
					(end 256.831338 -245.971314)
				)
				(arc
					(start 256.831338 -245.562374)
					(mid 256.816459 -245.526453)
					(end 256.780538 -245.511574)
				)
				(arc
					(start 255.380998 -245.511574)
					(mid 255.345077 -245.526453)
					(end 255.330198 -245.562374)
				)
			)
		)
	)
	(zone
		(layers "In1.Cu" "In2.Cu")
		(hatch none 0.5)
		(connect_pads
			(clearance 0)
		)
		(min_thickness 0.25)
		(keepout
			(tracks not_allowed)
			(vias allowed)
			(pads allowed)
			(copperpour not_allowed)
			(footprints allowed)
		)
		(placement
			(enabled no)
			(sheetname "")
		)
		(fill yes
			(thermal_gap 0.5)
			(thermal_bridge_width 0.5)
			(island_removal_mode 0)
		)
		(polygon
			(pts
				(arc
					(start 52.65293 -232.371392)
					(mid 52.667809 -232.407313)
					(end 52.70373 -232.422192)
				)
				(arc
					(start 54.10327 -232.422192)
					(mid 54.139191 -232.407313)
					(end 54.15407 -232.371392)
				)
				(arc
					(start 54.15407 -231.962452)
					(mid 54.139191 -231.926531)
					(end 54.10327 -231.911652)
				)
				(arc
					(start 52.70373 -231.911652)
					(mid 52.667809 -231.926531)
					(end 52.65293 -231.962452)
				)
			)
		)
	)
	(zone
		(layers "In1.Cu" "In2.Cu")
		(hatch none 0.5)
		(connect_pads
			(clearance 0)
		)
		(min_thickness 0.25)
		(keepout
			(tracks not_allowed)
			(vias allowed)
			(pads allowed)
			(copperpour not_allowed)
			(footprints allowed)
		)
		(placement
			(enabled no)
			(sheetname "")
		)
		(fill yes
			(thermal_gap 0.5)
			(thermal_bridge_width 0.5)
			(island_removal_mode 0)
		)
		(polygon
			(pts
				(arc
					(start 270.417798 -288.471356)
					(mid 270.432677 -288.507277)
					(end 270.468598 -288.522156)
				)
				(arc
					(start 271.868138 -288.522156)
					(mid 271.904059 -288.507277)
					(end 271.918938 -288.471356)
				)
				(arc
					(start 271.918938 -288.062416)
					(mid 271.904059 -288.026495)
					(end 271.868138 -288.011616)
				)
				(arc
					(start 270.468598 -288.011616)
					(mid 270.432677 -288.026495)
					(end 270.417798 -288.062416)
				)
			)
		)
	)
	(zone
		(layers "In1.Cu" "In2.Cu")
		(hatch none 0.5)
		(connect_pads
			(clearance 0)
		)
		(min_thickness 0.25)
		(keepout
			(tracks not_allowed)
			(vias allowed)
			(pads allowed)
			(copperpour not_allowed)
			(footprints allowed)
		)
		(placement
			(enabled no)
			(sheetname "")
		)
		(fill yes
			(thermal_gap 0.5)
			(thermal_bridge_width 0.5)
			(island_removal_mode 0)
		)
		(polygon
			(pts
				(arc
					(start 30.02153 -206.021432)
					(mid 30.036409 -206.057353)
					(end 30.07233 -206.072232)
				)
				(arc
					(start 31.47187 -206.072232)
					(mid 31.507791 -206.057353)
					(end 31.52267 -206.021432)
				)
				(arc
					(start 31.52267 -205.612492)
					(mid 31.507791 -205.576571)
					(end 31.47187 -205.561692)
				)
				(arc
					(start 30.07233 -205.561692)
					(mid 30.036409 -205.576571)
					(end 30.02153 -205.612492)
				)
			)
		)
	)
	(zone
		(layers "In1.Cu" "In2.Cu")
		(hatch none 0.5)
		(connect_pads
			(clearance 0)
		)
		(min_thickness 0.25)
		(keepout
			(tracks not_allowed)
			(vias allowed)
			(pads allowed)
			(copperpour not_allowed)
			(footprints allowed)
		)
		(placement
			(enabled no)
			(sheetname "")
		)
		(fill yes
			(thermal_gap 0.5)
			(thermal_bridge_width 0.5)
			(island_removal_mode 0)
		)
		(polygon
			(pts
				(arc
					(start 184.794398 -283.371544)
					(mid 184.809277 -283.407465)
					(end 184.845198 -283.422344)
				)
				(arc
					(start 186.244738 -283.422344)
					(mid 186.280659 -283.407465)
					(end 186.295538 -283.371544)
				)
				(arc
					(start 186.295538 -282.962604)
					(mid 186.280659 -282.926683)
					(end 186.244738 -282.911804)
				)
				(arc
					(start 184.845198 -282.911804)
					(mid 184.809277 -282.926683)
					(end 184.794398 -282.962604)
				)
			)
		)
	)
	(zone
		(layers "In1.Cu" "In2.Cu")
		(hatch none 0.5)
		(connect_pads
			(clearance 0)
		)
		(min_thickness 0.25)
		(keepout
			(tracks not_allowed)
			(vias allowed)
			(pads allowed)
			(copperpour not_allowed)
			(footprints allowed)
		)
		(placement
			(enabled no)
			(sheetname "")
		)
		(fill yes
			(thermal_gap 0.5)
			(thermal_bridge_width 0.5)
			(island_removal_mode 0)
		)
		(polygon
			(pts
				(arc
					(start 41.665398 -228.121464)
					(mid 41.680277 -228.157385)
					(end 41.716198 -228.172264)
				)
				(arc
					(start 43.115738 -228.172264)
					(mid 43.151659 -228.157385)
					(end 43.166538 -228.121464)
				)
				(arc
					(start 43.166538 -227.712524)
					(mid 43.151659 -227.676603)
					(end 43.115738 -227.661724)
				)
				(arc
					(start 41.716198 -227.661724)
					(mid 41.680277 -227.676603)
					(end 41.665398 -227.712524)
				)
			)
		)
	)
	(zone
		(layers "In1.Cu" "In2.Cu")
		(hatch none 0.5)
		(connect_pads
			(clearance 0)
		)
		(min_thickness 0.25)
		(keepout
			(tracks not_allowed)
			(vias allowed)
			(pads allowed)
			(copperpour not_allowed)
			(footprints allowed)
		)
		(placement
			(enabled no)
			(sheetname "")
		)
		(fill yes
			(thermal_gap 0.5)
			(thermal_bridge_width 0.5)
			(island_removal_mode 0)
		)
		(polygon
			(pts
				(arc
					(start 41.665398 -300.37151)
					(mid 41.680277 -300.407431)
					(end 41.716198 -300.42231)
				)
				(arc
					(start 43.115738 -300.42231)
					(mid 43.151659 -300.407431)
					(end 43.166538 -300.37151)
				)
				(arc
					(start 43.166538 -299.96257)
					(mid 43.151659 -299.926649)
					(end 43.115738 -299.91177)
				)
				(arc
					(start 41.716198 -299.91177)
					(mid 41.680277 -299.926649)
					(end 41.665398 -299.96257)
				)
			)
		)
	)
	(zone
		(layers "In1.Cu" "In2.Cu")
		(hatch none 0.5)
		(connect_pads
			(clearance 0)
		)
		(min_thickness 0.25)
		(keepout
			(tracks not_allowed)
			(vias allowed)
			(pads allowed)
			(copperpour not_allowed)
			(footprints allowed)
		)
		(placement
			(enabled no)
			(sheetname "")
		)
		(fill yes
			(thermal_gap 0.5)
			(thermal_bridge_width 0.5)
			(island_removal_mode 0)
		)
		(polygon
			(pts
				(arc
					(start 417.646866 -214.521542)
					(mid 417.661745 -214.557463)
					(end 417.697666 -214.572342)
				)
				(arc
					(start 419.097206 -214.572342)
					(mid 419.133127 -214.557463)
					(end 419.148006 -214.521542)
				)
				(arc
					(start 419.148006 -214.112602)
					(mid 419.133127 -214.076681)
					(end 419.097206 -214.061802)
				)
				(arc
					(start 417.697666 -214.061802)
					(mid 417.661745 -214.076681)
					(end 417.646866 -214.112602)
				)
			)
		)
	)
	(zone
		(layers "In1.Cu" "In2.Cu")
		(hatch none 0.5)
		(connect_pads
			(clearance 0)
		)
		(min_thickness 0.25)
		(keepout
			(tracks not_allowed)
			(vias allowed)
			(pads allowed)
			(copperpour not_allowed)
			(footprints allowed)
		)
		(placement
			(enabled no)
			(sheetname "")
		)
		(fill yes
			(thermal_gap 0.5)
			(thermal_bridge_width 0.5)
			(island_removal_mode 0)
		)
		(polygon
			(pts
				(arc
					(start 210.86953 -221.321376)
					(mid 210.884409 -221.357297)
					(end 210.92033 -221.372176)
				)
				(arc
					(start 212.31987 -221.372176)
					(mid 212.355791 -221.357297)
					(end 212.37067 -221.321376)
				)
				(arc
					(start 212.37067 -220.912436)
					(mid 212.355791 -220.876515)
					(end 212.31987 -220.861636)
				)
				(arc
					(start 210.92033 -220.861636)
					(mid 210.884409 -220.876515)
					(end 210.86953 -220.912436)
				)
			)
		)
	)
	(zone
		(layers "In1.Cu" "In2.Cu")
		(hatch none 0.5)
		(connect_pads
			(clearance 0)
		)
		(min_thickness 0.25)
		(keepout
			(tracks not_allowed)
			(vias allowed)
			(pads allowed)
			(copperpour not_allowed)
			(footprints allowed)
		)
		(placement
			(enabled no)
			(sheetname "")
		)
		(fill yes
			(thermal_gap 0.5)
			(thermal_bridge_width 0.5)
			(island_removal_mode 0)
		)
		(polygon
			(pts
				(arc
					(start 447.822066 -295.271444)
					(mid 447.836945 -295.307365)
					(end 447.872866 -295.322244)
				)
				(arc
					(start 449.272406 -295.322244)
					(mid 449.308327 -295.307365)
					(end 449.323206 -295.271444)
				)
				(arc
					(start 449.323206 -294.862504)
					(mid 449.308327 -294.826583)
					(end 449.272406 -294.811704)
				)
				(arc
					(start 447.872866 -294.811704)
					(mid 447.836945 -294.826583)
					(end 447.822066 -294.862504)
				)
			)
		)
	)
	(zone
		(layers "In1.Cu" "In2.Cu")
		(hatch none 0.5)
		(connect_pads
			(clearance 0)
		)
		(min_thickness 0.25)
		(keepout
			(tracks not_allowed)
			(vias allowed)
			(pads allowed)
			(copperpour not_allowed)
			(footprints allowed)
		)
		(placement
			(enabled no)
			(sheetname "")
		)
		(fill yes
			(thermal_gap 0.5)
			(thermal_bridge_width 0.5)
			(island_removal_mode 0)
		)
		(polygon
			(pts
				(arc
					(start 165.60673 -274.871434)
					(mid 165.621609 -274.907355)
					(end 165.65753 -274.922234)
				)
				(arc
					(start 167.05707 -274.922234)
					(mid 167.092991 -274.907355)
					(end 167.10787 -274.871434)
				)
				(arc
					(start 167.10787 -274.462494)
					(mid 167.092991 -274.426573)
					(end 167.05707 -274.411694)
				)
				(arc
					(start 165.65753 -274.411694)
					(mid 165.621609 -274.426573)
					(end 165.60673 -274.462494)
				)
			)
		)
	)
	(zone
		(layers "In1.Cu" "In2.Cu")
		(hatch none 0.5)
		(connect_pads
			(clearance 0)
		)
		(min_thickness 0.25)
		(keepout
			(tracks not_allowed)
			(vias allowed)
			(pads allowed)
			(copperpour not_allowed)
			(footprints allowed)
		)
		(placement
			(enabled no)
			(sheetname "")
		)
		(fill yes
			(thermal_gap 0.5)
			(thermal_bridge_width 0.5)
			(island_removal_mode 0)
		)
		(polygon
			(pts
				(arc
					(start 259.430266 -281.671522)
					(mid 259.445145 -281.707443)
					(end 259.481066 -281.722322)
				)
				(arc
					(start 260.880606 -281.722322)
					(mid 260.916527 -281.707443)
					(end 260.931406 -281.671522)
				)
				(arc
					(start 260.931406 -281.262582)
					(mid 260.916527 -281.226661)
					(end 260.880606 -281.211782)
				)
				(arc
					(start 259.481066 -281.211782)
					(mid 259.445145 -281.226661)
					(end 259.430266 -281.262582)
				)
			)
		)
	)
	(zone
		(layers "In1.Cu" "In2.Cu")
		(hatch none 0.5)
		(connect_pads
			(clearance 0)
		)
		(min_thickness 0.25)
		(keepout
			(tracks not_allowed)
			(vias allowed)
			(pads allowed)
			(copperpour not_allowed)
			(footprints allowed)
		)
		(placement
			(enabled no)
			(sheetname "")
		)
		(fill yes
			(thermal_gap 0.5)
			(thermal_bridge_width 0.5)
			(island_removal_mode 0)
		)
		(polygon
			(pts
				(arc
					(start 262.873998 -213.671404)
					(mid 262.888877 -213.707325)
					(end 262.924798 -213.722204)
				)
				(arc
					(start 264.324338 -213.722204)
					(mid 264.360259 -213.707325)
					(end 264.375138 -213.671404)
				)
				(arc
					(start 264.375138 -213.262464)
					(mid 264.360259 -213.226543)
					(end 264.324338 -213.211664)
				)
				(arc
					(start 262.924798 -213.211664)
					(mid 262.888877 -213.226543)
					(end 262.873998 -213.262464)
				)
			)
		)
	)
	(zone
		(layers "In1.Cu" "In2.Cu")
		(hatch none 0.5)
		(connect_pads
			(clearance 0)
		)
		(min_thickness 0.25)
		(keepout
			(tracks not_allowed)
			(vias allowed)
			(pads allowed)
			(copperpour not_allowed)
			(footprints allowed)
		)
		(placement
			(enabled no)
			(sheetname "")
		)
		(fill yes
			(thermal_gap 0.5)
			(thermal_bridge_width 0.5)
			(island_removal_mode 0)
		)
		(polygon
			(pts
				(arc
					(start 165.60673 -279.121362)
					(mid 165.621609 -279.157283)
					(end 165.65753 -279.172162)
				)
				(arc
					(start 167.05707 -279.172162)
					(mid 167.092991 -279.157283)
					(end 167.10787 -279.121362)
				)
				(arc
					(start 167.10787 -278.712422)
					(mid 167.092991 -278.676501)
					(end 167.05707 -278.661622)
				)
				(arc
					(start 165.65753 -278.661622)
					(mid 165.621609 -278.676501)
					(end 165.60673 -278.712422)
				)
			)
		)
	)
	(zone
		(layers "In1.Cu" "In2.Cu")
		(hatch none 0.5)
		(connect_pads
			(clearance 0)
		)
		(min_thickness 0.25)
		(keepout
			(tracks not_allowed)
			(vias allowed)
			(pads allowed)
			(copperpour not_allowed)
			(footprints allowed)
		)
		(placement
			(enabled no)
			(sheetname "")
		)
		(fill yes
			(thermal_gap 0.5)
			(thermal_bridge_width 0.5)
			(island_removal_mode 0)
		)
		(polygon
			(pts
				(arc
					(start 192.338198 -199.221344)
					(mid 192.353077 -199.257265)
					(end 192.388998 -199.272144)
				)
				(arc
					(start 193.788538 -199.272144)
					(mid 193.824459 -199.257265)
					(end 193.839338 -199.221344)
				)
				(arc
					(start 193.839338 -198.812404)
					(mid 193.824459 -198.776483)
					(end 193.788538 -198.761604)
				)
				(arc
					(start 192.388998 -198.761604)
					(mid 192.353077 -198.776483)
					(end 192.338198 -198.812404)
				)
			)
		)
	)
	(zone
		(layers "In1.Cu" "In2.Cu")
		(hatch none 0.5)
		(connect_pads
			(clearance 0)
		)
		(min_thickness 0.25)
		(keepout
			(tracks not_allowed)
			(vias allowed)
			(pads allowed)
			(copperpour not_allowed)
			(footprints allowed)
		)
		(placement
			(enabled no)
			(sheetname "")
		)
		(fill yes
			(thermal_gap 0.5)
			(thermal_bridge_width 0.5)
			(island_removal_mode 0)
		)
		(polygon
			(pts
				(arc
					(start 173.15053 -209.421476)
					(mid 173.165409 -209.457397)
					(end 173.20133 -209.472276)
				)
				(arc
					(start 174.60087 -209.472276)
					(mid 174.636791 -209.457397)
					(end 174.65167 -209.421476)
				)
				(arc
					(start 174.65167 -209.012536)
					(mid 174.636791 -208.976615)
					(end 174.60087 -208.961736)
				)
				(arc
					(start 173.20133 -208.961736)
					(mid 173.165409 -208.976615)
					(end 173.15053 -209.012536)
				)
			)
		)
	)
	(zone
		(layers "In1.Cu" "In2.Cu")
		(hatch none 0.5)
		(connect_pads
			(clearance 0)
		)
		(min_thickness 0.25)
		(keepout
			(tracks not_allowed)
			(vias allowed)
			(pads allowed)
			(copperpour not_allowed)
			(footprints allowed)
		)
		(placement
			(enabled no)
			(sheetname "")
		)
		(fill yes
			(thermal_gap 0.5)
			(thermal_bridge_width 0.5)
			(island_removal_mode 0)
		)
		(polygon
			(pts
				(arc
					(start 214.969598 -239.17148)
					(mid 214.984477 -239.207401)
					(end 215.020398 -239.22228)
				)
				(arc
					(start 216.419938 -239.22228)
					(mid 216.455859 -239.207401)
					(end 216.470738 -239.17148)
				)
				(arc
					(start 216.470738 -238.76254)
					(mid 216.455859 -238.726619)
					(end 216.419938 -238.71174)
				)
				(arc
					(start 215.020398 -238.71174)
					(mid 214.984477 -238.726619)
					(end 214.969598 -238.76254)
				)
			)
		)
	)
	(zone
		(layers "In1.Cu" "In2.Cu")
		(hatch none 0.5)
		(connect_pads
			(clearance 0)
		)
		(min_thickness 0.25)
		(keepout
			(tracks not_allowed)
			(vias allowed)
			(pads allowed)
			(copperpour not_allowed)
			(footprints allowed)
		)
		(placement
			(enabled no)
			(sheetname "")
		)
		(fill yes
			(thermal_gap 0.5)
			(thermal_bridge_width 0.5)
			(island_removal_mode 0)
		)
		(polygon
			(pts
				(arc
					(start 262.873998 -266.371324)
					(mid 262.888877 -266.407245)
					(end 262.924798 -266.422124)
				)
				(arc
					(start 264.324338 -266.422124)
					(mid 264.360259 -266.407245)
					(end 264.375138 -266.371324)
				)
				(arc
					(start 264.375138 -265.962384)
					(mid 264.360259 -265.926463)
					(end 264.324338 -265.911584)
				)
				(arc
					(start 262.924798 -265.911584)
					(mid 262.888877 -265.926463)
					(end 262.873998 -265.962384)
				)
			)
		)
	)
	(zone
		(layers "In1.Cu" "In2.Cu")
		(hatch none 0.5)
		(connect_pads
			(clearance 0)
		)
		(min_thickness 0.25)
		(keepout
			(tracks not_allowed)
			(vias allowed)
			(pads allowed)
			(copperpour not_allowed)
			(footprints allowed)
		)
		(placement
			(enabled no)
			(sheetname "")
		)
		(fill yes
			(thermal_gap 0.5)
			(thermal_bridge_width 0.5)
			(island_removal_mode 0)
		)
		(polygon
			(pts
				(arc
					(start 410.103066 -265.52144)
					(mid 410.117945 -265.557361)
					(end 410.153866 -265.57224)
				)
				(arc
					(start 411.553406 -265.57224)
					(mid 411.589327 -265.557361)
					(end 411.604206 -265.52144)
				)
				(arc
					(start 411.604206 -265.1125)
					(mid 411.589327 -265.076579)
					(end 411.553406 -265.0617)
				)
				(arc
					(start 410.153866 -265.0617)
					(mid 410.117945 -265.076579)
					(end 410.103066 -265.1125)
				)
			)
		)
	)
	(zone
		(layers "In1.Cu" "In2.Cu")
		(hatch none 0.5)
		(connect_pads
			(clearance 0)
		)
		(min_thickness 0.25)
		(keepout
			(tracks not_allowed)
			(vias allowed)
			(pads allowed)
			(copperpour not_allowed)
			(footprints allowed)
		)
		(placement
			(enabled no)
			(sheetname "")
		)
		(fill yes
			(thermal_gap 0.5)
			(thermal_bridge_width 0.5)
			(island_removal_mode 0)
		)
		(polygon
			(pts
				(arc
					(start 458.809598 -232.371392)
					(mid 458.824477 -232.407313)
					(end 458.860398 -232.422192)
				)
				(arc
					(start 460.259938 -232.422192)
					(mid 460.295859 -232.407313)
					(end 460.310738 -232.371392)
				)
				(arc
					(start 460.310738 -231.962452)
					(mid 460.295859 -231.926531)
					(end 460.259938 -231.911652)
				)
				(arc
					(start 458.860398 -231.911652)
					(mid 458.824477 -231.926531)
					(end 458.809598 -231.962452)
				)
			)
		)
	)
	(zone
		(layers "In1.Cu" "In2.Cu")
		(hatch none 0.5)
		(connect_pads
			(clearance 0)
		)
		(min_thickness 0.25)
		(keepout
			(tracks not_allowed)
			(vias allowed)
			(pads allowed)
			(copperpour not_allowed)
			(footprints allowed)
		)
		(placement
			(enabled no)
			(sheetname "")
		)
		(fill yes
			(thermal_gap 0.5)
			(thermal_bridge_width 0.5)
			(island_removal_mode 0)
		)
		(polygon
			(pts
				(arc
					(start 293.049198 -219.621354)
					(mid 293.064077 -219.657275)
					(end 293.099998 -219.672154)
				)
				(arc
					(start 294.499538 -219.672154)
					(mid 294.535459 -219.657275)
					(end 294.550338 -219.621354)
				)
				(arc
					(start 294.550338 -219.212414)
					(mid 294.535459 -219.176493)
					(end 294.499538 -219.161614)
				)
				(arc
					(start 293.099998 -219.161614)
					(mid 293.064077 -219.176493)
					(end 293.049198 -219.212414)
				)
			)
		)
	)
	(zone
		(layers "In1.Cu" "In2.Cu")
		(hatch none 0.5)
		(connect_pads
			(clearance 0)
		)
		(min_thickness 0.25)
		(keepout
			(tracks not_allowed)
			(vias allowed)
			(pads allowed)
			(copperpour not_allowed)
			(footprints allowed)
		)
		(placement
			(enabled no)
			(sheetname "")
		)
		(fill yes
			(thermal_gap 0.5)
			(thermal_bridge_width 0.5)
			(island_removal_mode 0)
		)
		(polygon
			(pts
				(arc
					(start 293.049198 -237.471458)
					(mid 293.064077 -237.507379)
					(end 293.099998 -237.522258)
				)
				(arc
					(start 294.499538 -237.522258)
					(mid 294.535459 -237.507379)
					(end 294.550338 -237.471458)
				)
				(arc
					(start 294.550338 -237.062518)
					(mid 294.535459 -237.026597)
					(end 294.499538 -237.011718)
				)
				(arc
					(start 293.099998 -237.011718)
					(mid 293.064077 -237.026597)
					(end 293.049198 -237.062518)
				)
			)
		)
	)
	(zone
		(layers "In1.Cu" "In2.Cu")
		(hatch none 0.5)
		(connect_pads
			(clearance 0)
		)
		(min_thickness 0.25)
		(keepout
			(tracks not_allowed)
			(vias allowed)
			(pads allowed)
			(copperpour not_allowed)
			(footprints allowed)
		)
		(placement
			(enabled no)
			(sheetname "")
		)
		(fill yes
			(thermal_gap 0.5)
			(thermal_bridge_width 0.5)
			(island_removal_mode 0)
		)
		(polygon
			(pts
				(arc
					(start 428.634398 -206.021432)
					(mid 428.649277 -206.057353)
					(end 428.685198 -206.072232)
				)
				(arc
					(start 430.084738 -206.072232)
					(mid 430.120659 -206.057353)
					(end 430.135538 -206.021432)
				)
				(arc
					(start 430.135538 -205.612492)
					(mid 430.120659 -205.576571)
					(end 430.084738 -205.561692)
				)
				(arc
					(start 428.685198 -205.561692)
					(mid 428.649277 -205.576571)
					(end 428.634398 -205.612492)
				)
			)
		)
	)
	(zone
		(layers "In1.Cu" "In2.Cu")
		(hatch none 0.5)
		(connect_pads
			(clearance 0)
		)
		(min_thickness 0.25)
		(keepout
			(tracks not_allowed)
			(vias allowed)
			(pads allowed)
			(copperpour not_allowed)
			(footprints allowed)
		)
		(placement
			(enabled no)
			(sheetname "")
		)
		(fill yes
			(thermal_gap 0.5)
			(thermal_bridge_width 0.5)
			(island_removal_mode 0)
		)
		(polygon
			(pts
				(arc
					(start 177.250598 -231.521508)
					(mid 177.265477 -231.557429)
					(end 177.301398 -231.572308)
				)
				(arc
					(start 178.700938 -231.572308)
					(mid 178.736859 -231.557429)
					(end 178.751738 -231.521508)
				)
				(arc
					(start 178.751738 -231.112568)
					(mid 178.736859 -231.076647)
					(end 178.700938 -231.061768)
				)
				(arc
					(start 177.301398 -231.061768)
					(mid 177.265477 -231.076647)
					(end 177.250598 -231.112568)
				)
			)
		)
	)
	(zone
		(layers "In1.Cu" "In2.Cu")
		(hatch none 0.5)
		(connect_pads
			(clearance 0)
		)
		(min_thickness 0.25)
		(keepout
			(tracks not_allowed)
			(vias allowed)
			(pads allowed)
			(copperpour not_allowed)
			(footprints allowed)
		)
		(placement
			(enabled no)
			(sheetname "")
		)
		(fill yes
			(thermal_gap 0.5)
			(thermal_bridge_width 0.5)
			(island_removal_mode 0)
		)
		(polygon
			(pts
				(arc
					(start 30.02153 -275.721318)
					(mid 30.036409 -275.757239)
					(end 30.07233 -275.772118)
				)
				(arc
					(start 31.47187 -275.772118)
					(mid 31.507791 -275.757239)
					(end 31.52267 -275.721318)
				)
				(arc
					(start 31.52267 -275.312378)
					(mid 31.507791 -275.276457)
					(end 31.47187 -275.261578)
				)
				(arc
					(start 30.07233 -275.261578)
					(mid 30.036409 -275.276457)
					(end 30.02153 -275.312378)
				)
			)
		)
	)
	(zone
		(layers "In1.Cu" "In2.Cu")
		(hatch none 0.5)
		(connect_pads
			(clearance 0)
		)
		(min_thickness 0.25)
		(keepout
			(tracks not_allowed)
			(vias allowed)
			(pads allowed)
			(copperpour not_allowed)
			(footprints allowed)
		)
		(placement
			(enabled no)
			(sheetname "")
		)
		(fill yes
			(thermal_gap 0.5)
			(thermal_bridge_width 0.5)
			(island_removal_mode 0)
		)
		(polygon
			(pts
				(arc
					(start 52.65293 -285.071312)
					(mid 52.667809 -285.107233)
					(end 52.70373 -285.122112)
				)
				(arc
					(start 54.10327 -285.122112)
					(mid 54.139191 -285.107233)
					(end 54.15407 -285.071312)
				)
				(arc
					(start 54.15407 -284.662372)
					(mid 54.139191 -284.626451)
					(end 54.10327 -284.611572)
				)
				(arc
					(start 52.70373 -284.611572)
					(mid 52.667809 -284.626451)
					(end 52.65293 -284.662372)
				)
			)
		)
	)
	(zone
		(layers "In1.Cu" "In2.Cu")
		(hatch none 0.5)
		(connect_pads
			(clearance 0)
		)
		(min_thickness 0.25)
		(keepout
			(tracks not_allowed)
			(vias allowed)
			(pads allowed)
			(copperpour not_allowed)
			(footprints allowed)
		)
		(placement
			(enabled no)
			(sheetname "")
		)
		(fill yes
			(thermal_gap 0.5)
			(thermal_bridge_width 0.5)
			(island_removal_mode 0)
		)
		(polygon
			(pts
				(arc
					(start 26.577798 -214.521542)
					(mid 26.592677 -214.557463)
					(end 26.628598 -214.572342)
				)
				(arc
					(start 28.028138 -214.572342)
					(mid 28.064059 -214.557463)
					(end 28.078938 -214.521542)
				)
				(arc
					(start 28.078938 -214.112602)
					(mid 28.064059 -214.076681)
					(end 28.028138 -214.061802)
				)
				(arc
					(start 26.628598 -214.061802)
					(mid 26.592677 -214.076681)
					(end 26.577798 -214.112602)
				)
			)
		)
	)
	(zone
		(layers "In1.Cu" "In2.Cu")
		(hatch none 0.5)
		(connect_pads
			(clearance 0)
		)
		(min_thickness 0.25)
		(keepout
			(tracks not_allowed)
			(vias allowed)
			(pads allowed)
			(copperpour not_allowed)
			(footprints allowed)
		)
		(placement
			(enabled no)
			(sheetname "")
		)
		(fill yes
			(thermal_gap 0.5)
			(thermal_bridge_width 0.5)
			(island_removal_mode 0)
		)
		(polygon
			(pts
				(arc
					(start 19.033998 -197.521322)
					(mid 19.048877 -197.557243)
					(end 19.084798 -197.572122)
				)
				(arc
					(start 20.484338 -197.572122)
					(mid 20.520259 -197.557243)
					(end 20.535138 -197.521322)
				)
				(arc
					(start 20.535138 -197.112382)
					(mid 20.520259 -197.076461)
					(end 20.484338 -197.061582)
				)
				(arc
					(start 19.084798 -197.061582)
					(mid 19.048877 -197.076461)
					(end 19.033998 -197.112382)
				)
			)
		)
	)
	(zone
		(layers "In1.Cu" "In2.Cu")
		(hatch none 0.5)
		(connect_pads
			(clearance 0)
		)
		(min_thickness 0.25)
		(keepout
			(tracks not_allowed)
			(vias allowed)
			(pads allowed)
			(copperpour not_allowed)
			(footprints allowed)
		)
		(placement
			(enabled no)
			(sheetname "")
		)
		(fill yes
			(thermal_gap 0.5)
			(thermal_bridge_width 0.5)
			(island_removal_mode 0)
		)
		(polygon
			(pts
				(arc
					(start 289.605466 -228.121464)
					(mid 289.620345 -228.157385)
					(end 289.656266 -228.172264)
				)
				(arc
					(start 291.055806 -228.172264)
					(mid 291.091727 -228.157385)
					(end 291.106606 -228.121464)
				)
				(arc
					(start 291.106606 -227.712524)
					(mid 291.091727 -227.676603)
					(end 291.055806 -227.661724)
				)
				(arc
					(start 289.656266 -227.661724)
					(mid 289.620345 -227.676603)
					(end 289.605466 -227.712524)
				)
			)
		)
	)
	(zone
		(layers "In1.Cu" "In2.Cu")
		(hatch none 0.5)
		(connect_pads
			(clearance 0)
		)
		(min_thickness 0.25)
		(keepout
			(tracks not_allowed)
			(vias allowed)
			(pads allowed)
			(copperpour not_allowed)
			(footprints allowed)
		)
		(placement
			(enabled no)
			(sheetname "")
		)
		(fill yes
			(thermal_gap 0.5)
			(thermal_bridge_width 0.5)
			(island_removal_mode 0)
		)
		(polygon
			(pts
				(arc
					(start 199.881998 -239.17148)
					(mid 199.896877 -239.207401)
					(end 199.932798 -239.22228)
				)
				(arc
					(start 201.332338 -239.22228)
					(mid 201.368259 -239.207401)
					(end 201.383138 -239.17148)
				)
				(arc
					(start 201.383138 -238.76254)
					(mid 201.368259 -238.726619)
					(end 201.332338 -238.71174)
				)
				(arc
					(start 199.932798 -238.71174)
					(mid 199.896877 -238.726619)
					(end 199.881998 -238.76254)
				)
			)
		)
	)
	(zone
		(layers "In1.Cu" "In2.Cu")
		(hatch none 0.5)
		(connect_pads
			(clearance 0)
		)
		(min_thickness 0.25)
		(keepout
			(tracks not_allowed)
			(vias allowed)
			(pads allowed)
			(copperpour not_allowed)
			(footprints allowed)
		)
		(placement
			(enabled no)
			(sheetname "")
		)
		(fill yes
			(thermal_gap 0.5)
			(thermal_bridge_width 0.5)
			(island_removal_mode 0)
		)
		(polygon
			(pts
				(arc
					(start 45.10913 -215.371426)
					(mid 45.124009 -215.407347)
					(end 45.15993 -215.422226)
				)
				(arc
					(start 46.55947 -215.422226)
					(mid 46.595391 -215.407347)
					(end 46.61027 -215.371426)
				)
				(arc
					(start 46.61027 -214.962486)
					(mid 46.595391 -214.926565)
					(end 46.55947 -214.911686)
				)
				(arc
					(start 45.15993 -214.911686)
					(mid 45.124009 -214.926565)
					(end 45.10913 -214.962486)
				)
			)
		)
	)
	(zone
		(layers "In1.Cu" "In2.Cu")
		(hatch none 0.5)
		(connect_pads
			(clearance 0)
		)
		(min_thickness 0.25)
		(keepout
			(tracks not_allowed)
			(vias allowed)
			(pads allowed)
			(copperpour not_allowed)
			(footprints allowed)
		)
		(placement
			(enabled no)
			(sheetname "")
		)
		(fill yes
			(thermal_gap 0.5)
			(thermal_bridge_width 0.5)
			(island_removal_mode 0)
		)
		(polygon
			(pts
				(arc
					(start 436.178198 -206.021432)
					(mid 436.193077 -206.057353)
					(end 436.228998 -206.072232)
				)
				(arc
					(start 437.628538 -206.072232)
					(mid 437.664459 -206.057353)
					(end 437.679338 -206.021432)
				)
				(arc
					(start 437.679338 -205.612492)
					(mid 437.664459 -205.576571)
					(end 437.628538 -205.561692)
				)
				(arc
					(start 436.228998 -205.561692)
					(mid 436.193077 -205.576571)
					(end 436.178198 -205.612492)
				)
			)
		)
	)
	(zone
		(layers "In1.Cu" "In2.Cu")
		(hatch none 0.5)
		(connect_pads
			(clearance 0)
		)
		(min_thickness 0.25)
		(keepout
			(tracks not_allowed)
			(vias allowed)
			(pads allowed)
			(copperpour not_allowed)
			(footprints allowed)
		)
		(placement
			(enabled no)
			(sheetname "")
		)
		(fill yes
			(thermal_gap 0.5)
			(thermal_bridge_width 0.5)
			(island_removal_mode 0)
		)
		(polygon
			(pts
				(arc
					(start 262.873998 -244.271292)
					(mid 262.888877 -244.307213)
					(end 262.924798 -244.322092)
				)
				(arc
					(start 264.324338 -244.322092)
					(mid 264.360259 -244.307213)
					(end 264.375138 -244.271292)
				)
				(arc
					(start 264.375138 -243.862352)
					(mid 264.360259 -243.826431)
					(end 264.324338 -243.811552)
				)
				(arc
					(start 262.924798 -243.811552)
					(mid 262.888877 -243.826431)
					(end 262.873998 -243.862352)
				)
			)
		)
	)
	(zone
		(layers "In1.Cu" "In2.Cu")
		(hatch none 0.5)
		(connect_pads
			(clearance 0)
		)
		(min_thickness 0.25)
		(keepout
			(tracks not_allowed)
			(vias allowed)
			(pads allowed)
			(copperpour not_allowed)
			(footprints allowed)
		)
		(placement
			(enabled no)
			(sheetname "")
		)
		(fill yes
			(thermal_gap 0.5)
			(thermal_bridge_width 0.5)
			(island_removal_mode 0)
		)
		(polygon
			(pts
				(arc
					(start 259.430266 -225.571304)
					(mid 259.445145 -225.607225)
					(end 259.481066 -225.622104)
				)
				(arc
					(start 260.880606 -225.622104)
					(mid 260.916527 -225.607225)
					(end 260.931406 -225.571304)
				)
				(arc
					(start 260.931406 -225.162364)
					(mid 260.916527 -225.126443)
					(end 260.880606 -225.111564)
				)
				(arc
					(start 259.481066 -225.111564)
					(mid 259.445145 -225.126443)
					(end 259.430266 -225.162364)
				)
			)
		)
	)
	(zone
		(layers "In1.Cu" "In2.Cu")
		(hatch none 0.5)
		(connect_pads
			(clearance 0)
		)
		(min_thickness 0.25)
		(keepout
			(tracks not_allowed)
			(vias allowed)
			(pads allowed)
			(copperpour not_allowed)
			(footprints allowed)
		)
		(placement
			(enabled no)
			(sheetname "")
		)
		(fill yes
			(thermal_gap 0.5)
			(thermal_bridge_width 0.5)
			(island_removal_mode 0)
		)
		(polygon
			(pts
				(arc
					(start 436.178198 -301.221394)
					(mid 436.193077 -301.257315)
					(end 436.228998 -301.272194)
				)
				(arc
					(start 437.628538 -301.272194)
					(mid 437.664459 -301.257315)
					(end 437.679338 -301.221394)
				)
				(arc
					(start 437.679338 -300.812454)
					(mid 437.664459 -300.776533)
					(end 437.628538 -300.761654)
				)
				(arc
					(start 436.228998 -300.761654)
					(mid 436.193077 -300.776533)
					(end 436.178198 -300.812454)
				)
			)
		)
	)
	(zone
		(layers "In1.Cu" "In2.Cu")
		(hatch none 0.5)
		(connect_pads
			(clearance 0)
		)
		(min_thickness 0.25)
		(keepout
			(tracks not_allowed)
			(vias allowed)
			(pads allowed)
			(copperpour not_allowed)
			(footprints allowed)
		)
		(placement
			(enabled no)
			(sheetname "")
		)
		(fill yes
			(thermal_gap 0.5)
			(thermal_bridge_width 0.5)
			(island_removal_mode 0)
		)
		(polygon
			(pts
				(arc
					(start 7.39013 -244.271292)
					(mid 7.405009 -244.307213)
					(end 7.44093 -244.322092)
				)
				(arc
					(start 8.84047 -244.322092)
					(mid 8.876391 -244.307213)
					(end 8.89127 -244.271292)
				)
				(arc
					(start 8.89127 -243.862352)
					(mid 8.876391 -243.826431)
					(end 8.84047 -243.811552)
				)
				(arc
					(start 7.44093 -243.811552)
					(mid 7.405009 -243.826431)
					(end 7.39013 -243.862352)
				)
			)
		)
	)
	(zone
		(layers "In1.Cu" "In2.Cu")
		(hatch none 0.5)
		(connect_pads
			(clearance 0)
		)
		(min_thickness 0.25)
		(keepout
			(tracks not_allowed)
			(vias allowed)
			(pads allowed)
			(copperpour not_allowed)
			(footprints allowed)
		)
		(placement
			(enabled no)
			(sheetname "")
		)
		(fill yes
			(thermal_gap 0.5)
			(thermal_bridge_width 0.5)
			(island_removal_mode 0)
		)
		(polygon
			(pts
				(arc
					(start 304.693066 -304.621438)
					(mid 304.707945 -304.657359)
					(end 304.743866 -304.672238)
				)
				(arc
					(start 306.143406 -304.672238)
					(mid 306.179327 -304.657359)
					(end 306.194206 -304.621438)
				)
				(arc
					(start 306.194206 -304.212498)
					(mid 306.179327 -304.176577)
					(end 306.143406 -304.161698)
				)
				(arc
					(start 304.743866 -304.161698)
					(mid 304.707945 -304.176577)
					(end 304.693066 -304.212498)
				)
			)
		)
	)
	(zone
		(layers "In1.Cu" "In2.Cu")
		(hatch none 0.5)
		(connect_pads
			(clearance 0)
		)
		(min_thickness 0.25)
		(keepout
			(tracks not_allowed)
			(vias allowed)
			(pads allowed)
			(copperpour not_allowed)
			(footprints allowed)
		)
		(placement
			(enabled no)
			(sheetname "")
		)
		(fill yes
			(thermal_gap 0.5)
			(thermal_bridge_width 0.5)
			(island_removal_mode 0)
		)
		(polygon
			(pts
				(arc
					(start 169.706798 -220.471492)
					(mid 169.721677 -220.507413)
					(end 169.757598 -220.522292)
				)
				(arc
					(start 171.157138 -220.522292)
					(mid 171.193059 -220.507413)
					(end 171.207938 -220.471492)
				)
				(arc
					(start 171.207938 -220.062552)
					(mid 171.193059 -220.026631)
					(end 171.157138 -220.011752)
				)
				(arc
					(start 169.757598 -220.011752)
					(mid 169.721677 -220.026631)
					(end 169.706798 -220.062552)
				)
			)
		)
	)
	(zone
		(layers "In1.Cu" "In2.Cu")
		(hatch none 0.5)
		(connect_pads
			(clearance 0)
		)
		(min_thickness 0.25)
		(keepout
			(tracks not_allowed)
			(vias allowed)
			(pads allowed)
			(copperpour not_allowed)
			(footprints allowed)
		)
		(placement
			(enabled no)
			(sheetname "")
		)
		(fill yes
			(thermal_gap 0.5)
			(thermal_bridge_width 0.5)
			(island_removal_mode 0)
		)
		(polygon
			(pts
				(arc
					(start 308.136798 -280.821384)
					(mid 308.151677 -280.857305)
					(end 308.187598 -280.872184)
				)
				(arc
					(start 309.587138 -280.872184)
					(mid 309.623059 -280.857305)
					(end 309.637938 -280.821384)
				)
				(arc
					(start 309.637938 -280.412444)
					(mid 309.623059 -280.376523)
					(end 309.587138 -280.361644)
				)
				(arc
					(start 308.187598 -280.361644)
					(mid 308.151677 -280.376523)
					(end 308.136798 -280.412444)
				)
			)
		)
	)
	(zone
		(layers "In1.Cu" "In2.Cu")
		(hatch none 0.5)
		(connect_pads
			(clearance 0)
		)
		(min_thickness 0.25)
		(keepout
			(tracks not_allowed)
			(vias allowed)
			(pads allowed)
			(copperpour not_allowed)
			(footprints allowed)
		)
		(placement
			(enabled no)
			(sheetname "")
		)
		(fill yes
			(thermal_gap 0.5)
			(thermal_bridge_width 0.5)
			(island_removal_mode 0)
		)
		(polygon
			(pts
				(arc
					(start 406.002998 -224.72142)
					(mid 406.017877 -224.757341)
					(end 406.053798 -224.77222)
				)
				(arc
					(start 407.453338 -224.77222)
					(mid 407.489259 -224.757341)
					(end 407.504138 -224.72142)
				)
				(arc
					(start 407.504138 -224.31248)
					(mid 407.489259 -224.276559)
					(end 407.453338 -224.26168)
				)
				(arc
					(start 406.053798 -224.26168)
					(mid 406.017877 -224.276559)
					(end 406.002998 -224.31248)
				)
			)
		)
	)
	(zone
		(layers "In1.Cu" "In2.Cu")
		(hatch none 0.5)
		(connect_pads
			(clearance 0)
		)
		(min_thickness 0.25)
		(keepout
			(tracks not_allowed)
			(vias allowed)
			(pads allowed)
			(copperpour not_allowed)
			(footprints allowed)
		)
		(placement
			(enabled no)
			(sheetname "")
		)
		(fill yes
			(thermal_gap 0.5)
			(thermal_bridge_width 0.5)
			(island_removal_mode 0)
		)
		(polygon
			(pts
				(arc
					(start 210.86953 -218.77147)
					(mid 210.884409 -218.807391)
					(end 210.92033 -218.82227)
				)
				(arc
					(start 212.31987 -218.82227)
					(mid 212.355791 -218.807391)
					(end 212.37067 -218.77147)
				)
				(arc
					(start 212.37067 -218.36253)
					(mid 212.355791 -218.326609)
					(end 212.31987 -218.31173)
				)
				(arc
					(start 210.92033 -218.31173)
					(mid 210.884409 -218.326609)
					(end 210.86953 -218.36253)
				)
			)
		)
	)
	(zone
		(layers "In1.Cu" "In2.Cu")
		(hatch none 0.5)
		(connect_pads
			(clearance 0)
		)
		(min_thickness 0.25)
		(keepout
			(tracks not_allowed)
			(vias allowed)
			(pads allowed)
			(copperpour not_allowed)
			(footprints allowed)
		)
		(placement
			(enabled no)
			(sheetname "")
		)
		(fill yes
			(thermal_gap 0.5)
			(thermal_bridge_width 0.5)
			(island_removal_mode 0)
		)
		(polygon
			(pts
				(arc
					(start 462.909666 -274.02155)
					(mid 462.924545 -274.057471)
					(end 462.960466 -274.07235)
				)
				(arc
					(start 464.360006 -274.07235)
					(mid 464.395927 -274.057471)
					(end 464.410806 -274.02155)
				)
				(arc
					(start 464.410806 -273.61261)
					(mid 464.395927 -273.576689)
					(end 464.360006 -273.56181)
				)
				(arc
					(start 462.960466 -273.56181)
					(mid 462.924545 -273.576689)
					(end 462.909666 -273.61261)
				)
			)
		)
	)
	(zone
		(layers "In1.Cu" "In2.Cu")
		(hatch none 0.5)
		(connect_pads
			(clearance 0)
		)
		(min_thickness 0.25)
		(keepout
			(tracks not_allowed)
			(vias allowed)
			(pads allowed)
			(copperpour not_allowed)
			(footprints allowed)
		)
		(placement
			(enabled no)
			(sheetname "")
		)
		(fill yes
			(thermal_gap 0.5)
			(thermal_bridge_width 0.5)
			(island_removal_mode 0)
		)
		(polygon
			(pts
				(arc
					(start 458.809598 -196.671438)
					(mid 458.824477 -196.707359)
					(end 458.860398 -196.722238)
				)
				(arc
					(start 460.259938 -196.722238)
					(mid 460.295859 -196.707359)
					(end 460.310738 -196.671438)
				)
				(arc
					(start 460.310738 -196.262498)
					(mid 460.295859 -196.226577)
					(end 460.259938 -196.211698)
				)
				(arc
					(start 458.860398 -196.211698)
					(mid 458.824477 -196.226577)
					(end 458.809598 -196.262498)
				)
			)
		)
	)
	(zone
		(layers "In1.Cu" "In2.Cu")
		(hatch none 0.5)
		(connect_pads
			(clearance 0)
		)
		(min_thickness 0.25)
		(keepout
			(tracks not_allowed)
			(vias allowed)
			(pads allowed)
			(copperpour not_allowed)
			(footprints allowed)
		)
		(placement
			(enabled no)
			(sheetname "")
		)
		(fill yes
			(thermal_gap 0.5)
			(thermal_bridge_width 0.5)
			(island_removal_mode 0)
		)
		(polygon
			(pts
				(arc
					(start 52.65293 -273.171412)
					(mid 52.667809 -273.207333)
					(end 52.70373 -273.222212)
				)
				(arc
					(start 54.10327 -273.222212)
					(mid 54.139191 -273.207333)
					(end 54.15407 -273.171412)
				)
				(arc
					(start 54.15407 -272.762472)
					(mid 54.139191 -272.726551)
					(end 54.10327 -272.711672)
				)
				(arc
					(start 52.70373 -272.711672)
					(mid 52.667809 -272.726551)
					(end 52.65293 -272.762472)
				)
			)
		)
	)
	(zone
		(layers "In1.Cu" "In2.Cu")
		(hatch none 0.5)
		(connect_pads
			(clearance 0)
		)
		(min_thickness 0.25)
		(keepout
			(tracks not_allowed)
			(vias allowed)
			(pads allowed)
			(copperpour not_allowed)
			(footprints allowed)
		)
		(placement
			(enabled no)
			(sheetname "")
		)
		(fill yes
			(thermal_gap 0.5)
			(thermal_bridge_width 0.5)
			(island_removal_mode 0)
		)
		(polygon
			(pts
				(arc
					(start 180.69433 -303.7713)
					(mid 180.709209 -303.807221)
					(end 180.74513 -303.8221)
				)
				(arc
					(start 182.14467 -303.8221)
					(mid 182.180591 -303.807221)
					(end 182.19547 -303.7713)
				)
				(arc
					(start 182.19547 -303.36236)
					(mid 182.180591 -303.326439)
					(end 182.14467 -303.31156)
				)
				(arc
					(start 180.74513 -303.31156)
					(mid 180.709209 -303.326439)
					(end 180.69433 -303.36236)
				)
			)
		)
	)
	(zone
		(layers "In1.Cu" "In2.Cu")
		(hatch none 0.5)
		(connect_pads
			(clearance 0)
		)
		(min_thickness 0.25)
		(keepout
			(tracks not_allowed)
			(vias allowed)
			(pads allowed)
			(copperpour not_allowed)
			(footprints allowed)
		)
		(placement
			(enabled no)
			(sheetname "")
		)
		(fill yes
			(thermal_gap 0.5)
			(thermal_bridge_width 0.5)
			(island_removal_mode 0)
		)
		(polygon
			(pts
				(arc
					(start 432.734466 -212.82152)
					(mid 432.749345 -212.857441)
					(end 432.785266 -212.87232)
				)
				(arc
					(start 434.184806 -212.87232)
					(mid 434.220727 -212.857441)
					(end 434.235606 -212.82152)
				)
				(arc
					(start 434.235606 -212.41258)
					(mid 434.220727 -212.376659)
					(end 434.184806 -212.36178)
				)
				(arc
					(start 432.785266 -212.36178)
					(mid 432.749345 -212.376659)
					(end 432.734466 -212.41258)
				)
			)
		)
	)
	(zone
		(layers "In1.Cu" "In2.Cu")
		(hatch none 0.5)
		(connect_pads
			(clearance 0)
		)
		(min_thickness 0.25)
		(keepout
			(tracks not_allowed)
			(vias allowed)
			(pads allowed)
			(copperpour not_allowed)
			(footprints allowed)
		)
		(placement
			(enabled no)
			(sheetname "")
		)
		(fill yes
			(thermal_gap 0.5)
			(thermal_bridge_width 0.5)
			(island_removal_mode 0)
		)
		(polygon
			(pts
				(arc
					(start 255.330198 -305.471322)
					(mid 255.345077 -305.507243)
					(end 255.380998 -305.522122)
				)
				(arc
					(start 256.780538 -305.522122)
					(mid 256.816459 -305.507243)
					(end 256.831338 -305.471322)
				)
				(arc
					(start 256.831338 -305.062382)
					(mid 256.816459 -305.026461)
					(end 256.780538 -305.011582)
				)
				(arc
					(start 255.380998 -305.011582)
					(mid 255.345077 -305.026461)
					(end 255.330198 -305.062382)
				)
			)
		)
	)
	(zone
		(layers "In1.Cu" "In2.Cu")
		(hatch none 0.5)
		(connect_pads
			(clearance 0)
		)
		(min_thickness 0.25)
		(keepout
			(tracks not_allowed)
			(vias allowed)
			(pads allowed)
			(copperpour not_allowed)
			(footprints allowed)
		)
		(placement
			(enabled no)
			(sheetname "")
		)
		(fill yes
			(thermal_gap 0.5)
			(thermal_bridge_width 0.5)
			(island_removal_mode 0)
		)
		(polygon
			(pts
				(arc
					(start 443.721998 -237.471458)
					(mid 443.736877 -237.507379)
					(end 443.772798 -237.522258)
				)
				(arc
					(start 445.172338 -237.522258)
					(mid 445.208259 -237.507379)
					(end 445.223138 -237.471458)
				)
				(arc
					(start 445.223138 -237.062518)
					(mid 445.208259 -237.026597)
					(end 445.172338 -237.011718)
				)
				(arc
					(start 443.772798 -237.011718)
					(mid 443.736877 -237.026597)
					(end 443.721998 -237.062518)
				)
			)
		)
	)
	(zone
		(layers "In1.Cu" "In2.Cu")
		(hatch none 0.5)
		(connect_pads
			(clearance 0)
		)
		(min_thickness 0.25)
		(keepout
			(tracks not_allowed)
			(vias allowed)
			(pads allowed)
			(copperpour not_allowed)
			(footprints allowed)
		)
		(placement
			(enabled no)
			(sheetname "")
		)
		(fill yes
			(thermal_gap 0.5)
			(thermal_bridge_width 0.5)
			(island_removal_mode 0)
		)
		(polygon
			(pts
				(arc
					(start 210.86953 -200.921366)
					(mid 210.884409 -200.957287)
					(end 210.92033 -200.972166)
				)
				(arc
					(start 212.31987 -200.972166)
					(mid 212.355791 -200.957287)
					(end 212.37067 -200.921366)
				)
				(arc
					(start 212.37067 -200.512426)
					(mid 212.355791 -200.476505)
					(end 212.31987 -200.461626)
				)
				(arc
					(start 210.92033 -200.461626)
					(mid 210.884409 -200.476505)
					(end 210.86953 -200.512426)
				)
			)
		)
	)
	(zone
		(layers "In1.Cu" "In2.Cu")
		(hatch none 0.5)
		(connect_pads
			(clearance 0)
		)
		(min_thickness 0.25)
		(keepout
			(tracks not_allowed)
			(vias allowed)
			(pads allowed)
			(copperpour not_allowed)
			(footprints allowed)
		)
		(placement
			(enabled no)
			(sheetname "")
		)
		(fill yes
			(thermal_gap 0.5)
			(thermal_bridge_width 0.5)
			(island_removal_mode 0)
		)
		(polygon
			(pts
				(arc
					(start 11.490198 -278.271478)
					(mid 11.505077 -278.307399)
					(end 11.540998 -278.322278)
				)
				(arc
					(start 12.940538 -278.322278)
					(mid 12.976459 -278.307399)
					(end 12.991338 -278.271478)
				)
				(arc
					(start 12.991338 -277.862538)
					(mid 12.976459 -277.826617)
					(end 12.940538 -277.811738)
				)
				(arc
					(start 11.540998 -277.811738)
					(mid 11.505077 -277.826617)
					(end 11.490198 -277.862538)
				)
			)
		)
	)
	(zone
		(layers "In1.Cu" "In2.Cu")
		(hatch none 0.5)
		(connect_pads
			(clearance 0)
		)
		(min_thickness 0.25)
		(keepout
			(tracks not_allowed)
			(vias allowed)
			(pads allowed)
			(copperpour not_allowed)
			(footprints allowed)
		)
		(placement
			(enabled no)
			(sheetname "")
		)
		(fill yes
			(thermal_gap 0.5)
			(thermal_bridge_width 0.5)
			(island_removal_mode 0)
		)
		(polygon
			(pts
				(arc
					(start 312.236866 -292.721538)
					(mid 312.251745 -292.757459)
					(end 312.287666 -292.772338)
				)
				(arc
					(start 313.687206 -292.772338)
					(mid 313.723127 -292.757459)
					(end 313.738006 -292.721538)
				)
				(arc
					(start 313.738006 -292.312598)
					(mid 313.723127 -292.276677)
					(end 313.687206 -292.261798)
				)
				(arc
					(start 312.287666 -292.261798)
					(mid 312.251745 -292.276677)
					(end 312.236866 -292.312598)
				)
			)
		)
	)
	(zone
		(layers "In1.Cu" "In2.Cu")
		(hatch none 0.5)
		(connect_pads
			(clearance 0)
		)
		(min_thickness 0.25)
		(keepout
			(tracks not_allowed)
			(vias allowed)
			(pads allowed)
			(copperpour not_allowed)
			(footprints allowed)
		)
		(placement
			(enabled no)
			(sheetname "")
		)
		(fill yes
			(thermal_gap 0.5)
			(thermal_bridge_width 0.5)
			(island_removal_mode 0)
		)
		(polygon
			(pts
				(arc
					(start 285.505398 -302.921416)
					(mid 285.520277 -302.957337)
					(end 285.556198 -302.972216)
				)
				(arc
					(start 286.955738 -302.972216)
					(mid 286.991659 -302.957337)
					(end 287.006538 -302.921416)
				)
				(arc
					(start 287.006538 -302.512476)
					(mid 286.991659 -302.476555)
					(end 286.955738 -302.461676)
				)
				(arc
					(start 285.556198 -302.461676)
					(mid 285.520277 -302.476555)
					(end 285.505398 -302.512476)
				)
			)
		)
	)
	(zone
		(layers "In1.Cu" "In2.Cu")
		(hatch none 0.5)
		(connect_pads
			(clearance 0)
		)
		(min_thickness 0.25)
		(keepout
			(tracks not_allowed)
			(vias allowed)
			(pads allowed)
			(copperpour not_allowed)
			(footprints allowed)
		)
		(placement
			(enabled no)
			(sheetname "")
		)
		(fill yes
			(thermal_gap 0.5)
			(thermal_bridge_width 0.5)
			(island_removal_mode 0)
		)
		(polygon
			(pts
				(arc
					(start 14.93393 -299.521372)
					(mid 14.948809 -299.557293)
					(end 14.98473 -299.572172)
				)
				(arc
					(start 16.38427 -299.572172)
					(mid 16.420191 -299.557293)
					(end 16.43507 -299.521372)
				)
				(arc
					(start 16.43507 -299.112432)
					(mid 16.420191 -299.076511)
					(end 16.38427 -299.061632)
				)
				(arc
					(start 14.98473 -299.061632)
					(mid 14.948809 -299.076511)
					(end 14.93393 -299.112432)
				)
			)
		)
	)
	(zone
		(layers "In1.Cu" "In2.Cu")
		(hatch none 0.5)
		(connect_pads
			(clearance 0)
		)
		(min_thickness 0.25)
		(keepout
			(tracks not_allowed)
			(vias allowed)
			(pads allowed)
			(copperpour not_allowed)
			(footprints allowed)
		)
		(placement
			(enabled no)
			(sheetname "")
		)
		(fill yes
			(thermal_gap 0.5)
			(thermal_bridge_width 0.5)
			(island_removal_mode 0)
		)
		(polygon
			(pts
				(arc
					(start 165.60673 -234.071414)
					(mid 165.621609 -234.107335)
					(end 165.65753 -234.122214)
				)
				(arc
					(start 167.05707 -234.122214)
					(mid 167.092991 -234.107335)
					(end 167.10787 -234.071414)
				)
				(arc
					(start 167.10787 -233.662474)
					(mid 167.092991 -233.626553)
					(end 167.05707 -233.611674)
				)
				(arc
					(start 165.65753 -233.611674)
					(mid 165.621609 -233.626553)
					(end 165.60673 -233.662474)
				)
			)
		)
	)
	(zone
		(layers "In1.Cu" "In2.Cu")
		(hatch none 0.5)
		(connect_pads
			(clearance 0)
		)
		(min_thickness 0.25)
		(keepout
			(tracks not_allowed)
			(vias allowed)
			(pads allowed)
			(copperpour not_allowed)
			(footprints allowed)
		)
		(placement
			(enabled no)
			(sheetname "")
		)
		(fill yes
			(thermal_gap 0.5)
			(thermal_bridge_width 0.5)
			(island_removal_mode 0)
		)
		(polygon
			(pts
				(arc
					(start 14.93393 -264.671302)
					(mid 14.948809 -264.707223)
					(end 14.98473 -264.722102)
				)
				(arc
					(start 16.38427 -264.722102)
					(mid 16.420191 -264.707223)
					(end 16.43507 -264.671302)
				)
				(arc
					(start 16.43507 -264.262362)
					(mid 16.420191 -264.226441)
					(end 16.38427 -264.211562)
				)
				(arc
					(start 14.98473 -264.211562)
					(mid 14.948809 -264.226441)
					(end 14.93393 -264.262362)
				)
			)
		)
	)
	(zone
		(layers "In1.Cu" "In2.Cu")
		(hatch none 0.5)
		(connect_pads
			(clearance 0)
		)
		(min_thickness 0.25)
		(keepout
			(tracks not_allowed)
			(vias allowed)
			(pads allowed)
			(copperpour not_allowed)
			(footprints allowed)
		)
		(placement
			(enabled no)
			(sheetname "")
		)
		(fill yes
			(thermal_gap 0.5)
			(thermal_bridge_width 0.5)
			(island_removal_mode 0)
		)
		(polygon
			(pts
				(arc
					(start 162.162998 -225.571304)
					(mid 162.177877 -225.607225)
					(end 162.213798 -225.622104)
				)
				(arc
					(start 163.613338 -225.622104)
					(mid 163.649259 -225.607225)
					(end 163.664138 -225.571304)
				)
				(arc
					(start 163.664138 -225.162364)
					(mid 163.649259 -225.126443)
					(end 163.613338 -225.111564)
				)
				(arc
					(start 162.213798 -225.111564)
					(mid 162.177877 -225.126443)
					(end 162.162998 -225.162364)
				)
			)
		)
	)
	(zone
		(layers "In1.Cu" "In2.Cu")
		(hatch none 0.5)
		(connect_pads
			(clearance 0)
		)
		(min_thickness 0.25)
		(keepout
			(tracks not_allowed)
			(vias allowed)
			(pads allowed)
			(copperpour not_allowed)
			(footprints allowed)
		)
		(placement
			(enabled no)
			(sheetname "")
		)
		(fill yes
			(thermal_gap 0.5)
			(thermal_bridge_width 0.5)
			(island_removal_mode 0)
		)
		(polygon
			(pts
				(arc
					(start 406.002998 -271.47139)
					(mid 406.017877 -271.507311)
					(end 406.053798 -271.52219)
				)
				(arc
					(start 407.453338 -271.52219)
					(mid 407.489259 -271.507311)
					(end 407.504138 -271.47139)
				)
				(arc
					(start 407.504138 -271.06245)
					(mid 407.489259 -271.026529)
					(end 407.453338 -271.01165)
				)
				(arc
					(start 406.053798 -271.01165)
					(mid 406.017877 -271.026529)
					(end 406.002998 -271.06245)
				)
			)
		)
	)
	(zone
		(layers "In1.Cu" "In2.Cu")
		(hatch none 0.5)
		(connect_pads
			(clearance 0)
		)
		(min_thickness 0.25)
		(keepout
			(tracks not_allowed)
			(vias allowed)
			(pads allowed)
			(copperpour not_allowed)
			(footprints allowed)
		)
		(placement
			(enabled no)
			(sheetname "")
		)
		(fill yes
			(thermal_gap 0.5)
			(thermal_bridge_width 0.5)
			(island_removal_mode 0)
		)
		(polygon
			(pts
				(arc
					(start 255.330198 -234.071414)
					(mid 255.345077 -234.107335)
					(end 255.380998 -234.122214)
				)
				(arc
					(start 256.780538 -234.122214)
					(mid 256.816459 -234.107335)
					(end 256.831338 -234.071414)
				)
				(arc
					(start 256.831338 -233.662474)
					(mid 256.816459 -233.626553)
					(end 256.780538 -233.611674)
				)
				(arc
					(start 255.380998 -233.611674)
					(mid 255.345077 -233.626553)
					(end 255.330198 -233.662474)
				)
			)
		)
	)
	(zone
		(layers "In1.Cu" "In2.Cu")
		(hatch none 0.5)
		(connect_pads
			(clearance 0)
		)
		(min_thickness 0.25)
		(keepout
			(tracks not_allowed)
			(vias allowed)
			(pads allowed)
			(copperpour not_allowed)
			(footprints allowed)
		)
		(placement
			(enabled no)
			(sheetname "")
		)
		(fill yes
			(thermal_gap 0.5)
			(thermal_bridge_width 0.5)
			(island_removal_mode 0)
		)
		(polygon
			(pts
				(arc
					(start 56.752998 -225.571304)
					(mid 56.767877 -225.607225)
					(end 56.803798 -225.622104)
				)
				(arc
					(start 58.203338 -225.622104)
					(mid 58.239259 -225.607225)
					(end 58.254138 -225.571304)
				)
				(arc
					(start 58.254138 -225.162364)
					(mid 58.239259 -225.126443)
					(end 58.203338 -225.111564)
				)
				(arc
					(start 56.803798 -225.111564)
					(mid 56.767877 -225.126443)
					(end 56.752998 -225.162364)
				)
			)
		)
	)
	(zone
		(layers "In1.Cu" "In2.Cu")
		(hatch none 0.5)
		(connect_pads
			(clearance 0)
		)
		(min_thickness 0.25)
		(keepout
			(tracks not_allowed)
			(vias allowed)
			(pads allowed)
			(copperpour not_allowed)
			(footprints allowed)
		)
		(placement
			(enabled no)
			(sheetname "")
		)
		(fill yes
			(thermal_gap 0.5)
			(thermal_bridge_width 0.5)
			(island_removal_mode 0)
		)
		(polygon
			(pts
				(arc
					(start 203.32573 -316.521338)
					(mid 203.340609 -316.557259)
					(end 203.37653 -316.572138)
				)
				(arc
					(start 204.77607 -316.572138)
					(mid 204.811991 -316.557259)
					(end 204.82687 -316.521338)
				)
				(arc
					(start 204.82687 -316.112398)
					(mid 204.811991 -316.076477)
					(end 204.77607 -316.061598)
				)
				(arc
					(start 203.37653 -316.061598)
					(mid 203.340609 -316.076477)
					(end 203.32573 -316.112398)
				)
			)
		)
	)
	(zone
		(layers "In1.Cu" "In2.Cu")
		(hatch none 0.5)
		(connect_pads
			(clearance 0)
		)
		(min_thickness 0.25)
		(keepout
			(tracks not_allowed)
			(vias allowed)
			(pads allowed)
			(copperpour not_allowed)
			(footprints allowed)
		)
		(placement
			(enabled no)
			(sheetname "")
		)
		(fill yes
			(thermal_gap 0.5)
			(thermal_bridge_width 0.5)
			(island_removal_mode 0)
		)
		(polygon
			(pts
				(arc
					(start 285.505398 -200.071482)
					(mid 285.520277 -200.107403)
					(end 285.556198 -200.122282)
				)
				(arc
					(start 286.955738 -200.122282)
					(mid 286.991659 -200.107403)
					(end 287.006538 -200.071482)
				)
				(arc
					(start 287.006538 -199.662542)
					(mid 286.991659 -199.626621)
					(end 286.955738 -199.611742)
				)
				(arc
					(start 285.556198 -199.611742)
					(mid 285.520277 -199.626621)
					(end 285.505398 -199.662542)
				)
			)
		)
	)
	(zone
		(layers "In1.Cu" "In2.Cu")
		(hatch none 0.5)
		(connect_pads
			(clearance 0)
		)
		(min_thickness 0.25)
		(keepout
			(tracks not_allowed)
			(vias allowed)
			(pads allowed)
			(copperpour not_allowed)
			(footprints allowed)
		)
		(placement
			(enabled no)
			(sheetname "")
		)
		(fill yes
			(thermal_gap 0.5)
			(thermal_bridge_width 0.5)
			(island_removal_mode 0)
		)
		(polygon
			(pts
				(arc
					(start 266.974066 -260.421374)
					(mid 266.988945 -260.457295)
					(end 267.024866 -260.472174)
				)
				(arc
					(start 268.424406 -260.472174)
					(mid 268.460327 -260.457295)
					(end 268.475206 -260.421374)
				)
				(arc
					(start 268.475206 -260.012434)
					(mid 268.460327 -259.976513)
					(end 268.424406 -259.961634)
				)
				(arc
					(start 267.024866 -259.961634)
					(mid 266.988945 -259.976513)
					(end 266.974066 -260.012434)
				)
			)
		)
	)
	(zone
		(layers "In1.Cu" "In2.Cu")
		(hatch none 0.5)
		(connect_pads
			(clearance 0)
		)
		(min_thickness 0.25)
		(keepout
			(tracks not_allowed)
			(vias allowed)
			(pads allowed)
			(copperpour not_allowed)
			(footprints allowed)
		)
		(placement
			(enabled no)
			(sheetname "")
		)
		(fill yes
			(thermal_gap 0.5)
			(thermal_bridge_width 0.5)
			(island_removal_mode 0)
		)
		(polygon
			(pts
				(arc
					(start 270.417798 -249.371358)
					(mid 270.432677 -249.407279)
					(end 270.468598 -249.422158)
				)
				(arc
					(start 271.868138 -249.422158)
					(mid 271.904059 -249.407279)
					(end 271.918938 -249.371358)
				)
				(arc
					(start 271.918938 -248.962418)
					(mid 271.904059 -248.926497)
					(end 271.868138 -248.911618)
				)
				(arc
					(start 270.468598 -248.911618)
					(mid 270.432677 -248.926497)
					(end 270.417798 -248.962418)
				)
			)
		)
	)
	(zone
		(layers "In1.Cu" "In2.Cu")
		(hatch none 0.5)
		(connect_pads
			(clearance 0)
		)
		(min_thickness 0.25)
		(keepout
			(tracks not_allowed)
			(vias allowed)
			(pads allowed)
			(copperpour not_allowed)
			(footprints allowed)
		)
		(placement
			(enabled no)
			(sheetname "")
		)
		(fill yes
			(thermal_gap 0.5)
			(thermal_bridge_width 0.5)
			(island_removal_mode 0)
		)
		(polygon
			(pts
				(arc
					(start 11.490198 -302.071532)
					(mid 11.505077 -302.107453)
					(end 11.540998 -302.122332)
				)
				(arc
					(start 12.940538 -302.122332)
					(mid 12.976459 -302.107453)
					(end 12.991338 -302.071532)
				)
				(arc
					(start 12.991338 -301.662592)
					(mid 12.976459 -301.626671)
					(end 12.940538 -301.611792)
				)
				(arc
					(start 11.540998 -301.611792)
					(mid 11.505077 -301.626671)
					(end 11.490198 -301.662592)
				)
			)
		)
	)
	(zone
		(layers "In1.Cu" "In2.Cu")
		(hatch none 0.5)
		(connect_pads
			(clearance 0)
		)
		(min_thickness 0.25)
		(keepout
			(tracks not_allowed)
			(vias allowed)
			(pads allowed)
			(copperpour not_allowed)
			(footprints allowed)
		)
		(placement
			(enabled no)
			(sheetname "")
		)
		(fill yes
			(thermal_gap 0.5)
			(thermal_bridge_width 0.5)
			(island_removal_mode 0)
		)
		(polygon
			(pts
				(arc
					(start 165.60673 -266.371324)
					(mid 165.621609 -266.407245)
					(end 165.65753 -266.422124)
				)
				(arc
					(start 167.05707 -266.422124)
					(mid 167.092991 -266.407245)
					(end 167.10787 -266.371324)
				)
				(arc
					(start 167.10787 -265.962384)
					(mid 167.092991 -265.926463)
					(end 167.05707 -265.911584)
				)
				(arc
					(start 165.65753 -265.911584)
					(mid 165.621609 -265.926463)
					(end 165.60673 -265.962384)
				)
			)
		)
	)
	(zone
		(layers "In1.Cu" "In2.Cu")
		(hatch none 0.5)
		(connect_pads
			(clearance 0)
		)
		(min_thickness 0.25)
		(keepout
			(tracks not_allowed)
			(vias allowed)
			(pads allowed)
			(copperpour not_allowed)
			(footprints allowed)
		)
		(placement
			(enabled no)
			(sheetname "")
		)
		(fill yes
			(thermal_gap 0.5)
			(thermal_bridge_width 0.5)
			(island_removal_mode 0)
		)
		(polygon
			(pts
				(arc
					(start 210.86953 -249.371358)
					(mid 210.884409 -249.407279)
					(end 210.92033 -249.422158)
				)
				(arc
					(start 212.31987 -249.422158)
					(mid 212.355791 -249.407279)
					(end 212.37067 -249.371358)
				)
				(arc
					(start 212.37067 -248.962418)
					(mid 212.355791 -248.926497)
					(end 212.31987 -248.911618)
				)
				(arc
					(start 210.92033 -248.911618)
					(mid 210.884409 -248.926497)
					(end 210.86953 -248.962418)
				)
			)
		)
	)
	(zone
		(layers "In1.Cu" "In2.Cu")
		(hatch none 0.5)
		(connect_pads
			(clearance 0)
		)
		(min_thickness 0.25)
		(keepout
			(tracks not_allowed)
			(vias allowed)
			(pads allowed)
			(copperpour not_allowed)
			(footprints allowed)
		)
		(placement
			(enabled no)
			(sheetname "")
		)
		(fill yes
			(thermal_gap 0.5)
			(thermal_bridge_width 0.5)
			(island_removal_mode 0)
		)
		(polygon
			(pts
				(arc
					(start 262.873998 -259.57149)
					(mid 262.888877 -259.607411)
					(end 262.924798 -259.62229)
				)
				(arc
					(start 264.324338 -259.62229)
					(mid 264.360259 -259.607411)
					(end 264.375138 -259.57149)
				)
				(arc
					(start 264.375138 -259.16255)
					(mid 264.360259 -259.126629)
					(end 264.324338 -259.11175)
				)
				(arc
					(start 262.924798 -259.11175)
					(mid 262.888877 -259.126629)
					(end 262.873998 -259.16255)
				)
			)
		)
	)
	(zone
		(layers "In1.Cu" "In2.Cu")
		(hatch none 0.5)
		(connect_pads
			(clearance 0)
		)
		(min_thickness 0.25)
		(keepout
			(tracks not_allowed)
			(vias allowed)
			(pads allowed)
			(copperpour not_allowed)
			(footprints allowed)
		)
		(placement
			(enabled no)
			(sheetname "")
		)
		(fill yes
			(thermal_gap 0.5)
			(thermal_bridge_width 0.5)
			(island_removal_mode 0)
		)
		(polygon
			(pts
				(arc
					(start 49.209198 -298.671488)
					(mid 49.224077 -298.707409)
					(end 49.259998 -298.722288)
				)
				(arc
					(start 50.659538 -298.722288)
					(mid 50.695459 -298.707409)
					(end 50.710338 -298.671488)
				)
				(arc
					(start 50.710338 -298.262548)
					(mid 50.695459 -298.226627)
					(end 50.659538 -298.211748)
				)
				(arc
					(start 49.259998 -298.211748)
					(mid 49.224077 -298.226627)
					(end 49.209198 -298.262548)
				)
			)
		)
	)
	(zone
		(layers "In1.Cu" "In2.Cu")
		(hatch none 0.5)
		(connect_pads
			(clearance 0)
		)
		(min_thickness 0.25)
		(keepout
			(tracks not_allowed)
			(vias allowed)
			(pads allowed)
			(copperpour not_allowed)
			(footprints allowed)
		)
		(placement
			(enabled no)
			(sheetname "")
		)
		(fill yes
			(thermal_gap 0.5)
			(thermal_bridge_width 0.5)
			(island_removal_mode 0)
		)
		(polygon
			(pts
				(arc
					(start 282.061666 -287.621472)
					(mid 282.076545 -287.657393)
					(end 282.112466 -287.672272)
				)
				(arc
					(start 283.512006 -287.672272)
					(mid 283.547927 -287.657393)
					(end 283.562806 -287.621472)
				)
				(arc
					(start 283.562806 -287.212532)
					(mid 283.547927 -287.176611)
					(end 283.512006 -287.161732)
				)
				(arc
					(start 282.112466 -287.161732)
					(mid 282.076545 -287.176611)
					(end 282.061666 -287.212532)
				)
			)
		)
	)
	(zone
		(layers "In1.Cu" "In2.Cu")
		(hatch none 0.5)
		(connect_pads
			(clearance 0)
		)
		(min_thickness 0.25)
		(keepout
			(tracks not_allowed)
			(vias allowed)
			(pads allowed)
			(copperpour not_allowed)
			(footprints allowed)
		)
		(placement
			(enabled no)
			(sheetname "")
		)
		(fill yes
			(thermal_gap 0.5)
			(thermal_bridge_width 0.5)
			(island_removal_mode 0)
		)
		(polygon
			(pts
				(arc
					(start 169.706798 -311.421526)
					(mid 169.721677 -311.457447)
					(end 169.757598 -311.472326)
				)
				(arc
					(start 171.157138 -311.472326)
					(mid 171.193059 -311.457447)
					(end 171.207938 -311.421526)
				)
				(arc
					(start 171.207938 -311.012586)
					(mid 171.193059 -310.976665)
					(end 171.157138 -310.961786)
				)
				(arc
					(start 169.757598 -310.961786)
					(mid 169.721677 -310.976665)
					(end 169.706798 -311.012586)
				)
			)
		)
	)
	(zone
		(layers "In1.Cu" "In2.Cu")
		(hatch none 0.5)
		(connect_pads
			(clearance 0)
		)
		(min_thickness 0.25)
		(keepout
			(tracks not_allowed)
			(vias allowed)
			(pads allowed)
			(copperpour not_allowed)
			(footprints allowed)
		)
		(placement
			(enabled no)
			(sheetname "")
		)
		(fill yes
			(thermal_gap 0.5)
			(thermal_bridge_width 0.5)
			(island_removal_mode 0)
		)
		(polygon
			(pts
				(arc
					(start 455.365866 -293.571422)
					(mid 455.380745 -293.607343)
					(end 455.416666 -293.622222)
				)
				(arc
					(start 456.816206 -293.622222)
					(mid 456.852127 -293.607343)
					(end 456.867006 -293.571422)
				)
				(arc
					(start 456.867006 -293.162482)
					(mid 456.852127 -293.126561)
					(end 456.816206 -293.111682)
				)
				(arc
					(start 455.416666 -293.111682)
					(mid 455.380745 -293.126561)
					(end 455.365866 -293.162482)
				)
			)
		)
	)
	(zone
		(layers "In1.Cu" "In2.Cu")
		(hatch none 0.5)
		(connect_pads
			(clearance 0)
		)
		(min_thickness 0.25)
		(keepout
			(tracks not_allowed)
			(vias allowed)
			(pads allowed)
			(copperpour not_allowed)
			(footprints allowed)
		)
		(placement
			(enabled no)
			(sheetname "")
		)
		(fill yes
			(thermal_gap 0.5)
			(thermal_bridge_width 0.5)
			(island_removal_mode 0)
		)
		(polygon
			(pts
				(arc
					(start 64.296798 -265.52144)
					(mid 64.311677 -265.557361)
					(end 64.347598 -265.57224)
				)
				(arc
					(start 65.747138 -265.57224)
					(mid 65.783059 -265.557361)
					(end 65.797938 -265.52144)
				)
				(arc
					(start 65.797938 -265.1125)
					(mid 65.783059 -265.076579)
					(end 65.747138 -265.0617)
				)
				(arc
					(start 64.347598 -265.0617)
					(mid 64.311677 -265.076579)
					(end 64.296798 -265.1125)
				)
			)
		)
	)
	(zone
		(layers "In1.Cu" "In2.Cu")
		(hatch none 0.5)
		(connect_pads
			(clearance 0)
		)
		(min_thickness 0.25)
		(keepout
			(tracks not_allowed)
			(vias allowed)
			(pads allowed)
			(copperpour not_allowed)
			(footprints allowed)
		)
		(placement
			(enabled no)
			(sheetname "")
		)
		(fill yes
			(thermal_gap 0.5)
			(thermal_bridge_width 0.5)
			(island_removal_mode 0)
		)
		(polygon
			(pts
				(arc
					(start 312.236866 -217.921332)
					(mid 312.251745 -217.957253)
					(end 312.287666 -217.972132)
				)
				(arc
					(start 313.687206 -217.972132)
					(mid 313.723127 -217.957253)
					(end 313.738006 -217.921332)
				)
				(arc
					(start 313.738006 -217.512392)
					(mid 313.723127 -217.476471)
					(end 313.687206 -217.461592)
				)
				(arc
					(start 312.287666 -217.461592)
					(mid 312.251745 -217.476471)
					(end 312.236866 -217.512392)
				)
			)
		)
	)
	(zone
		(layers "In1.Cu" "In2.Cu")
		(hatch none 0.5)
		(connect_pads
			(clearance 0)
		)
		(min_thickness 0.25)
		(keepout
			(tracks not_allowed)
			(vias allowed)
			(pads allowed)
			(copperpour not_allowed)
			(footprints allowed)
		)
		(placement
			(enabled no)
			(sheetname "")
		)
		(fill yes
			(thermal_gap 0.5)
			(thermal_bridge_width 0.5)
			(island_removal_mode 0)
		)
		(polygon
			(pts
				(arc
					(start 440.278266 -281.671522)
					(mid 440.293145 -281.707443)
					(end 440.329066 -281.722322)
				)
				(arc
					(start 441.728606 -281.722322)
					(mid 441.764527 -281.707443)
					(end 441.779406 -281.671522)
				)
				(arc
					(start 441.779406 -281.262582)
					(mid 441.764527 -281.226661)
					(end 441.728606 -281.211782)
				)
				(arc
					(start 440.329066 -281.211782)
					(mid 440.293145 -281.226661)
					(end 440.278266 -281.262582)
				)
			)
		)
	)
	(zone
		(layers "In1.Cu" "In2.Cu")
		(hatch none 0.5)
		(connect_pads
			(clearance 0)
		)
		(min_thickness 0.25)
		(keepout
			(tracks not_allowed)
			(vias allowed)
			(pads allowed)
			(copperpour not_allowed)
			(footprints allowed)
		)
		(placement
			(enabled no)
			(sheetname "")
		)
		(fill yes
			(thermal_gap 0.5)
			(thermal_bridge_width 0.5)
			(island_removal_mode 0)
		)
		(polygon
			(pts
				(arc
					(start 173.15053 -215.371426)
					(mid 173.165409 -215.407347)
					(end 173.20133 -215.422226)
				)
				(arc
					(start 174.60087 -215.422226)
					(mid 174.636791 -215.407347)
					(end 174.65167 -215.371426)
				)
				(arc
					(start 174.65167 -214.962486)
					(mid 174.636791 -214.926565)
					(end 174.60087 -214.911686)
				)
				(arc
					(start 173.20133 -214.911686)
					(mid 173.165409 -214.926565)
					(end 173.15053 -214.962486)
				)
			)
		)
	)
	(zone
		(layers "In1.Cu" "In2.Cu")
		(hatch none 0.5)
		(connect_pads
			(clearance 0)
		)
		(min_thickness 0.25)
		(keepout
			(tracks not_allowed)
			(vias allowed)
			(pads allowed)
			(copperpour not_allowed)
			(footprints allowed)
		)
		(placement
			(enabled no)
			(sheetname "")
		)
		(fill yes
			(thermal_gap 0.5)
			(thermal_bridge_width 0.5)
			(island_removal_mode 0)
		)
		(polygon
			(pts
				(arc
					(start 60.19673 -252.771402)
					(mid 60.211609 -252.807323)
					(end 60.24753 -252.822202)
				)
				(arc
					(start 61.64707 -252.822202)
					(mid 61.682991 -252.807323)
					(end 61.69787 -252.771402)
				)
				(arc
					(start 61.69787 -252.362462)
					(mid 61.682991 -252.326541)
					(end 61.64707 -252.311662)
				)
				(arc
					(start 60.24753 -252.311662)
					(mid 60.211609 -252.326541)
					(end 60.19673 -252.362462)
				)
			)
		)
	)
	(zone
		(layers "In1.Cu" "In2.Cu")
		(hatch none 0.5)
		(connect_pads
			(clearance 0)
		)
		(min_thickness 0.25)
		(keepout
			(tracks not_allowed)
			(vias allowed)
			(pads allowed)
			(copperpour not_allowed)
			(footprints allowed)
		)
		(placement
			(enabled no)
			(sheetname "")
		)
		(fill yes
			(thermal_gap 0.5)
			(thermal_bridge_width 0.5)
			(island_removal_mode 0)
		)
		(polygon
			(pts
				(arc
					(start 210.86953 -213.671404)
					(mid 210.884409 -213.707325)
					(end 210.92033 -213.722204)
				)
				(arc
					(start 212.31987 -213.722204)
					(mid 212.355791 -213.707325)
					(end 212.37067 -213.671404)
				)
				(arc
					(start 212.37067 -213.262464)
					(mid 212.355791 -213.226543)
					(end 212.31987 -213.211664)
				)
				(arc
					(start 210.92033 -213.211664)
					(mid 210.884409 -213.226543)
					(end 210.86953 -213.262464)
				)
			)
		)
	)
	(zone
		(layers "In1.Cu" "In2.Cu")
		(hatch none 0.5)
		(connect_pads
			(clearance 0)
		)
		(min_thickness 0.25)
		(keepout
			(tracks not_allowed)
			(vias allowed)
			(pads allowed)
			(copperpour not_allowed)
			(footprints allowed)
		)
		(placement
			(enabled no)
			(sheetname "")
		)
		(fill yes
			(thermal_gap 0.5)
			(thermal_bridge_width 0.5)
			(island_removal_mode 0)
		)
		(polygon
			(pts
				(arc
					(start 195.78193 -249.371358)
					(mid 195.796809 -249.407279)
					(end 195.83273 -249.422158)
				)
				(arc
					(start 197.23227 -249.422158)
					(mid 197.268191 -249.407279)
					(end 197.28307 -249.371358)
				)
				(arc
					(start 197.28307 -248.962418)
					(mid 197.268191 -248.926497)
					(end 197.23227 -248.911618)
				)
				(arc
					(start 195.83273 -248.911618)
					(mid 195.796809 -248.926497)
					(end 195.78193 -248.962418)
				)
			)
		)
	)
	(zone
		(layers "In1.Cu" "In2.Cu")
		(hatch none 0.5)
		(connect_pads
			(clearance 0)
		)
		(min_thickness 0.25)
		(keepout
			(tracks not_allowed)
			(vias allowed)
			(pads allowed)
			(copperpour not_allowed)
			(footprints allowed)
		)
		(placement
			(enabled no)
			(sheetname "")
		)
		(fill yes
			(thermal_gap 0.5)
			(thermal_bridge_width 0.5)
			(island_removal_mode 0)
		)
		(polygon
			(pts
				(arc
					(start 421.090598 -261.271512)
					(mid 421.105477 -261.307433)
					(end 421.141398 -261.322312)
				)
				(arc
					(start 422.540938 -261.322312)
					(mid 422.576859 -261.307433)
					(end 422.591738 -261.271512)
				)
				(arc
					(start 422.591738 -260.862572)
					(mid 422.576859 -260.826651)
					(end 422.540938 -260.811772)
				)
				(arc
					(start 421.141398 -260.811772)
					(mid 421.105477 -260.826651)
					(end 421.090598 -260.862572)
				)
			)
		)
	)
	(zone
		(layers "In1.Cu" "In2.Cu")
		(hatch none 0.5)
		(connect_pads
			(clearance 0)
		)
		(min_thickness 0.25)
		(keepout
			(tracks not_allowed)
			(vias allowed)
			(pads allowed)
			(copperpour not_allowed)
			(footprints allowed)
		)
		(placement
			(enabled no)
			(sheetname "")
		)
		(fill yes
			(thermal_gap 0.5)
			(thermal_bridge_width 0.5)
			(island_removal_mode 0)
		)
		(polygon
			(pts
				(arc
					(start 455.365866 -306.32146)
					(mid 455.380745 -306.357381)
					(end 455.416666 -306.37226)
				)
				(arc
					(start 456.816206 -306.37226)
					(mid 456.852127 -306.357381)
					(end 456.867006 -306.32146)
				)
				(arc
					(start 456.867006 -305.91252)
					(mid 456.852127 -305.876599)
					(end 456.816206 -305.86172)
				)
				(arc
					(start 455.416666 -305.86172)
					(mid 455.380745 -305.876599)
					(end 455.365866 -305.91252)
				)
			)
		)
	)
	(zone
		(layers "In1.Cu" "In2.Cu")
		(hatch none 0.5)
		(connect_pads
			(clearance 0)
		)
		(min_thickness 0.25)
		(keepout
			(tracks not_allowed)
			(vias allowed)
			(pads allowed)
			(copperpour not_allowed)
			(footprints allowed)
		)
		(placement
			(enabled no)
			(sheetname "")
		)
		(fill yes
			(thermal_gap 0.5)
			(thermal_bridge_width 0.5)
			(island_removal_mode 0)
		)
		(polygon
			(pts
				(arc
					(start 210.86953 -268.071346)
					(mid 210.884409 -268.107267)
					(end 210.92033 -268.122146)
				)
				(arc
					(start 212.31987 -268.122146)
					(mid 212.355791 -268.107267)
					(end 212.37067 -268.071346)
				)
				(arc
					(start 212.37067 -267.662406)
					(mid 212.355791 -267.626485)
					(end 212.31987 -267.611606)
				)
				(arc
					(start 210.92033 -267.611606)
					(mid 210.884409 -267.626485)
					(end 210.86953 -267.662406)
				)
			)
		)
	)
	(zone
		(layers "In1.Cu" "In2.Cu")
		(hatch none 0.5)
		(connect_pads
			(clearance 0)
		)
		(min_thickness 0.25)
		(keepout
			(tracks not_allowed)
			(vias allowed)
			(pads allowed)
			(copperpour not_allowed)
			(footprints allowed)
		)
		(placement
			(enabled no)
			(sheetname "")
		)
		(fill yes
			(thermal_gap 0.5)
			(thermal_bridge_width 0.5)
			(island_removal_mode 0)
		)
		(polygon
			(pts
				(arc
					(start 277.961598 -275.721318)
					(mid 277.976477 -275.757239)
					(end 278.012398 -275.772118)
				)
				(arc
					(start 279.411938 -275.772118)
					(mid 279.447859 -275.757239)
					(end 279.462738 -275.721318)
				)
				(arc
					(start 279.462738 -275.312378)
					(mid 279.447859 -275.276457)
					(end 279.411938 -275.261578)
				)
				(arc
					(start 278.012398 -275.261578)
					(mid 277.976477 -275.276457)
					(end 277.961598 -275.312378)
				)
			)
		)
	)
	(zone
		(layers "In1.Cu" "In2.Cu")
		(hatch none 0.5)
		(connect_pads
			(clearance 0)
		)
		(min_thickness 0.25)
		(keepout
			(tracks not_allowed)
			(vias allowed)
			(pads allowed)
			(copperpour not_allowed)
			(footprints allowed)
		)
		(placement
			(enabled no)
			(sheetname "")
		)
		(fill yes
			(thermal_gap 0.5)
			(thermal_bridge_width 0.5)
			(island_removal_mode 0)
		)
		(polygon
			(pts
				(arc
					(start 162.162998 -216.22131)
					(mid 162.177877 -216.257231)
					(end 162.213798 -216.27211)
				)
				(arc
					(start 163.613338 -216.27211)
					(mid 163.649259 -216.257231)
					(end 163.664138 -216.22131)
				)
				(arc
					(start 163.664138 -215.81237)
					(mid 163.649259 -215.776449)
					(end 163.613338 -215.76157)
				)
				(arc
					(start 162.213798 -215.76157)
					(mid 162.177877 -215.776449)
					(end 162.162998 -215.81237)
				)
			)
		)
	)
	(zone
		(layers "In1.Cu" "In2.Cu")
		(hatch none 0.5)
		(connect_pads
			(clearance 0)
		)
		(min_thickness 0.25)
		(keepout
			(tracks not_allowed)
			(vias allowed)
			(pads allowed)
			(copperpour not_allowed)
			(footprints allowed)
		)
		(placement
			(enabled no)
			(sheetname "")
		)
		(fill yes
			(thermal_gap 0.5)
			(thermal_bridge_width 0.5)
			(island_removal_mode 0)
		)
		(polygon
			(pts
				(arc
					(start 413.546798 -296.121328)
					(mid 413.561677 -296.157249)
					(end 413.597598 -296.172128)
				)
				(arc
					(start 414.997138 -296.172128)
					(mid 415.033059 -296.157249)
					(end 415.047938 -296.121328)
				)
				(arc
					(start 415.047938 -295.712388)
					(mid 415.033059 -295.676467)
					(end 414.997138 -295.661588)
				)
				(arc
					(start 413.597598 -295.661588)
					(mid 413.561677 -295.676467)
					(end 413.546798 -295.712388)
				)
			)
		)
	)
	(zone
		(layers "In1.Cu" "In2.Cu")
		(hatch none 0.5)
		(connect_pads
			(clearance 0)
		)
		(min_thickness 0.25)
		(keepout
			(tracks not_allowed)
			(vias allowed)
			(pads allowed)
			(copperpour not_allowed)
			(footprints allowed)
		)
		(placement
			(enabled no)
			(sheetname "")
		)
		(fill yes
			(thermal_gap 0.5)
			(thermal_bridge_width 0.5)
			(island_removal_mode 0)
		)
		(polygon
			(pts
				(arc
					(start 37.56533 -221.321376)
					(mid 37.580209 -221.357297)
					(end 37.61613 -221.372176)
				)
				(arc
					(start 39.01567 -221.372176)
					(mid 39.051591 -221.357297)
					(end 39.06647 -221.321376)
				)
				(arc
					(start 39.06647 -220.912436)
					(mid 39.051591 -220.876515)
					(end 39.01567 -220.861636)
				)
				(arc
					(start 37.61613 -220.861636)
					(mid 37.580209 -220.876515)
					(end 37.56533 -220.912436)
				)
			)
		)
	)
	(zone
		(layers "In1.Cu" "In2.Cu")
		(hatch none 0.5)
		(connect_pads
			(clearance 0)
		)
		(min_thickness 0.25)
		(keepout
			(tracks not_allowed)
			(vias allowed)
			(pads allowed)
			(copperpour not_allowed)
			(footprints allowed)
		)
		(placement
			(enabled no)
			(sheetname "")
		)
		(fill yes
			(thermal_gap 0.5)
			(thermal_bridge_width 0.5)
			(island_removal_mode 0)
		)
		(polygon
			(pts
				(arc
					(start 308.136798 -266.371324)
					(mid 308.151677 -266.407245)
					(end 308.187598 -266.422124)
				)
				(arc
					(start 309.587138 -266.422124)
					(mid 309.623059 -266.407245)
					(end 309.637938 -266.371324)
				)
				(arc
					(start 309.637938 -265.962384)
					(mid 309.623059 -265.926463)
					(end 309.587138 -265.911584)
				)
				(arc
					(start 308.187598 -265.911584)
					(mid 308.151677 -265.926463)
					(end 308.136798 -265.962384)
				)
			)
		)
	)
	(zone
		(layers "In1.Cu" "In2.Cu")
		(hatch none 0.5)
		(connect_pads
			(clearance 0)
		)
		(min_thickness 0.25)
		(keepout
			(tracks not_allowed)
			(vias allowed)
			(pads allowed)
			(copperpour not_allowed)
			(footprints allowed)
		)
		(placement
			(enabled no)
			(sheetname "")
		)
		(fill yes
			(thermal_gap 0.5)
			(thermal_bridge_width 0.5)
			(island_removal_mode 0)
		)
		(polygon
			(pts
				(arc
					(start 214.969598 -203.471526)
					(mid 214.984477 -203.507447)
					(end 215.020398 -203.522326)
				)
				(arc
					(start 216.419938 -203.522326)
					(mid 216.455859 -203.507447)
					(end 216.470738 -203.471526)
				)
				(arc
					(start 216.470738 -203.062586)
					(mid 216.455859 -203.026665)
					(end 216.419938 -203.011786)
				)
				(arc
					(start 215.020398 -203.011786)
					(mid 214.984477 -203.026665)
					(end 214.969598 -203.062586)
				)
			)
		)
	)
	(zone
		(layers "In1.Cu" "In2.Cu")
		(hatch none 0.5)
		(connect_pads
			(clearance 0)
		)
		(min_thickness 0.25)
		(keepout
			(tracks not_allowed)
			(vias allowed)
			(pads allowed)
			(copperpour not_allowed)
			(footprints allowed)
		)
		(placement
			(enabled no)
			(sheetname "")
		)
		(fill yes
			(thermal_gap 0.5)
			(thermal_bridge_width 0.5)
			(island_removal_mode 0)
		)
		(polygon
			(pts
				(arc
					(start 64.296798 -291.021516)
					(mid 64.311677 -291.057437)
					(end 64.347598 -291.072316)
				)
				(arc
					(start 65.747138 -291.072316)
					(mid 65.783059 -291.057437)
					(end 65.797938 -291.021516)
				)
				(arc
					(start 65.797938 -290.612576)
					(mid 65.783059 -290.576655)
					(end 65.747138 -290.561776)
				)
				(arc
					(start 64.347598 -290.561776)
					(mid 64.311677 -290.576655)
					(end 64.296798 -290.612576)
				)
			)
		)
	)
	(zone
		(layers "In1.Cu" "In2.Cu")
		(hatch none 0.5)
		(connect_pads
			(clearance 0)
		)
		(min_thickness 0.25)
		(keepout
			(tracks not_allowed)
			(vias allowed)
			(pads allowed)
			(copperpour not_allowed)
			(footprints allowed)
		)
		(placement
			(enabled no)
			(sheetname "")
		)
		(fill yes
			(thermal_gap 0.5)
			(thermal_bridge_width 0.5)
			(island_removal_mode 0)
		)
		(polygon
			(pts
				(arc
					(start 192.338198 -263.821418)
					(mid 192.353077 -263.857339)
					(end 192.388998 -263.872218)
				)
				(arc
					(start 193.788538 -263.872218)
					(mid 193.824459 -263.857339)
					(end 193.839338 -263.821418)
				)
				(arc
					(start 193.839338 -263.412478)
					(mid 193.824459 -263.376557)
					(end 193.788538 -263.361678)
				)
				(arc
					(start 192.388998 -263.361678)
					(mid 192.353077 -263.376557)
					(end 192.338198 -263.412478)
				)
			)
		)
	)
	(zone
		(layers "In1.Cu" "In2.Cu")
		(hatch none 0.5)
		(connect_pads
			(clearance 0)
		)
		(min_thickness 0.25)
		(keepout
			(tracks not_allowed)
			(vias allowed)
			(pads allowed)
			(copperpour not_allowed)
			(footprints allowed)
		)
		(placement
			(enabled no)
			(sheetname "")
		)
		(fill yes
			(thermal_gap 0.5)
			(thermal_bridge_width 0.5)
			(island_removal_mode 0)
		)
		(polygon
			(pts
				(arc
					(start 37.56533 -232.371392)
					(mid 37.580209 -232.407313)
					(end 37.61613 -232.422192)
				)
				(arc
					(start 39.01567 -232.422192)
					(mid 39.051591 -232.407313)
					(end 39.06647 -232.371392)
				)
				(arc
					(start 39.06647 -231.962452)
					(mid 39.051591 -231.926531)
					(end 39.01567 -231.911652)
				)
				(arc
					(start 37.61613 -231.911652)
					(mid 37.580209 -231.926531)
					(end 37.56533 -231.962452)
				)
			)
		)
	)
	(zone
		(layers "In1.Cu" "In2.Cu")
		(hatch none 0.5)
		(connect_pads
			(clearance 0)
		)
		(min_thickness 0.25)
		(keepout
			(tracks not_allowed)
			(vias allowed)
			(pads allowed)
			(copperpour not_allowed)
			(footprints allowed)
		)
		(placement
			(enabled no)
			(sheetname "")
		)
		(fill yes
			(thermal_gap 0.5)
			(thermal_bridge_width 0.5)
			(island_removal_mode 0)
		)
		(polygon
			(pts
				(arc
					(start 195.78193 -293.571422)
					(mid 195.796809 -293.607343)
					(end 195.83273 -293.622222)
				)
				(arc
					(start 197.23227 -293.622222)
					(mid 197.268191 -293.607343)
					(end 197.28307 -293.571422)
				)
				(arc
					(start 197.28307 -293.162482)
					(mid 197.268191 -293.126561)
					(end 197.23227 -293.111682)
				)
				(arc
					(start 195.83273 -293.111682)
					(mid 195.796809 -293.126561)
					(end 195.78193 -293.162482)
				)
			)
		)
	)
	(zone
		(layers "In1.Cu" "In2.Cu")
		(hatch none 0.5)
		(connect_pads
			(clearance 0)
		)
		(min_thickness 0.25)
		(keepout
			(tracks not_allowed)
			(vias allowed)
			(pads allowed)
			(copperpour not_allowed)
			(footprints allowed)
		)
		(placement
			(enabled no)
			(sheetname "")
		)
		(fill yes
			(thermal_gap 0.5)
			(thermal_bridge_width 0.5)
			(island_removal_mode 0)
		)
		(polygon
			(pts
				(arc
					(start 259.430266 -262.121396)
					(mid 259.445145 -262.157317)
					(end 259.481066 -262.172196)
				)
				(arc
					(start 260.880606 -262.172196)
					(mid 260.916527 -262.157317)
					(end 260.931406 -262.121396)
				)
				(arc
					(start 260.931406 -261.712456)
					(mid 260.916527 -261.676535)
					(end 260.880606 -261.661656)
				)
				(arc
					(start 259.481066 -261.661656)
					(mid 259.445145 -261.676535)
					(end 259.430266 -261.712456)
				)
			)
		)
	)
	(zone
		(layers "In1.Cu" "In2.Cu")
		(hatch none 0.5)
		(connect_pads
			(clearance 0)
		)
		(min_thickness 0.25)
		(keepout
			(tracks not_allowed)
			(vias allowed)
			(pads allowed)
			(copperpour not_allowed)
			(footprints allowed)
		)
		(placement
			(enabled no)
			(sheetname "")
		)
		(fill yes
			(thermal_gap 0.5)
			(thermal_bridge_width 0.5)
			(island_removal_mode 0)
		)
		(polygon
			(pts
				(arc
					(start 203.32573 -299.521372)
					(mid 203.340609 -299.557293)
					(end 203.37653 -299.572172)
				)
				(arc
					(start 204.77607 -299.572172)
					(mid 204.811991 -299.557293)
					(end 204.82687 -299.521372)
				)
				(arc
					(start 204.82687 -299.112432)
					(mid 204.811991 -299.076511)
					(end 204.77607 -299.061632)
				)
				(arc
					(start 203.37653 -299.061632)
					(mid 203.340609 -299.076511)
					(end 203.32573 -299.112432)
				)
			)
		)
	)
	(zone
		(layers "In1.Cu" "In2.Cu")
		(hatch none 0.5)
		(connect_pads
			(clearance 0)
		)
		(min_thickness 0.25)
		(keepout
			(tracks not_allowed)
			(vias allowed)
			(pads allowed)
			(copperpour not_allowed)
			(footprints allowed)
		)
		(placement
			(enabled no)
			(sheetname "")
		)
		(fill yes
			(thermal_gap 0.5)
			(thermal_bridge_width 0.5)
			(island_removal_mode 0)
		)
		(polygon
			(pts
				(arc
					(start 417.646866 -311.421526)
					(mid 417.661745 -311.457447)
					(end 417.697666 -311.472326)
				)
				(arc
					(start 419.097206 -311.472326)
					(mid 419.133127 -311.457447)
					(end 419.148006 -311.421526)
				)
				(arc
					(start 419.148006 -311.012586)
					(mid 419.133127 -310.976665)
					(end 419.097206 -310.961786)
				)
				(arc
					(start 417.697666 -310.961786)
					(mid 417.661745 -310.976665)
					(end 417.646866 -311.012586)
				)
			)
		)
	)
	(zone
		(layers "In1.Cu" "In2.Cu")
		(hatch none 0.5)
		(connect_pads
			(clearance 0)
		)
		(min_thickness 0.25)
		(keepout
			(tracks not_allowed)
			(vias allowed)
			(pads allowed)
			(copperpour not_allowed)
			(footprints allowed)
		)
		(placement
			(enabled no)
			(sheetname "")
		)
		(fill yes
			(thermal_gap 0.5)
			(thermal_bridge_width 0.5)
			(island_removal_mode 0)
		)
		(polygon
			(pts
				(arc
					(start 195.78193 -232.371392)
					(mid 195.796809 -232.407313)
					(end 195.83273 -232.422192)
				)
				(arc
					(start 197.23227 -232.422192)
					(mid 197.268191 -232.407313)
					(end 197.28307 -232.371392)
				)
				(arc
					(start 197.28307 -231.962452)
					(mid 197.268191 -231.926531)
					(end 197.23227 -231.911652)
				)
				(arc
					(start 195.83273 -231.911652)
					(mid 195.796809 -231.926531)
					(end 195.78193 -231.962452)
				)
			)
		)
	)
	(zone
		(layers "In1.Cu" "In2.Cu")
		(hatch none 0.5)
		(connect_pads
			(clearance 0)
		)
		(min_thickness 0.25)
		(keepout
			(tracks not_allowed)
			(vias allowed)
			(pads allowed)
			(copperpour not_allowed)
			(footprints allowed)
		)
		(placement
			(enabled no)
			(sheetname "")
		)
		(fill yes
			(thermal_gap 0.5)
			(thermal_bridge_width 0.5)
			(island_removal_mode 0)
		)
		(polygon
			(pts
				(arc
					(start 30.02153 -200.921366)
					(mid 30.036409 -200.957287)
					(end 30.07233 -200.972166)
				)
				(arc
					(start 31.47187 -200.972166)
					(mid 31.507791 -200.957287)
					(end 31.52267 -200.921366)
				)
				(arc
					(start 31.52267 -200.512426)
					(mid 31.507791 -200.476505)
					(end 31.47187 -200.461626)
				)
				(arc
					(start 30.07233 -200.461626)
					(mid 30.036409 -200.476505)
					(end 30.02153 -200.512426)
				)
			)
		)
	)
	(zone
		(layers "In1.Cu" "In2.Cu")
		(hatch none 0.5)
		(connect_pads
			(clearance 0)
		)
		(min_thickness 0.25)
		(keepout
			(tracks not_allowed)
			(vias allowed)
			(pads allowed)
			(copperpour not_allowed)
			(footprints allowed)
		)
		(placement
			(enabled no)
			(sheetname "")
		)
		(fill yes
			(thermal_gap 0.5)
			(thermal_bridge_width 0.5)
			(island_removal_mode 0)
		)
		(polygon
			(pts
				(arc
					(start 195.78193 -240.021364)
					(mid 195.796809 -240.057285)
					(end 195.83273 -240.072164)
				)
				(arc
					(start 197.23227 -240.072164)
					(mid 197.268191 -240.057285)
					(end 197.28307 -240.021364)
				)
				(arc
					(start 197.28307 -239.612424)
					(mid 197.268191 -239.576503)
					(end 197.23227 -239.561624)
				)
				(arc
					(start 195.83273 -239.561624)
					(mid 195.796809 -239.576503)
					(end 195.78193 -239.612424)
				)
			)
		)
	)
	(zone
		(layers "In1.Cu" "In2.Cu")
		(hatch none 0.5)
		(connect_pads
			(clearance 0)
		)
		(min_thickness 0.25)
		(keepout
			(tracks not_allowed)
			(vias allowed)
			(pads allowed)
			(copperpour not_allowed)
			(footprints allowed)
		)
		(placement
			(enabled no)
			(sheetname "")
		)
		(fill yes
			(thermal_gap 0.5)
			(thermal_bridge_width 0.5)
			(island_removal_mode 0)
		)
		(polygon
			(pts
				(arc
					(start 7.39013 -234.071414)
					(mid 7.405009 -234.107335)
					(end 7.44093 -234.122214)
				)
				(arc
					(start 8.84047 -234.122214)
					(mid 8.876391 -234.107335)
					(end 8.89127 -234.071414)
				)
				(arc
					(start 8.89127 -233.662474)
					(mid 8.876391 -233.626553)
					(end 8.84047 -233.611674)
				)
				(arc
					(start 7.44093 -233.611674)
					(mid 7.405009 -233.626553)
					(end 7.39013 -233.662474)
				)
			)
		)
	)
	(zone
		(layers "In1.Cu" "In2.Cu")
		(hatch none 0.5)
		(connect_pads
			(clearance 0)
		)
		(min_thickness 0.25)
		(keepout
			(tracks not_allowed)
			(vias allowed)
			(pads allowed)
			(copperpour not_allowed)
			(footprints allowed)
		)
		(placement
			(enabled no)
			(sheetname "")
		)
		(fill yes
			(thermal_gap 0.5)
			(thermal_bridge_width 0.5)
			(island_removal_mode 0)
		)
		(polygon
			(pts
				(arc
					(start 462.909666 -311.421526)
					(mid 462.924545 -311.457447)
					(end 462.960466 -311.472326)
				)
				(arc
					(start 464.360006 -311.472326)
					(mid 464.395927 -311.457447)
					(end 464.410806 -311.421526)
				)
				(arc
					(start 464.410806 -311.012586)
					(mid 464.395927 -310.976665)
					(end 464.360006 -310.961786)
				)
				(arc
					(start 462.960466 -310.961786)
					(mid 462.924545 -310.976665)
					(end 462.909666 -311.012586)
				)
			)
		)
	)
	(zone
		(layers "In1.Cu" "In2.Cu")
		(hatch none 0.5)
		(connect_pads
			(clearance 0)
		)
		(min_thickness 0.25)
		(keepout
			(tracks not_allowed)
			(vias allowed)
			(pads allowed)
			(copperpour not_allowed)
			(footprints allowed)
		)
		(placement
			(enabled no)
			(sheetname "")
		)
		(fill yes
			(thermal_gap 0.5)
			(thermal_bridge_width 0.5)
			(island_removal_mode 0)
		)
		(polygon
			(pts
				(arc
					(start 285.505398 -219.621354)
					(mid 285.520277 -219.657275)
					(end 285.556198 -219.672154)
				)
				(arc
					(start 286.955738 -219.672154)
					(mid 286.991659 -219.657275)
					(end 287.006538 -219.621354)
				)
				(arc
					(start 287.006538 -219.212414)
					(mid 286.991659 -219.176493)
					(end 286.955738 -219.161614)
				)
				(arc
					(start 285.556198 -219.161614)
					(mid 285.520277 -219.176493)
					(end 285.505398 -219.212414)
				)
			)
		)
	)
	(zone
		(layers "In1.Cu" "In2.Cu")
		(hatch none 0.5)
		(connect_pads
			(clearance 0)
		)
		(min_thickness 0.25)
		(keepout
			(tracks not_allowed)
			(vias allowed)
			(pads allowed)
			(copperpour not_allowed)
			(footprints allowed)
		)
		(placement
			(enabled no)
			(sheetname "")
		)
		(fill yes
			(thermal_gap 0.5)
			(thermal_bridge_width 0.5)
			(island_removal_mode 0)
		)
		(polygon
			(pts
				(arc
					(start 192.338198 -281.671522)
					(mid 192.353077 -281.707443)
					(end 192.388998 -281.722322)
				)
				(arc
					(start 193.788538 -281.722322)
					(mid 193.824459 -281.707443)
					(end 193.839338 -281.671522)
				)
				(arc
					(start 193.839338 -281.262582)
					(mid 193.824459 -281.226661)
					(end 193.788538 -281.211782)
				)
				(arc
					(start 192.388998 -281.211782)
					(mid 192.353077 -281.226661)
					(end 192.338198 -281.262582)
				)
			)
		)
	)
	(zone
		(layers "In1.Cu" "In2.Cu")
		(hatch none 0.5)
		(connect_pads
			(clearance 0)
		)
		(min_thickness 0.25)
		(keepout
			(tracks not_allowed)
			(vias allowed)
			(pads allowed)
			(copperpour not_allowed)
			(footprints allowed)
		)
		(placement
			(enabled no)
			(sheetname "")
		)
		(fill yes
			(thermal_gap 0.5)
			(thermal_bridge_width 0.5)
			(island_removal_mode 0)
		)
		(polygon
			(pts
				(arc
					(start 297.149266 -211.121498)
					(mid 297.164145 -211.157419)
					(end 297.200066 -211.172298)
				)
				(arc
					(start 298.599606 -211.172298)
					(mid 298.635527 -211.157419)
					(end 298.650406 -211.121498)
				)
				(arc
					(start 298.650406 -210.712558)
					(mid 298.635527 -210.676637)
					(end 298.599606 -210.661758)
				)
				(arc
					(start 297.200066 -210.661758)
					(mid 297.164145 -210.676637)
					(end 297.149266 -210.712558)
				)
			)
		)
	)
	(zone
		(layers "In1.Cu" "In2.Cu")
		(hatch none 0.5)
		(connect_pads
			(clearance 0)
		)
		(min_thickness 0.25)
		(keepout
			(tracks not_allowed)
			(vias allowed)
			(pads allowed)
			(copperpour not_allowed)
			(footprints allowed)
		)
		(placement
			(enabled no)
			(sheetname "")
		)
		(fill yes
			(thermal_gap 0.5)
			(thermal_bridge_width 0.5)
			(island_removal_mode 0)
		)
		(polygon
			(pts
				(arc
					(start 428.634398 -249.371358)
					(mid 428.649277 -249.407279)
					(end 428.685198 -249.422158)
				)
				(arc
					(start 430.084738 -249.422158)
					(mid 430.120659 -249.407279)
					(end 430.135538 -249.371358)
				)
				(arc
					(start 430.135538 -248.962418)
					(mid 430.120659 -248.926497)
					(end 430.084738 -248.911618)
				)
				(arc
					(start 428.685198 -248.911618)
					(mid 428.649277 -248.926497)
					(end 428.634398 -248.962418)
				)
			)
		)
	)
	(zone
		(layers "In1.Cu" "In2.Cu")
		(hatch none 0.5)
		(connect_pads
			(clearance 0)
		)
		(min_thickness 0.25)
		(keepout
			(tracks not_allowed)
			(vias allowed)
			(pads allowed)
			(copperpour not_allowed)
			(footprints allowed)
		)
		(placement
			(enabled no)
			(sheetname "")
		)
		(fill yes
			(thermal_gap 0.5)
			(thermal_bridge_width 0.5)
			(island_removal_mode 0)
		)
		(polygon
			(pts
				(arc
					(start 312.236866 -262.121396)
					(mid 312.251745 -262.157317)
					(end 312.287666 -262.172196)
				)
				(arc
					(start 313.687206 -262.172196)
					(mid 313.723127 -262.157317)
					(end 313.738006 -262.121396)
				)
				(arc
					(start 313.738006 -261.712456)
					(mid 313.723127 -261.676535)
					(end 313.687206 -261.661656)
				)
				(arc
					(start 312.287666 -261.661656)
					(mid 312.251745 -261.676535)
					(end 312.236866 -261.712456)
				)
			)
		)
	)
	(zone
		(layers "In1.Cu" "In2.Cu")
		(hatch none 0.5)
		(connect_pads
			(clearance 0)
		)
		(min_thickness 0.25)
		(keepout
			(tracks not_allowed)
			(vias allowed)
			(pads allowed)
			(copperpour not_allowed)
			(footprints allowed)
		)
		(placement
			(enabled no)
			(sheetname "")
		)
		(fill yes
			(thermal_gap 0.5)
			(thermal_bridge_width 0.5)
			(island_removal_mode 0)
		)
		(polygon
			(pts
				(arc
					(start 210.86953 -223.021398)
					(mid 210.884409 -223.057319)
					(end 210.92033 -223.072198)
				)
				(arc
					(start 212.31987 -223.072198)
					(mid 212.355791 -223.057319)
					(end 212.37067 -223.021398)
				)
				(arc
					(start 212.37067 -222.612458)
					(mid 212.355791 -222.576537)
					(end 212.31987 -222.561658)
				)
				(arc
					(start 210.92033 -222.561658)
					(mid 210.884409 -222.576537)
					(end 210.86953 -222.612458)
				)
			)
		)
	)
	(zone
		(layers "In1.Cu" "In2.Cu")
		(hatch none 0.5)
		(connect_pads
			(clearance 0)
		)
		(min_thickness 0.25)
		(keepout
			(tracks not_allowed)
			(vias allowed)
			(pads allowed)
			(copperpour not_allowed)
			(footprints allowed)
		)
		(placement
			(enabled no)
			(sheetname "")
		)
		(fill yes
			(thermal_gap 0.5)
			(thermal_bridge_width 0.5)
			(island_removal_mode 0)
		)
		(polygon
			(pts
				(arc
					(start 282.061666 -223.871536)
					(mid 282.076545 -223.907457)
					(end 282.112466 -223.922336)
				)
				(arc
					(start 283.512006 -223.922336)
					(mid 283.547927 -223.907457)
					(end 283.562806 -223.871536)
				)
				(arc
					(start 283.562806 -223.462596)
					(mid 283.547927 -223.426675)
					(end 283.512006 -223.411796)
				)
				(arc
					(start 282.112466 -223.411796)
					(mid 282.076545 -223.426675)
					(end 282.061666 -223.462596)
				)
			)
		)
	)
	(zone
		(layers "In1.Cu" "In2.Cu")
		(hatch none 0.5)
		(connect_pads
			(clearance 0)
		)
		(min_thickness 0.25)
		(keepout
			(tracks not_allowed)
			(vias allowed)
			(pads allowed)
			(copperpour not_allowed)
			(footprints allowed)
		)
		(placement
			(enabled no)
			(sheetname "")
		)
		(fill yes
			(thermal_gap 0.5)
			(thermal_bridge_width 0.5)
			(island_removal_mode 0)
		)
		(polygon
			(pts
				(arc
					(start 192.338198 -259.57149)
					(mid 192.353077 -259.607411)
					(end 192.388998 -259.62229)
				)
				(arc
					(start 193.788538 -259.62229)
					(mid 193.824459 -259.607411)
					(end 193.839338 -259.57149)
				)
				(arc
					(start 193.839338 -259.16255)
					(mid 193.824459 -259.126629)
					(end 193.788538 -259.11175)
				)
				(arc
					(start 192.388998 -259.11175)
					(mid 192.353077 -259.126629)
					(end 192.338198 -259.16255)
				)
			)
		)
	)
	(zone
		(layers "In1.Cu" "In2.Cu")
		(hatch none 0.5)
		(connect_pads
			(clearance 0)
		)
		(min_thickness 0.25)
		(keepout
			(tracks not_allowed)
			(vias allowed)
			(pads allowed)
			(copperpour not_allowed)
			(footprints allowed)
		)
		(placement
			(enabled no)
			(sheetname "")
		)
		(fill yes
			(thermal_gap 0.5)
			(thermal_bridge_width 0.5)
			(island_removal_mode 0)
		)
		(polygon
			(pts
				(arc
					(start 60.19673 -247.671336)
					(mid 60.211609 -247.707257)
					(end 60.24753 -247.722136)
				)
				(arc
					(start 61.64707 -247.722136)
					(mid 61.682991 -247.707257)
					(end 61.69787 -247.671336)
				)
				(arc
					(start 61.69787 -247.262396)
					(mid 61.682991 -247.226475)
					(end 61.64707 -247.211596)
				)
				(arc
					(start 60.24753 -247.211596)
					(mid 60.211609 -247.226475)
					(end 60.19673 -247.262396)
				)
			)
		)
	)
	(zone
		(layers "In1.Cu" "In2.Cu")
		(hatch none 0.5)
		(connect_pads
			(clearance 0)
		)
		(min_thickness 0.25)
		(keepout
			(tracks not_allowed)
			(vias allowed)
			(pads allowed)
			(copperpour not_allowed)
			(footprints allowed)
		)
		(placement
			(enabled no)
			(sheetname "")
		)
		(fill yes
			(thermal_gap 0.5)
			(thermal_bridge_width 0.5)
			(island_removal_mode 0)
		)
		(polygon
			(pts
				(arc
					(start 425.190666 -209.421476)
					(mid 425.205545 -209.457397)
					(end 425.241466 -209.472276)
				)
				(arc
					(start 426.641006 -209.472276)
					(mid 426.676927 -209.457397)
					(end 426.691806 -209.421476)
				)
				(arc
					(start 426.691806 -209.012536)
					(mid 426.676927 -208.976615)
					(end 426.641006 -208.961736)
				)
				(arc
					(start 425.241466 -208.961736)
					(mid 425.205545 -208.976615)
					(end 425.190666 -209.012536)
				)
			)
		)
	)
	(zone
		(layers "In1.Cu" "In2.Cu")
		(hatch none 0.5)
		(connect_pads
			(clearance 0)
		)
		(min_thickness 0.25)
		(keepout
			(tracks not_allowed)
			(vias allowed)
			(pads allowed)
			(copperpour not_allowed)
			(footprints allowed)
		)
		(placement
			(enabled no)
			(sheetname "")
		)
		(fill yes
			(thermal_gap 0.5)
			(thermal_bridge_width 0.5)
			(island_removal_mode 0)
		)
		(polygon
			(pts
				(arc
					(start 410.103066 -240.871502)
					(mid 410.117945 -240.907423)
					(end 410.153866 -240.922302)
				)
				(arc
					(start 411.553406 -240.922302)
					(mid 411.589327 -240.907423)
					(end 411.604206 -240.871502)
				)
				(arc
					(start 411.604206 -240.462562)
					(mid 411.589327 -240.426641)
					(end 411.553406 -240.411762)
				)
				(arc
					(start 410.153866 -240.411762)
					(mid 410.117945 -240.426641)
					(end 410.103066 -240.462562)
				)
			)
		)
	)
	(zone
		(layers "In1.Cu" "In2.Cu")
		(hatch none 0.5)
		(connect_pads
			(clearance 0)
		)
		(min_thickness 0.25)
		(keepout
			(tracks not_allowed)
			(vias allowed)
			(pads allowed)
			(copperpour not_allowed)
			(footprints allowed)
		)
		(placement
			(enabled no)
			(sheetname "")
		)
		(fill yes
			(thermal_gap 0.5)
			(thermal_bridge_width 0.5)
			(island_removal_mode 0)
		)
		(polygon
			(pts
				(arc
					(start 285.505398 -210.27136)
					(mid 285.520277 -210.307281)
					(end 285.556198 -210.32216)
				)
				(arc
					(start 286.955738 -210.32216)
					(mid 286.991659 -210.307281)
					(end 287.006538 -210.27136)
				)
				(arc
					(start 287.006538 -209.86242)
					(mid 286.991659 -209.826499)
					(end 286.955738 -209.81162)
				)
				(arc
					(start 285.556198 -209.81162)
					(mid 285.520277 -209.826499)
					(end 285.505398 -209.86242)
				)
			)
		)
	)
	(zone
		(layers "In1.Cu" "In2.Cu")
		(hatch none 0.5)
		(connect_pads
			(clearance 0)
		)
		(min_thickness 0.25)
		(keepout
			(tracks not_allowed)
			(vias allowed)
			(pads allowed)
			(copperpour not_allowed)
			(footprints allowed)
		)
		(placement
			(enabled no)
			(sheetname "")
		)
		(fill yes
			(thermal_gap 0.5)
			(thermal_bridge_width 0.5)
			(island_removal_mode 0)
		)
		(polygon
			(pts
				(arc
					(start 30.02153 -303.7713)
					(mid 30.036409 -303.807221)
					(end 30.07233 -303.8221)
				)
				(arc
					(start 31.47187 -303.8221)
					(mid 31.507791 -303.807221)
					(end 31.52267 -303.7713)
				)
				(arc
					(start 31.52267 -303.36236)
					(mid 31.507791 -303.326439)
					(end 31.47187 -303.31156)
				)
				(arc
					(start 30.07233 -303.31156)
					(mid 30.036409 -303.326439)
					(end 30.02153 -303.36236)
				)
			)
		)
	)
	(zone
		(layers "In1.Cu" "In2.Cu")
		(hatch none 0.5)
		(connect_pads
			(clearance 0)
		)
		(min_thickness 0.25)
		(keepout
			(tracks not_allowed)
			(vias allowed)
			(pads allowed)
			(copperpour not_allowed)
			(footprints allowed)
		)
		(placement
			(enabled no)
			(sheetname "")
		)
		(fill yes
			(thermal_gap 0.5)
			(thermal_bridge_width 0.5)
			(island_removal_mode 0)
		)
		(polygon
			(pts
				(arc
					(start 56.752998 -259.57149)
					(mid 56.767877 -259.607411)
					(end 56.803798 -259.62229)
				)
				(arc
					(start 58.203338 -259.62229)
					(mid 58.239259 -259.607411)
					(end 58.254138 -259.57149)
				)
				(arc
					(start 58.254138 -259.16255)
					(mid 58.239259 -259.126629)
					(end 58.203338 -259.11175)
				)
				(arc
					(start 56.803798 -259.11175)
					(mid 56.767877 -259.126629)
					(end 56.752998 -259.16255)
				)
			)
		)
	)
	(zone
		(layers "In1.Cu" "In2.Cu")
		(hatch none 0.5)
		(connect_pads
			(clearance 0)
		)
		(min_thickness 0.25)
		(keepout
			(tracks not_allowed)
			(vias allowed)
			(pads allowed)
			(copperpour not_allowed)
			(footprints allowed)
		)
		(placement
			(enabled no)
			(sheetname "")
		)
		(fill yes
			(thermal_gap 0.5)
			(thermal_bridge_width 0.5)
			(island_removal_mode 0)
		)
		(polygon
			(pts
				(arc
					(start 421.090598 -312.27141)
					(mid 421.105477 -312.307331)
					(end 421.141398 -312.32221)
				)
				(arc
					(start 422.540938 -312.32221)
					(mid 422.576859 -312.307331)
					(end 422.591738 -312.27141)
				)
				(arc
					(start 422.591738 -311.86247)
					(mid 422.576859 -311.826549)
					(end 422.540938 -311.81167)
				)
				(arc
					(start 421.141398 -311.81167)
					(mid 421.105477 -311.826549)
					(end 421.090598 -311.86247)
				)
			)
		)
	)
	(zone
		(layers "In1.Cu" "In2.Cu")
		(hatch none 0.5)
		(connect_pads
			(clearance 0)
		)
		(min_thickness 0.25)
		(keepout
			(tracks not_allowed)
			(vias allowed)
			(pads allowed)
			(copperpour not_allowed)
			(footprints allowed)
		)
		(placement
			(enabled no)
			(sheetname "")
		)
		(fill yes
			(thermal_gap 0.5)
			(thermal_bridge_width 0.5)
			(island_removal_mode 0)
		)
		(polygon
			(pts
				(arc
					(start 266.974066 -200.071482)
					(mid 266.988945 -200.107403)
					(end 267.024866 -200.122282)
				)
				(arc
					(start 268.424406 -200.122282)
					(mid 268.460327 -200.107403)
					(end 268.475206 -200.071482)
				)
				(arc
					(start 268.475206 -199.662542)
					(mid 268.460327 -199.626621)
					(end 268.424406 -199.611742)
				)
				(arc
					(start 267.024866 -199.611742)
					(mid 266.988945 -199.626621)
					(end 266.974066 -199.662542)
				)
			)
		)
	)
	(zone
		(layers "In1.Cu" "In2.Cu")
		(hatch none 0.5)
		(connect_pads
			(clearance 0)
		)
		(min_thickness 0.25)
		(keepout
			(tracks not_allowed)
			(vias allowed)
			(pads allowed)
			(copperpour not_allowed)
			(footprints allowed)
		)
		(placement
			(enabled no)
			(sheetname "")
		)
		(fill yes
			(thermal_gap 0.5)
			(thermal_bridge_width 0.5)
			(island_removal_mode 0)
		)
		(polygon
			(pts
				(arc
					(start 440.278266 -274.02155)
					(mid 440.293145 -274.057471)
					(end 440.329066 -274.07235)
				)
				(arc
					(start 441.728606 -274.07235)
					(mid 441.764527 -274.057471)
					(end 441.779406 -274.02155)
				)
				(arc
					(start 441.779406 -273.61261)
					(mid 441.764527 -273.576689)
					(end 441.728606 -273.56181)
				)
				(arc
					(start 440.329066 -273.56181)
					(mid 440.293145 -273.576689)
					(end 440.278266 -273.61261)
				)
			)
		)
	)
	(zone
		(layers "In1.Cu" "In2.Cu")
		(hatch none 0.5)
		(connect_pads
			(clearance 0)
		)
		(min_thickness 0.25)
		(keepout
			(tracks not_allowed)
			(vias allowed)
			(pads allowed)
			(copperpour not_allowed)
			(footprints allowed)
		)
		(placement
			(enabled no)
			(sheetname "")
		)
		(fill yes
			(thermal_gap 0.5)
			(thermal_bridge_width 0.5)
			(island_removal_mode 0)
		)
		(polygon
			(pts
				(arc
					(start 52.65293 -274.871434)
					(mid 52.667809 -274.907355)
					(end 52.70373 -274.922234)
				)
				(arc
					(start 54.10327 -274.922234)
					(mid 54.139191 -274.907355)
					(end 54.15407 -274.871434)
				)
				(arc
					(start 54.15407 -274.462494)
					(mid 54.139191 -274.426573)
					(end 54.10327 -274.411694)
				)
				(arc
					(start 52.70373 -274.411694)
					(mid 52.667809 -274.426573)
					(end 52.65293 -274.462494)
				)
			)
		)
	)
	(zone
		(layers "In1.Cu" "In2.Cu")
		(hatch none 0.5)
		(connect_pads
			(clearance 0)
		)
		(min_thickness 0.25)
		(keepout
			(tracks not_allowed)
			(vias allowed)
			(pads allowed)
			(copperpour not_allowed)
			(footprints allowed)
		)
		(placement
			(enabled no)
			(sheetname "")
		)
		(fill yes
			(thermal_gap 0.5)
			(thermal_bridge_width 0.5)
			(island_removal_mode 0)
		)
		(polygon
			(pts
				(arc
					(start 266.974066 -248.521474)
					(mid 266.988945 -248.557395)
					(end 267.024866 -248.572274)
				)
				(arc
					(start 268.424406 -248.572274)
					(mid 268.460327 -248.557395)
					(end 268.475206 -248.521474)
				)
				(arc
					(start 268.475206 -248.112534)
					(mid 268.460327 -248.076613)
					(end 268.424406 -248.061734)
				)
				(arc
					(start 267.024866 -248.061734)
					(mid 266.988945 -248.076613)
					(end 266.974066 -248.112534)
				)
			)
		)
	)
	(zone
		(layers "In1.Cu" "In2.Cu")
		(hatch none 0.5)
		(connect_pads
			(clearance 0)
		)
		(min_thickness 0.25)
		(keepout
			(tracks not_allowed)
			(vias allowed)
			(pads allowed)
			(copperpour not_allowed)
			(footprints allowed)
		)
		(placement
			(enabled no)
			(sheetname "")
		)
		(fill yes
			(thermal_gap 0.5)
			(thermal_bridge_width 0.5)
			(island_removal_mode 0)
		)
		(polygon
			(pts
				(arc
					(start 440.278266 -218.77147)
					(mid 440.293145 -218.807391)
					(end 440.329066 -218.82227)
				)
				(arc
					(start 441.728606 -218.82227)
					(mid 441.764527 -218.807391)
					(end 441.779406 -218.77147)
				)
				(arc
					(start 441.779406 -218.36253)
					(mid 441.764527 -218.326609)
					(end 441.728606 -218.31173)
				)
				(arc
					(start 440.329066 -218.31173)
					(mid 440.293145 -218.326609)
					(end 440.278266 -218.36253)
				)
			)
		)
	)
	(zone
		(layers "In1.Cu" "In2.Cu")
		(hatch none 0.5)
		(connect_pads
			(clearance 0)
		)
		(min_thickness 0.25)
		(keepout
			(tracks not_allowed)
			(vias allowed)
			(pads allowed)
			(copperpour not_allowed)
			(footprints allowed)
		)
		(placement
			(enabled no)
			(sheetname "")
		)
		(fill yes
			(thermal_gap 0.5)
			(thermal_bridge_width 0.5)
			(island_removal_mode 0)
		)
		(polygon
			(pts
				(arc
					(start 308.136798 -223.021398)
					(mid 308.151677 -223.057319)
					(end 308.187598 -223.072198)
				)
				(arc
					(start 309.587138 -223.072198)
					(mid 309.623059 -223.057319)
					(end 309.637938 -223.021398)
				)
				(arc
					(start 309.637938 -222.612458)
					(mid 309.623059 -222.576537)
					(end 309.587138 -222.561658)
				)
				(arc
					(start 308.187598 -222.561658)
					(mid 308.151677 -222.576537)
					(end 308.136798 -222.612458)
				)
			)
		)
	)
	(zone
		(layers "In1.Cu" "In2.Cu")
		(hatch none 0.5)
		(connect_pads
			(clearance 0)
		)
		(min_thickness 0.25)
		(keepout
			(tracks not_allowed)
			(vias allowed)
			(pads allowed)
			(copperpour not_allowed)
			(footprints allowed)
		)
		(placement
			(enabled no)
			(sheetname "")
		)
		(fill yes
			(thermal_gap 0.5)
			(thermal_bridge_width 0.5)
			(island_removal_mode 0)
		)
		(polygon
			(pts
				(arc
					(start 274.517866 -262.121396)
					(mid 274.532745 -262.157317)
					(end 274.568666 -262.172196)
				)
				(arc
					(start 275.968206 -262.172196)
					(mid 276.004127 -262.157317)
					(end 276.019006 -262.121396)
				)
				(arc
					(start 276.019006 -261.712456)
					(mid 276.004127 -261.676535)
					(end 275.968206 -261.661656)
				)
				(arc
					(start 274.568666 -261.661656)
					(mid 274.532745 -261.676535)
					(end 274.517866 -261.712456)
				)
			)
		)
	)
	(zone
		(layers "In1.Cu" "In2.Cu")
		(hatch none 0.5)
		(connect_pads
			(clearance 0)
		)
		(min_thickness 0.25)
		(keepout
			(tracks not_allowed)
			(vias allowed)
			(pads allowed)
			(copperpour not_allowed)
			(footprints allowed)
		)
		(placement
			(enabled no)
			(sheetname "")
		)
		(fill yes
			(thermal_gap 0.5)
			(thermal_bridge_width 0.5)
			(island_removal_mode 0)
		)
		(polygon
			(pts
				(arc
					(start 37.56533 -249.371358)
					(mid 37.580209 -249.407279)
					(end 37.61613 -249.422158)
				)
				(arc
					(start 39.01567 -249.422158)
					(mid 39.051591 -249.407279)
					(end 39.06647 -249.371358)
				)
				(arc
					(start 39.06647 -248.962418)
					(mid 39.051591 -248.926497)
					(end 39.01567 -248.911618)
				)
				(arc
					(start 37.61613 -248.911618)
					(mid 37.580209 -248.926497)
					(end 37.56533 -248.962418)
				)
			)
		)
	)
	(zone
		(layers "In1.Cu" "In2.Cu")
		(hatch none 0.5)
		(connect_pads
			(clearance 0)
		)
		(min_thickness 0.25)
		(keepout
			(tracks not_allowed)
			(vias allowed)
			(pads allowed)
			(copperpour not_allowed)
			(footprints allowed)
		)
		(placement
			(enabled no)
			(sheetname "")
		)
		(fill yes
			(thermal_gap 0.5)
			(thermal_bridge_width 0.5)
			(island_removal_mode 0)
		)
		(polygon
			(pts
				(arc
					(start 440.278266 -203.471526)
					(mid 440.293145 -203.507447)
					(end 440.329066 -203.522326)
				)
				(arc
					(start 441.728606 -203.522326)
					(mid 441.764527 -203.507447)
					(end 441.779406 -203.471526)
				)
				(arc
					(start 441.779406 -203.062586)
					(mid 441.764527 -203.026665)
					(end 441.728606 -203.011786)
				)
				(arc
					(start 440.329066 -203.011786)
					(mid 440.293145 -203.026665)
					(end 440.278266 -203.062586)
				)
			)
		)
	)
	(zone
		(layers "In1.Cu" "In2.Cu")
		(hatch none 0.5)
		(connect_pads
			(clearance 0)
		)
		(min_thickness 0.25)
		(keepout
			(tracks not_allowed)
			(vias allowed)
			(pads allowed)
			(copperpour not_allowed)
			(footprints allowed)
		)
		(placement
			(enabled no)
			(sheetname "")
		)
		(fill yes
			(thermal_gap 0.5)
			(thermal_bridge_width 0.5)
			(island_removal_mode 0)
		)
		(polygon
			(pts
				(arc
					(start 30.02153 -244.271292)
					(mid 30.036409 -244.307213)
					(end 30.07233 -244.322092)
				)
				(arc
					(start 31.47187 -244.322092)
					(mid 31.507791 -244.307213)
					(end 31.52267 -244.271292)
				)
				(arc
					(start 31.52267 -243.862352)
					(mid 31.507791 -243.826431)
					(end 31.47187 -243.811552)
				)
				(arc
					(start 30.07233 -243.811552)
					(mid 30.036409 -243.826431)
					(end 30.02153 -243.862352)
				)
			)
		)
	)
	(zone
		(layers "In1.Cu" "In2.Cu")
		(hatch none 0.5)
		(connect_pads
			(clearance 0)
		)
		(min_thickness 0.25)
		(keepout
			(tracks not_allowed)
			(vias allowed)
			(pads allowed)
			(copperpour not_allowed)
			(footprints allowed)
		)
		(placement
			(enabled no)
			(sheetname "")
		)
		(fill yes
			(thermal_gap 0.5)
			(thermal_bridge_width 0.5)
			(island_removal_mode 0)
		)
		(polygon
			(pts
				(arc
					(start 210.86953 -294.421306)
					(mid 210.884409 -294.457227)
					(end 210.92033 -294.472106)
				)
				(arc
					(start 212.31987 -294.472106)
					(mid 212.355791 -294.457227)
					(end 212.37067 -294.421306)
				)
				(arc
					(start 212.37067 -294.012366)
					(mid 212.355791 -293.976445)
					(end 212.31987 -293.961566)
				)
				(arc
					(start 210.92033 -293.961566)
					(mid 210.884409 -293.976445)
					(end 210.86953 -294.012366)
				)
			)
		)
	)
	(zone
		(layers "In1.Cu" "In2.Cu")
		(hatch none 0.5)
		(connect_pads
			(clearance 0)
		)
		(min_thickness 0.25)
		(keepout
			(tracks not_allowed)
			(vias allowed)
			(pads allowed)
			(copperpour not_allowed)
			(footprints allowed)
		)
		(placement
			(enabled no)
			(sheetname "")
		)
		(fill yes
			(thermal_gap 0.5)
			(thermal_bridge_width 0.5)
			(island_removal_mode 0)
		)
		(polygon
			(pts
				(arc
					(start 443.721998 -302.921416)
					(mid 443.736877 -302.957337)
					(end 443.772798 -302.972216)
				)
				(arc
					(start 445.172338 -302.972216)
					(mid 445.208259 -302.957337)
					(end 445.223138 -302.921416)
				)
				(arc
					(start 445.223138 -302.512476)
					(mid 445.208259 -302.476555)
					(end 445.172338 -302.461676)
				)
				(arc
					(start 443.772798 -302.461676)
					(mid 443.736877 -302.476555)
					(end 443.721998 -302.512476)
				)
			)
		)
	)
	(zone
		(layers "In1.Cu" "In2.Cu")
		(hatch none 0.5)
		(connect_pads
			(clearance 0)
		)
		(min_thickness 0.25)
		(keepout
			(tracks not_allowed)
			(vias allowed)
			(pads allowed)
			(copperpour not_allowed)
			(footprints allowed)
		)
		(placement
			(enabled no)
			(sheetname "")
		)
		(fill yes
			(thermal_gap 0.5)
			(thermal_bridge_width 0.5)
			(island_removal_mode 0)
		)
		(polygon
			(pts
				(arc
					(start 56.752998 -201.771504)
					(mid 56.767877 -201.807425)
					(end 56.803798 -201.822304)
				)
				(arc
					(start 58.203338 -201.822304)
					(mid 58.239259 -201.807425)
					(end 58.254138 -201.771504)
				)
				(arc
					(start 58.254138 -201.362564)
					(mid 58.239259 -201.326643)
					(end 58.203338 -201.311764)
				)
				(arc
					(start 56.803798 -201.311764)
					(mid 56.767877 -201.326643)
					(end 56.752998 -201.362564)
				)
			)
		)
	)
	(zone
		(layers "In1.Cu" "In2.Cu")
		(hatch none 0.5)
		(connect_pads
			(clearance 0)
		)
		(min_thickness 0.25)
		(keepout
			(tracks not_allowed)
			(vias allowed)
			(pads allowed)
			(copperpour not_allowed)
			(footprints allowed)
		)
		(placement
			(enabled no)
			(sheetname "")
		)
		(fill yes
			(thermal_gap 0.5)
			(thermal_bridge_width 0.5)
			(island_removal_mode 0)
		)
		(polygon
			(pts
				(arc
					(start 274.517866 -315.671454)
					(mid 274.532745 -315.707375)
					(end 274.568666 -315.722254)
				)
				(arc
					(start 275.968206 -315.722254)
					(mid 276.004127 -315.707375)
					(end 276.019006 -315.671454)
				)
				(arc
					(start 276.019006 -315.262514)
					(mid 276.004127 -315.226593)
					(end 275.968206 -315.211714)
				)
				(arc
					(start 274.568666 -315.211714)
					(mid 274.532745 -315.226593)
					(end 274.517866 -315.262514)
				)
			)
		)
	)
	(zone
		(layers "In1.Cu" "In2.Cu")
		(hatch none 0.5)
		(connect_pads
			(clearance 0)
		)
		(min_thickness 0.25)
		(keepout
			(tracks not_allowed)
			(vias allowed)
			(pads allowed)
			(copperpour not_allowed)
			(footprints allowed)
		)
		(placement
			(enabled no)
			(sheetname "")
		)
		(fill yes
			(thermal_gap 0.5)
			(thermal_bridge_width 0.5)
			(island_removal_mode 0)
		)
		(polygon
			(pts
				(arc
					(start 22.47773 -291.8714)
					(mid 22.492609 -291.907321)
					(end 22.52853 -291.9222)
				)
				(arc
					(start 23.92807 -291.9222)
					(mid 23.963991 -291.907321)
					(end 23.97887 -291.8714)
				)
				(arc
					(start 23.97887 -291.46246)
					(mid 23.963991 -291.426539)
					(end 23.92807 -291.41166)
				)
				(arc
					(start 22.52853 -291.41166)
					(mid 22.492609 -291.426539)
					(end 22.47773 -291.46246)
				)
			)
		)
	)
	(zone
		(layers "In1.Cu" "In2.Cu")
		(hatch none 0.5)
		(connect_pads
			(clearance 0)
		)
		(min_thickness 0.25)
		(keepout
			(tracks not_allowed)
			(vias allowed)
			(pads allowed)
			(copperpour not_allowed)
			(footprints allowed)
		)
		(placement
			(enabled no)
			(sheetname "")
		)
		(fill yes
			(thermal_gap 0.5)
			(thermal_bridge_width 0.5)
			(island_removal_mode 0)
		)
		(polygon
			(pts
				(arc
					(start 177.250598 -227.271326)
					(mid 177.265477 -227.307247)
					(end 177.301398 -227.322126)
				)
				(arc
					(start 178.700938 -227.322126)
					(mid 178.736859 -227.307247)
					(end 178.751738 -227.271326)
				)
				(arc
					(start 178.751738 -226.862386)
					(mid 178.736859 -226.826465)
					(end 178.700938 -226.811586)
				)
				(arc
					(start 177.301398 -226.811586)
					(mid 177.265477 -226.826465)
					(end 177.250598 -226.862386)
				)
			)
		)
	)
	(zone
		(layers "In1.Cu" "In2.Cu")
		(hatch none 0.5)
		(connect_pads
			(clearance 0)
		)
		(min_thickness 0.25)
		(keepout
			(tracks not_allowed)
			(vias allowed)
			(pads allowed)
			(copperpour not_allowed)
			(footprints allowed)
		)
		(placement
			(enabled no)
			(sheetname "")
		)
		(fill yes
			(thermal_gap 0.5)
			(thermal_bridge_width 0.5)
			(island_removal_mode 0)
		)
		(polygon
			(pts
				(arc
					(start 173.15053 -268.071346)
					(mid 173.165409 -268.107267)
					(end 173.20133 -268.122146)
				)
				(arc
					(start 174.60087 -268.122146)
					(mid 174.636791 -268.107267)
					(end 174.65167 -268.071346)
				)
				(arc
					(start 174.65167 -267.662406)
					(mid 174.636791 -267.626485)
					(end 174.60087 -267.611606)
				)
				(arc
					(start 173.20133 -267.611606)
					(mid 173.165409 -267.626485)
					(end 173.15053 -267.662406)
				)
			)
		)
	)
	(zone
		(layers "In1.Cu" "In2.Cu")
		(hatch none 0.5)
		(connect_pads
			(clearance 0)
		)
		(min_thickness 0.25)
		(keepout
			(tracks not_allowed)
			(vias allowed)
			(pads allowed)
			(copperpour not_allowed)
			(footprints allowed)
		)
		(placement
			(enabled no)
			(sheetname "")
		)
		(fill yes
			(thermal_gap 0.5)
			(thermal_bridge_width 0.5)
			(island_removal_mode 0)
		)
		(polygon
			(pts
				(arc
					(start 451.265798 -196.671438)
					(mid 451.280677 -196.707359)
					(end 451.316598 -196.722238)
				)
				(arc
					(start 452.716138 -196.722238)
					(mid 452.752059 -196.707359)
					(end 452.766938 -196.671438)
				)
				(arc
					(start 452.766938 -196.262498)
					(mid 452.752059 -196.226577)
					(end 452.716138 -196.211698)
				)
				(arc
					(start 451.316598 -196.211698)
					(mid 451.280677 -196.226577)
					(end 451.265798 -196.262498)
				)
			)
		)
	)
	(zone
		(layers "In1.Cu" "In2.Cu")
		(hatch none 0.5)
		(connect_pads
			(clearance 0)
		)
		(min_thickness 0.25)
		(keepout
			(tracks not_allowed)
			(vias allowed)
			(pads allowed)
			(copperpour not_allowed)
			(footprints allowed)
		)
		(placement
			(enabled no)
			(sheetname "")
		)
		(fill yes
			(thermal_gap 0.5)
			(thermal_bridge_width 0.5)
			(island_removal_mode 0)
		)
		(polygon
			(pts
				(arc
					(start 165.60673 -245.971314)
					(mid 165.621609 -246.007235)
					(end 165.65753 -246.022114)
				)
				(arc
					(start 167.05707 -246.022114)
					(mid 167.092991 -246.007235)
					(end 167.10787 -245.971314)
				)
				(arc
					(start 167.10787 -245.562374)
					(mid 167.092991 -245.526453)
					(end 167.05707 -245.511574)
				)
				(arc
					(start 165.65753 -245.511574)
					(mid 165.621609 -245.526453)
					(end 165.60673 -245.562374)
				)
			)
		)
	)
	(zone
		(layers "In1.Cu" "In2.Cu")
		(hatch none 0.5)
		(connect_pads
			(clearance 0)
		)
		(min_thickness 0.25)
		(keepout
			(tracks not_allowed)
			(vias allowed)
			(pads allowed)
			(copperpour not_allowed)
			(footprints allowed)
		)
		(placement
			(enabled no)
			(sheetname "")
		)
		(fill yes
			(thermal_gap 0.5)
			(thermal_bridge_width 0.5)
			(island_removal_mode 0)
		)
		(polygon
			(pts
				(arc
					(start 169.706798 -260.421374)
					(mid 169.721677 -260.457295)
					(end 169.757598 -260.472174)
				)
				(arc
					(start 171.157138 -260.472174)
					(mid 171.193059 -260.457295)
					(end 171.207938 -260.421374)
				)
				(arc
					(start 171.207938 -260.012434)
					(mid 171.193059 -259.976513)
					(end 171.157138 -259.961634)
				)
				(arc
					(start 169.757598 -259.961634)
					(mid 169.721677 -259.976513)
					(end 169.706798 -260.012434)
				)
			)
		)
	)
	(zone
		(layers "In1.Cu" "In2.Cu")
		(hatch none 0.5)
		(connect_pads
			(clearance 0)
		)
		(min_thickness 0.25)
		(keepout
			(tracks not_allowed)
			(vias allowed)
			(pads allowed)
			(copperpour not_allowed)
			(footprints allowed)
		)
		(placement
			(enabled no)
			(sheetname "")
		)
		(fill yes
			(thermal_gap 0.5)
			(thermal_bridge_width 0.5)
			(island_removal_mode 0)
		)
		(polygon
			(pts
				(arc
					(start 282.061666 -262.121396)
					(mid 282.076545 -262.157317)
					(end 282.112466 -262.172196)
				)
				(arc
					(start 283.512006 -262.172196)
					(mid 283.547927 -262.157317)
					(end 283.562806 -262.121396)
				)
				(arc
					(start 283.562806 -261.712456)
					(mid 283.547927 -261.676535)
					(end 283.512006 -261.661656)
				)
				(arc
					(start 282.112466 -261.661656)
					(mid 282.076545 -261.676535)
					(end 282.061666 -261.712456)
				)
			)
		)
	)
	(zone
		(layers "In1.Cu" "In2.Cu")
		(hatch none 0.5)
		(connect_pads
			(clearance 0)
		)
		(min_thickness 0.25)
		(keepout
			(tracks not_allowed)
			(vias allowed)
			(pads allowed)
			(copperpour not_allowed)
			(footprints allowed)
		)
		(placement
			(enabled no)
			(sheetname "")
		)
		(fill yes
			(thermal_gap 0.5)
			(thermal_bridge_width 0.5)
			(island_removal_mode 0)
		)
		(polygon
			(pts
				(arc
					(start 173.15053 -274.871434)
					(mid 173.165409 -274.907355)
					(end 173.20133 -274.922234)
				)
				(arc
					(start 174.60087 -274.922234)
					(mid 174.636791 -274.907355)
					(end 174.65167 -274.871434)
				)
				(arc
					(start 174.65167 -274.462494)
					(mid 174.636791 -274.426573)
					(end 174.60087 -274.411694)
				)
				(arc
					(start 173.20133 -274.411694)
					(mid 173.165409 -274.426573)
					(end 173.15053 -274.462494)
				)
			)
		)
	)
	(zone
		(layers "In1.Cu" "In2.Cu")
		(hatch none 0.5)
		(connect_pads
			(clearance 0)
		)
		(min_thickness 0.25)
		(keepout
			(tracks not_allowed)
			(vias allowed)
			(pads allowed)
			(copperpour not_allowed)
			(footprints allowed)
		)
		(placement
			(enabled no)
			(sheetname "")
		)
		(fill yes
			(thermal_gap 0.5)
			(thermal_bridge_width 0.5)
			(island_removal_mode 0)
		)
		(polygon
			(pts
				(arc
					(start 455.365866 -246.821452)
					(mid 455.380745 -246.857373)
					(end 455.416666 -246.872252)
				)
				(arc
					(start 456.816206 -246.872252)
					(mid 456.852127 -246.857373)
					(end 456.867006 -246.821452)
				)
				(arc
					(start 456.867006 -246.412512)
					(mid 456.852127 -246.376591)
					(end 456.816206 -246.361712)
				)
				(arc
					(start 455.416666 -246.361712)
					(mid 455.380745 -246.376591)
					(end 455.365866 -246.412512)
				)
			)
		)
	)
	(zone
		(layers "In1.Cu" "In2.Cu")
		(hatch none 0.5)
		(connect_pads
			(clearance 0)
		)
		(min_thickness 0.25)
		(keepout
			(tracks not_allowed)
			(vias allowed)
			(pads allowed)
			(copperpour not_allowed)
			(footprints allowed)
		)
		(placement
			(enabled no)
			(sheetname "")
		)
		(fill yes
			(thermal_gap 0.5)
			(thermal_bridge_width 0.5)
			(island_removal_mode 0)
		)
		(polygon
			(pts
				(arc
					(start 293.049198 -207.721454)
					(mid 293.064077 -207.757375)
					(end 293.099998 -207.772254)
				)
				(arc
					(start 294.499538 -207.772254)
					(mid 294.535459 -207.757375)
					(end 294.550338 -207.721454)
				)
				(arc
					(start 294.550338 -207.312514)
					(mid 294.535459 -207.276593)
					(end 294.499538 -207.261714)
				)
				(arc
					(start 293.099998 -207.261714)
					(mid 293.064077 -207.276593)
					(end 293.049198 -207.312514)
				)
			)
		)
	)
	(zone
		(layers "In1.Cu" "In2.Cu")
		(hatch none 0.5)
		(connect_pads
			(clearance 0)
		)
		(min_thickness 0.25)
		(keepout
			(tracks not_allowed)
			(vias allowed)
			(pads allowed)
			(copperpour not_allowed)
			(footprints allowed)
		)
		(placement
			(enabled no)
			(sheetname "")
		)
		(fill yes
			(thermal_gap 0.5)
			(thermal_bridge_width 0.5)
			(island_removal_mode 0)
		)
		(polygon
			(pts
				(arc
					(start 462.909666 -276.571456)
					(mid 462.924545 -276.607377)
					(end 462.960466 -276.622256)
				)
				(arc
					(start 464.360006 -276.622256)
					(mid 464.395927 -276.607377)
					(end 464.410806 -276.571456)
				)
				(arc
					(start 464.410806 -276.162516)
					(mid 464.395927 -276.126595)
					(end 464.360006 -276.111716)
				)
				(arc
					(start 462.960466 -276.111716)
					(mid 462.924545 -276.126595)
					(end 462.909666 -276.162516)
				)
			)
		)
	)
	(zone
		(layers "In1.Cu" "In2.Cu")
		(hatch none 0.5)
		(connect_pads
			(clearance 0)
		)
		(min_thickness 0.25)
		(keepout
			(tracks not_allowed)
			(vias allowed)
			(pads allowed)
			(copperpour not_allowed)
			(footprints allowed)
		)
		(placement
			(enabled no)
			(sheetname "")
		)
		(fill yes
			(thermal_gap 0.5)
			(thermal_bridge_width 0.5)
			(island_removal_mode 0)
		)
		(polygon
			(pts
				(arc
					(start 34.121598 -279.9715)
					(mid 34.136477 -280.007421)
					(end 34.172398 -280.0223)
				)
				(arc
					(start 35.571938 -280.0223)
					(mid 35.607859 -280.007421)
					(end 35.622738 -279.9715)
				)
				(arc
					(start 35.622738 -279.56256)
					(mid 35.607859 -279.526639)
					(end 35.571938 -279.51176)
				)
				(arc
					(start 34.172398 -279.51176)
					(mid 34.136477 -279.526639)
					(end 34.121598 -279.56256)
				)
			)
		)
	)
	(zone
		(layers "In1.Cu" "In2.Cu")
		(hatch none 0.5)
		(connect_pads
			(clearance 0)
		)
		(min_thickness 0.25)
		(keepout
			(tracks not_allowed)
			(vias allowed)
			(pads allowed)
			(copperpour not_allowed)
			(footprints allowed)
		)
		(placement
			(enabled no)
			(sheetname "")
		)
		(fill yes
			(thermal_gap 0.5)
			(thermal_bridge_width 0.5)
			(island_removal_mode 0)
		)
		(polygon
			(pts
				(arc
					(start 169.706798 -308.021482)
					(mid 169.721677 -308.057403)
					(end 169.757598 -308.072282)
				)
				(arc
					(start 171.157138 -308.072282)
					(mid 171.193059 -308.057403)
					(end 171.207938 -308.021482)
				)
				(arc
					(start 171.207938 -307.612542)
					(mid 171.193059 -307.576621)
					(end 171.157138 -307.561742)
				)
				(arc
					(start 169.757598 -307.561742)
					(mid 169.721677 -307.576621)
					(end 169.706798 -307.612542)
				)
			)
		)
	)
	(zone
		(layers "In1.Cu" "In2.Cu")
		(hatch none 0.5)
		(connect_pads
			(clearance 0)
		)
		(min_thickness 0.25)
		(keepout
			(tracks not_allowed)
			(vias allowed)
			(pads allowed)
			(copperpour not_allowed)
			(footprints allowed)
		)
		(placement
			(enabled no)
			(sheetname "")
		)
		(fill yes
			(thermal_gap 0.5)
			(thermal_bridge_width 0.5)
			(island_removal_mode 0)
		)
		(polygon
			(pts
				(arc
					(start 289.605466 -289.321494)
					(mid 289.620345 -289.357415)
					(end 289.656266 -289.372294)
				)
				(arc
					(start 291.055806 -289.372294)
					(mid 291.091727 -289.357415)
					(end 291.106606 -289.321494)
				)
				(arc
					(start 291.106606 -288.912554)
					(mid 291.091727 -288.876633)
					(end 291.055806 -288.861754)
				)
				(arc
					(start 289.656266 -288.861754)
					(mid 289.620345 -288.876633)
					(end 289.605466 -288.912554)
				)
			)
		)
	)
	(zone
		(layers "In1.Cu" "In2.Cu")
		(hatch none 0.5)
		(connect_pads
			(clearance 0)
		)
		(min_thickness 0.25)
		(keepout
			(tracks not_allowed)
			(vias allowed)
			(pads allowed)
			(copperpour not_allowed)
			(footprints allowed)
		)
		(placement
			(enabled no)
			(sheetname "")
		)
		(fill yes
			(thermal_gap 0.5)
			(thermal_bridge_width 0.5)
			(island_removal_mode 0)
		)
		(polygon
			(pts
				(arc
					(start 37.56533 -206.021432)
					(mid 37.580209 -206.057353)
					(end 37.61613 -206.072232)
				)
				(arc
					(start 39.01567 -206.072232)
					(mid 39.051591 -206.057353)
					(end 39.06647 -206.021432)
				)
				(arc
					(start 39.06647 -205.612492)
					(mid 39.051591 -205.576571)
					(end 39.01567 -205.561692)
				)
				(arc
					(start 37.61613 -205.561692)
					(mid 37.580209 -205.576571)
					(end 37.56533 -205.612492)
				)
			)
		)
	)
	(zone
		(layers "In1.Cu" "In2.Cu")
		(hatch none 0.5)
		(connect_pads
			(clearance 0)
		)
		(min_thickness 0.25)
		(keepout
			(tracks not_allowed)
			(vias allowed)
			(pads allowed)
			(copperpour not_allowed)
			(footprints allowed)
		)
		(placement
			(enabled no)
			(sheetname "")
		)
		(fill yes
			(thermal_gap 0.5)
			(thermal_bridge_width 0.5)
			(island_removal_mode 0)
		)
		(polygon
			(pts
				(arc
					(start 425.190666 -287.621472)
					(mid 425.205545 -287.657393)
					(end 425.241466 -287.672272)
				)
				(arc
					(start 426.641006 -287.672272)
					(mid 426.676927 -287.657393)
					(end 426.691806 -287.621472)
				)
				(arc
					(start 426.691806 -287.212532)
					(mid 426.676927 -287.176611)
					(end 426.641006 -287.161732)
				)
				(arc
					(start 425.241466 -287.161732)
					(mid 425.205545 -287.176611)
					(end 425.190666 -287.212532)
				)
			)
		)
	)
	(zone
		(layers "In1.Cu" "In2.Cu")
		(hatch none 0.5)
		(connect_pads
			(clearance 0)
		)
		(min_thickness 0.25)
		(keepout
			(tracks not_allowed)
			(vias allowed)
			(pads allowed)
			(copperpour not_allowed)
			(footprints allowed)
		)
		(placement
			(enabled no)
			(sheetname "")
		)
		(fill yes
			(thermal_gap 0.5)
			(thermal_bridge_width 0.5)
			(island_removal_mode 0)
		)
		(polygon
			(pts
				(arc
					(start 180.69433 -196.671438)
					(mid 180.709209 -196.707359)
					(end 180.74513 -196.722238)
				)
				(arc
					(start 182.14467 -196.722238)
					(mid 182.180591 -196.707359)
					(end 182.19547 -196.671438)
				)
				(arc
					(start 182.19547 -196.262498)
					(mid 182.180591 -196.226577)
					(end 182.14467 -196.211698)
				)
				(arc
					(start 180.74513 -196.211698)
					(mid 180.709209 -196.226577)
					(end 180.69433 -196.262498)
				)
			)
		)
	)
	(zone
		(layers "In1.Cu" "In2.Cu")
		(hatch none 0.5)
		(connect_pads
			(clearance 0)
		)
		(min_thickness 0.25)
		(keepout
			(tracks not_allowed)
			(vias allowed)
			(pads allowed)
			(copperpour not_allowed)
			(footprints allowed)
		)
		(placement
			(enabled no)
			(sheetname "")
		)
		(fill yes
			(thermal_gap 0.5)
			(thermal_bridge_width 0.5)
			(island_removal_mode 0)
		)
		(polygon
			(pts
				(arc
					(start 451.265798 -273.171412)
					(mid 451.280677 -273.207333)
					(end 451.316598 -273.222212)
				)
				(arc
					(start 452.716138 -273.222212)
					(mid 452.752059 -273.207333)
					(end 452.766938 -273.171412)
				)
				(arc
					(start 452.766938 -272.762472)
					(mid 452.752059 -272.726551)
					(end 452.716138 -272.711672)
				)
				(arc
					(start 451.316598 -272.711672)
					(mid 451.280677 -272.726551)
					(end 451.265798 -272.762472)
				)
			)
		)
	)
	(zone
		(layers "In1.Cu" "In2.Cu")
		(hatch none 0.5)
		(connect_pads
			(clearance 0)
		)
		(min_thickness 0.25)
		(keepout
			(tracks not_allowed)
			(vias allowed)
			(pads allowed)
			(copperpour not_allowed)
			(footprints allowed)
		)
		(placement
			(enabled no)
			(sheetname "")
		)
		(fill yes
			(thermal_gap 0.5)
			(thermal_bridge_width 0.5)
			(island_removal_mode 0)
		)
		(polygon
			(pts
				(arc
					(start 64.296798 -239.17148)
					(mid 64.311677 -239.207401)
					(end 64.347598 -239.22228)
				)
				(arc
					(start 65.747138 -239.22228)
					(mid 65.783059 -239.207401)
					(end 65.797938 -239.17148)
				)
				(arc
					(start 65.797938 -238.76254)
					(mid 65.783059 -238.726619)
					(end 65.747138 -238.71174)
				)
				(arc
					(start 64.347598 -238.71174)
					(mid 64.311677 -238.726619)
					(end 64.296798 -238.76254)
				)
			)
		)
	)
	(zone
		(layers "In1.Cu" "In2.Cu")
		(hatch none 0.5)
		(connect_pads
			(clearance 0)
		)
		(min_thickness 0.25)
		(keepout
			(tracks not_allowed)
			(vias allowed)
			(pads allowed)
			(copperpour not_allowed)
			(footprints allowed)
		)
		(placement
			(enabled no)
			(sheetname "")
		)
		(fill yes
			(thermal_gap 0.5)
			(thermal_bridge_width 0.5)
			(island_removal_mode 0)
		)
		(polygon
			(pts
				(arc
					(start 22.47773 -223.021398)
					(mid 22.492609 -223.057319)
					(end 22.52853 -223.072198)
				)
				(arc
					(start 23.92807 -223.072198)
					(mid 23.963991 -223.057319)
					(end 23.97887 -223.021398)
				)
				(arc
					(start 23.97887 -222.612458)
					(mid 23.963991 -222.576537)
					(end 23.92807 -222.561658)
				)
				(arc
					(start 22.52853 -222.561658)
					(mid 22.492609 -222.576537)
					(end 22.47773 -222.612458)
				)
			)
		)
	)
	(zone
		(layers "In1.Cu" "In2.Cu")
		(hatch none 0.5)
		(connect_pads
			(clearance 0)
		)
		(min_thickness 0.25)
		(keepout
			(tracks not_allowed)
			(vias allowed)
			(pads allowed)
			(copperpour not_allowed)
			(footprints allowed)
		)
		(placement
			(enabled no)
			(sheetname "")
		)
		(fill yes
			(thermal_gap 0.5)
			(thermal_bridge_width 0.5)
			(island_removal_mode 0)
		)
		(polygon
			(pts
				(arc
					(start 11.490198 -201.771504)
					(mid 11.505077 -201.807425)
					(end 11.540998 -201.822304)
				)
				(arc
					(start 12.940538 -201.822304)
					(mid 12.976459 -201.807425)
					(end 12.991338 -201.771504)
				)
				(arc
					(start 12.991338 -201.362564)
					(mid 12.976459 -201.326643)
					(end 12.940538 -201.311764)
				)
				(arc
					(start 11.540998 -201.311764)
					(mid 11.505077 -201.326643)
					(end 11.490198 -201.362564)
				)
			)
		)
	)
	(zone
		(layers "In1.Cu" "In2.Cu")
		(hatch none 0.5)
		(connect_pads
			(clearance 0)
		)
		(min_thickness 0.25)
		(keepout
			(tracks not_allowed)
			(vias allowed)
			(pads allowed)
			(copperpour not_allowed)
			(footprints allowed)
		)
		(placement
			(enabled no)
			(sheetname "")
		)
		(fill yes
			(thermal_gap 0.5)
			(thermal_bridge_width 0.5)
			(island_removal_mode 0)
		)
		(polygon
			(pts
				(arc
					(start 207.425798 -308.021482)
					(mid 207.440677 -308.057403)
					(end 207.476598 -308.072282)
				)
				(arc
					(start 208.876138 -308.072282)
					(mid 208.912059 -308.057403)
					(end 208.926938 -308.021482)
				)
				(arc
					(start 208.926938 -307.612542)
					(mid 208.912059 -307.576621)
					(end 208.876138 -307.561742)
				)
				(arc
					(start 207.476598 -307.561742)
					(mid 207.440677 -307.576621)
					(end 207.425798 -307.612542)
				)
			)
		)
	)
	(zone
		(layers "In1.Cu" "In2.Cu")
		(hatch none 0.5)
		(connect_pads
			(clearance 0)
		)
		(min_thickness 0.25)
		(keepout
			(tracks not_allowed)
			(vias allowed)
			(pads allowed)
			(copperpour not_allowed)
			(footprints allowed)
		)
		(placement
			(enabled no)
			(sheetname "")
		)
		(fill yes
			(thermal_gap 0.5)
			(thermal_bridge_width 0.5)
			(island_removal_mode 0)
		)
		(polygon
			(pts
				(arc
					(start 451.265798 -275.721318)
					(mid 451.280677 -275.757239)
					(end 451.316598 -275.772118)
				)
				(arc
					(start 452.716138 -275.772118)
					(mid 452.752059 -275.757239)
					(end 452.766938 -275.721318)
				)
				(arc
					(start 452.766938 -275.312378)
					(mid 452.752059 -275.276457)
					(end 452.716138 -275.261578)
				)
				(arc
					(start 451.316598 -275.261578)
					(mid 451.280677 -275.276457)
					(end 451.265798 -275.312378)
				)
			)
		)
	)
	(zone
		(layers "In1.Cu" "In2.Cu")
		(hatch none 0.5)
		(connect_pads
			(clearance 0)
		)
		(min_thickness 0.25)
		(keepout
			(tracks not_allowed)
			(vias allowed)
			(pads allowed)
			(copperpour not_allowed)
			(footprints allowed)
		)
		(placement
			(enabled no)
			(sheetname "")
		)
		(fill yes
			(thermal_gap 0.5)
			(thermal_bridge_width 0.5)
			(island_removal_mode 0)
		)
		(polygon
			(pts
				(arc
					(start 406.002998 -302.921416)
					(mid 406.017877 -302.957337)
					(end 406.053798 -302.972216)
				)
				(arc
					(start 407.453338 -302.972216)
					(mid 407.489259 -302.957337)
					(end 407.504138 -302.921416)
				)
				(arc
					(start 407.504138 -302.512476)
					(mid 407.489259 -302.476555)
					(end 407.453338 -302.461676)
				)
				(arc
					(start 406.053798 -302.461676)
					(mid 406.017877 -302.476555)
					(end 406.002998 -302.512476)
				)
			)
		)
	)
	(zone
		(layers "In1.Cu" "In2.Cu")
		(hatch none 0.5)
		(connect_pads
			(clearance 0)
		)
		(min_thickness 0.25)
		(keepout
			(tracks not_allowed)
			(vias allowed)
			(pads allowed)
			(copperpour not_allowed)
			(footprints allowed)
		)
		(placement
			(enabled no)
			(sheetname "")
		)
		(fill yes
			(thermal_gap 0.5)
			(thermal_bridge_width 0.5)
			(island_removal_mode 0)
		)
		(polygon
			(pts
				(arc
					(start 421.090598 -215.371426)
					(mid 421.105477 -215.407347)
					(end 421.141398 -215.422226)
				)
				(arc
					(start 422.540938 -215.422226)
					(mid 422.576859 -215.407347)
					(end 422.591738 -215.371426)
				)
				(arc
					(start 422.591738 -214.962486)
					(mid 422.576859 -214.926565)
					(end 422.540938 -214.911686)
				)
				(arc
					(start 421.141398 -214.911686)
					(mid 421.105477 -214.926565)
					(end 421.090598 -214.962486)
				)
			)
		)
	)
	(zone
		(layers "In1.Cu" "In2.Cu")
		(hatch none 0.5)
		(connect_pads
			(clearance 0)
		)
		(min_thickness 0.25)
		(keepout
			(tracks not_allowed)
			(vias allowed)
			(pads allowed)
			(copperpour not_allowed)
			(footprints allowed)
		)
		(placement
			(enabled no)
			(sheetname "")
		)
		(fill yes
			(thermal_gap 0.5)
			(thermal_bridge_width 0.5)
			(island_removal_mode 0)
		)
		(polygon
			(pts
				(arc
					(start 158.06293 -302.921416)
					(mid 158.077809 -302.957337)
					(end 158.11373 -302.972216)
				)
				(arc
					(start 159.51327 -302.972216)
					(mid 159.549191 -302.957337)
					(end 159.56407 -302.921416)
				)
				(arc
					(start 159.56407 -302.512476)
					(mid 159.549191 -302.476555)
					(end 159.51327 -302.461676)
				)
				(arc
					(start 158.11373 -302.461676)
					(mid 158.077809 -302.476555)
					(end 158.06293 -302.512476)
				)
			)
		)
	)
	(zone
		(layers "In1.Cu" "In2.Cu")
		(hatch none 0.5)
		(connect_pads
			(clearance 0)
		)
		(min_thickness 0.25)
		(keepout
			(tracks not_allowed)
			(vias allowed)
			(pads allowed)
			(copperpour not_allowed)
			(footprints allowed)
		)
		(placement
			(enabled no)
			(sheetname "")
		)
		(fill yes
			(thermal_gap 0.5)
			(thermal_bridge_width 0.5)
			(island_removal_mode 0)
		)
		(polygon
			(pts
				(arc
					(start 203.32573 -279.121362)
					(mid 203.340609 -279.157283)
					(end 203.37653 -279.172162)
				)
				(arc
					(start 204.77607 -279.172162)
					(mid 204.811991 -279.157283)
					(end 204.82687 -279.121362)
				)
				(arc
					(start 204.82687 -278.712422)
					(mid 204.811991 -278.676501)
					(end 204.77607 -278.661622)
				)
				(arc
					(start 203.37653 -278.661622)
					(mid 203.340609 -278.676501)
					(end 203.32573 -278.712422)
				)
			)
		)
	)
	(zone
		(layers "In1.Cu" "In2.Cu")
		(hatch none 0.5)
		(connect_pads
			(clearance 0)
		)
		(min_thickness 0.25)
		(keepout
			(tracks not_allowed)
			(vias allowed)
			(pads allowed)
			(copperpour not_allowed)
			(footprints allowed)
		)
		(placement
			(enabled no)
			(sheetname "")
		)
		(fill yes
			(thermal_gap 0.5)
			(thermal_bridge_width 0.5)
			(island_removal_mode 0)
		)
		(polygon
			(pts
				(arc
					(start 22.47773 -290.171378)
					(mid 22.492609 -290.207299)
					(end 22.52853 -290.222178)
				)
				(arc
					(start 23.92807 -290.222178)
					(mid 23.963991 -290.207299)
					(end 23.97887 -290.171378)
				)
				(arc
					(start 23.97887 -289.762438)
					(mid 23.963991 -289.726517)
					(end 23.92807 -289.711638)
				)
				(arc
					(start 22.52853 -289.711638)
					(mid 22.492609 -289.726517)
					(end 22.47773 -289.762438)
				)
			)
		)
	)
	(zone
		(layers "In1.Cu" "In2.Cu")
		(hatch none 0.5)
		(connect_pads
			(clearance 0)
		)
		(min_thickness 0.25)
		(keepout
			(tracks not_allowed)
			(vias allowed)
			(pads allowed)
			(copperpour not_allowed)
			(footprints allowed)
		)
		(placement
			(enabled no)
			(sheetname "")
		)
		(fill yes
			(thermal_gap 0.5)
			(thermal_bridge_width 0.5)
			(island_removal_mode 0)
		)
		(polygon
			(pts
				(arc
					(start 56.752998 -283.371544)
					(mid 56.767877 -283.407465)
					(end 56.803798 -283.422344)
				)
				(arc
					(start 58.203338 -283.422344)
					(mid 58.239259 -283.407465)
					(end 58.254138 -283.371544)
				)
				(arc
					(start 58.254138 -282.962604)
					(mid 58.239259 -282.926683)
					(end 58.203338 -282.911804)
				)
				(arc
					(start 56.803798 -282.911804)
					(mid 56.767877 -282.926683)
					(end 56.752998 -282.962604)
				)
			)
		)
	)
	(zone
		(layers "In1.Cu" "In2.Cu")
		(hatch none 0.5)
		(connect_pads
			(clearance 0)
		)
		(min_thickness 0.25)
		(keepout
			(tracks not_allowed)
			(vias allowed)
			(pads allowed)
			(copperpour not_allowed)
			(footprints allowed)
		)
		(placement
			(enabled no)
			(sheetname "")
		)
		(fill yes
			(thermal_gap 0.5)
			(thermal_bridge_width 0.5)
			(island_removal_mode 0)
		)
		(polygon
			(pts
				(arc
					(start 447.822066 -233.22153)
					(mid 447.836945 -233.257451)
					(end 447.872866 -233.27233)
				)
				(arc
					(start 449.272406 -233.27233)
					(mid 449.308327 -233.257451)
					(end 449.323206 -233.22153)
				)
				(arc
					(start 449.323206 -232.81259)
					(mid 449.308327 -232.776669)
					(end 449.272406 -232.76179)
				)
				(arc
					(start 447.872866 -232.76179)
					(mid 447.836945 -232.776669)
					(end 447.822066 -232.81259)
				)
			)
		)
	)
	(zone
		(layers "In1.Cu" "In2.Cu")
		(hatch none 0.5)
		(connect_pads
			(clearance 0)
		)
		(min_thickness 0.25)
		(keepout
			(tracks not_allowed)
			(vias allowed)
			(pads allowed)
			(copperpour not_allowed)
			(footprints allowed)
		)
		(placement
			(enabled no)
			(sheetname "")
		)
		(fill yes
			(thermal_gap 0.5)
			(thermal_bridge_width 0.5)
			(island_removal_mode 0)
		)
		(polygon
			(pts
				(arc
					(start 428.634398 -235.771436)
					(mid 428.649277 -235.807357)
					(end 428.685198 -235.822236)
				)
				(arc
					(start 430.084738 -235.822236)
					(mid 430.120659 -235.807357)
					(end 430.135538 -235.771436)
				)
				(arc
					(start 430.135538 -235.362496)
					(mid 430.120659 -235.326575)
					(end 430.084738 -235.311696)
				)
				(arc
					(start 428.685198 -235.311696)
					(mid 428.649277 -235.326575)
					(end 428.634398 -235.362496)
				)
			)
		)
	)
	(zone
		(layers "In1.Cu" "In2.Cu")
		(hatch none 0.5)
		(connect_pads
			(clearance 0)
		)
		(min_thickness 0.25)
		(keepout
			(tracks not_allowed)
			(vias allowed)
			(pads allowed)
			(copperpour not_allowed)
			(footprints allowed)
		)
		(placement
			(enabled no)
			(sheetname "")
		)
		(fill yes
			(thermal_gap 0.5)
			(thermal_bridge_width 0.5)
			(island_removal_mode 0)
		)
		(polygon
			(pts
				(arc
					(start 312.236866 -206.871316)
					(mid 312.251745 -206.907237)
					(end 312.287666 -206.922116)
				)
				(arc
					(start 313.687206 -206.922116)
					(mid 313.723127 -206.907237)
					(end 313.738006 -206.871316)
				)
				(arc
					(start 313.738006 -206.462376)
					(mid 313.723127 -206.426455)
					(end 313.687206 -206.411576)
				)
				(arc
					(start 312.287666 -206.411576)
					(mid 312.251745 -206.426455)
					(end 312.236866 -206.462376)
				)
			)
		)
	)
	(zone
		(layers "In1.Cu" "In2.Cu")
		(hatch none 0.5)
		(connect_pads
			(clearance 0)
		)
		(min_thickness 0.25)
		(keepout
			(tracks not_allowed)
			(vias allowed)
			(pads allowed)
			(copperpour not_allowed)
			(footprints allowed)
		)
		(placement
			(enabled no)
			(sheetname "")
		)
		(fill yes
			(thermal_gap 0.5)
			(thermal_bridge_width 0.5)
			(island_removal_mode 0)
		)
		(polygon
			(pts
				(arc
					(start 14.93393 -305.471322)
					(mid 14.948809 -305.507243)
					(end 14.98473 -305.522122)
				)
				(arc
					(start 16.38427 -305.522122)
					(mid 16.420191 -305.507243)
					(end 16.43507 -305.471322)
				)
				(arc
					(start 16.43507 -305.062382)
					(mid 16.420191 -305.026461)
					(end 16.38427 -305.011582)
				)
				(arc
					(start 14.98473 -305.011582)
					(mid 14.948809 -305.026461)
					(end 14.93393 -305.062382)
				)
			)
		)
	)
	(zone
		(layers "In1.Cu" "In2.Cu")
		(hatch none 0.5)
		(connect_pads
			(clearance 0)
		)
		(min_thickness 0.25)
		(keepout
			(tracks not_allowed)
			(vias allowed)
			(pads allowed)
			(copperpour not_allowed)
			(footprints allowed)
		)
		(placement
			(enabled no)
			(sheetname "")
		)
		(fill yes
			(thermal_gap 0.5)
			(thermal_bridge_width 0.5)
			(island_removal_mode 0)
		)
		(polygon
			(pts
				(arc
					(start 19.033998 -236.62132)
					(mid 19.048877 -236.657241)
					(end 19.084798 -236.67212)
				)
				(arc
					(start 20.484338 -236.67212)
					(mid 20.520259 -236.657241)
					(end 20.535138 -236.62132)
				)
				(arc
					(start 20.535138 -236.21238)
					(mid 20.520259 -236.176459)
					(end 20.484338 -236.16158)
				)
				(arc
					(start 19.084798 -236.16158)
					(mid 19.048877 -236.176459)
					(end 19.033998 -236.21238)
				)
			)
		)
	)
	(zone
		(layers "In1.Cu" "In2.Cu")
		(hatch none 0.5)
		(connect_pads
			(clearance 0)
		)
		(min_thickness 0.25)
		(keepout
			(tracks not_allowed)
			(vias allowed)
			(pads allowed)
			(copperpour not_allowed)
			(footprints allowed)
		)
		(placement
			(enabled no)
			(sheetname "")
		)
		(fill yes
			(thermal_gap 0.5)
			(thermal_bridge_width 0.5)
			(island_removal_mode 0)
		)
		(polygon
			(pts
				(arc
					(start 458.809598 -215.371426)
					(mid 458.824477 -215.407347)
					(end 458.860398 -215.422226)
				)
				(arc
					(start 460.259938 -215.422226)
					(mid 460.295859 -215.407347)
					(end 460.310738 -215.371426)
				)
				(arc
					(start 460.310738 -214.962486)
					(mid 460.295859 -214.926565)
					(end 460.259938 -214.911686)
				)
				(arc
					(start 458.860398 -214.911686)
					(mid 458.824477 -214.926565)
					(end 458.809598 -214.962486)
				)
			)
		)
	)
	(zone
		(layers "In1.Cu" "In2.Cu")
		(hatch none 0.5)
		(connect_pads
			(clearance 0)
		)
		(min_thickness 0.25)
		(keepout
			(tracks not_allowed)
			(vias allowed)
			(pads allowed)
			(copperpour not_allowed)
			(footprints allowed)
		)
		(placement
			(enabled no)
			(sheetname "")
		)
		(fill yes
			(thermal_gap 0.5)
			(thermal_bridge_width 0.5)
			(island_removal_mode 0)
		)
		(polygon
			(pts
				(arc
					(start 274.517866 -217.921332)
					(mid 274.532745 -217.957253)
					(end 274.568666 -217.972132)
				)
				(arc
					(start 275.968206 -217.972132)
					(mid 276.004127 -217.957253)
					(end 276.019006 -217.921332)
				)
				(arc
					(start 276.019006 -217.512392)
					(mid 276.004127 -217.476471)
					(end 275.968206 -217.461592)
				)
				(arc
					(start 274.568666 -217.461592)
					(mid 274.532745 -217.476471)
					(end 274.517866 -217.512392)
				)
			)
		)
	)
	(zone
		(layers "In1.Cu" "In2.Cu")
		(hatch none 0.5)
		(connect_pads
			(clearance 0)
		)
		(min_thickness 0.25)
		(keepout
			(tracks not_allowed)
			(vias allowed)
			(pads allowed)
			(copperpour not_allowed)
			(footprints allowed)
		)
		(placement
			(enabled no)
			(sheetname "")
		)
		(fill yes
			(thermal_gap 0.5)
			(thermal_bridge_width 0.5)
			(island_removal_mode 0)
		)
		(polygon
			(pts
				(arc
					(start 255.330198 -269.771368)
					(mid 255.345077 -269.807289)
					(end 255.380998 -269.822168)
				)
				(arc
					(start 256.780538 -269.822168)
					(mid 256.816459 -269.807289)
					(end 256.831338 -269.771368)
				)
				(arc
					(start 256.831338 -269.362428)
					(mid 256.816459 -269.326507)
					(end 256.780538 -269.311628)
				)
				(arc
					(start 255.380998 -269.311628)
					(mid 255.345077 -269.326507)
					(end 255.330198 -269.362428)
				)
			)
		)
	)
	(zone
		(layers "In1.Cu" "In2.Cu")
		(hatch none 0.5)
		(connect_pads
			(clearance 0)
		)
		(min_thickness 0.25)
		(keepout
			(tracks not_allowed)
			(vias allowed)
			(pads allowed)
			(copperpour not_allowed)
			(footprints allowed)
		)
		(placement
			(enabled no)
			(sheetname "")
		)
		(fill yes
			(thermal_gap 0.5)
			(thermal_bridge_width 0.5)
			(island_removal_mode 0)
		)
		(polygon
			(pts
				(arc
					(start 304.693066 -229.821486)
					(mid 304.707945 -229.857407)
					(end 304.743866 -229.872286)
				)
				(arc
					(start 306.143406 -229.872286)
					(mid 306.179327 -229.857407)
					(end 306.194206 -229.821486)
				)
				(arc
					(start 306.194206 -229.412546)
					(mid 306.179327 -229.376625)
					(end 306.143406 -229.361746)
				)
				(arc
					(start 304.743866 -229.361746)
					(mid 304.707945 -229.376625)
					(end 304.693066 -229.412546)
				)
			)
		)
	)
	(zone
		(layers "In1.Cu" "In2.Cu")
		(hatch none 0.5)
		(connect_pads
			(clearance 0)
		)
		(min_thickness 0.25)
		(keepout
			(tracks not_allowed)
			(vias allowed)
			(pads allowed)
			(copperpour not_allowed)
			(footprints allowed)
		)
		(placement
			(enabled no)
			(sheetname "")
		)
		(fill yes
			(thermal_gap 0.5)
			(thermal_bridge_width 0.5)
			(island_removal_mode 0)
		)
		(polygon
			(pts
				(arc
					(start 455.365866 -212.82152)
					(mid 455.380745 -212.857441)
					(end 455.416666 -212.87232)
				)
				(arc
					(start 456.816206 -212.87232)
					(mid 456.852127 -212.857441)
					(end 456.867006 -212.82152)
				)
				(arc
					(start 456.867006 -212.41258)
					(mid 456.852127 -212.376659)
					(end 456.816206 -212.36178)
				)
				(arc
					(start 455.416666 -212.36178)
					(mid 455.380745 -212.376659)
					(end 455.365866 -212.41258)
				)
			)
		)
	)
	(zone
		(layers "In1.Cu" "In2.Cu")
		(hatch none 0.5)
		(connect_pads
			(clearance 0)
		)
		(min_thickness 0.25)
		(keepout
			(tracks not_allowed)
			(vias allowed)
			(pads allowed)
			(copperpour not_allowed)
			(footprints allowed)
		)
		(placement
			(enabled no)
			(sheetname "")
		)
		(fill yes
			(thermal_gap 0.5)
			(thermal_bridge_width 0.5)
			(island_removal_mode 0)
		)
		(polygon
			(pts
				(arc
					(start 428.634398 -200.071482)
					(mid 428.649277 -200.107403)
					(end 428.685198 -200.122282)
				)
				(arc
					(start 430.084738 -200.122282)
					(mid 430.120659 -200.107403)
					(end 430.135538 -200.071482)
				)
				(arc
					(start 430.135538 -199.662542)
					(mid 430.120659 -199.626621)
					(end 430.084738 -199.611742)
				)
				(arc
					(start 428.685198 -199.611742)
					(mid 428.649277 -199.626621)
					(end 428.634398 -199.662542)
				)
			)
		)
	)
	(zone
		(layers "In1.Cu" "In2.Cu")
		(hatch none 0.5)
		(connect_pads
			(clearance 0)
		)
		(min_thickness 0.25)
		(keepout
			(tracks not_allowed)
			(vias allowed)
			(pads allowed)
			(copperpour not_allowed)
			(footprints allowed)
		)
		(placement
			(enabled no)
			(sheetname "")
		)
		(fill yes
			(thermal_gap 0.5)
			(thermal_bridge_width 0.5)
			(island_removal_mode 0)
		)
		(polygon
			(pts
				(arc
					(start 162.162998 -272.321528)
					(mid 162.177877 -272.357449)
					(end 162.213798 -272.372328)
				)
				(arc
					(start 163.613338 -272.372328)
					(mid 163.649259 -272.357449)
					(end 163.664138 -272.321528)
				)
				(arc
					(start 163.664138 -271.912588)
					(mid 163.649259 -271.876667)
					(end 163.613338 -271.861788)
				)
				(arc
					(start 162.213798 -271.861788)
					(mid 162.177877 -271.876667)
					(end 162.162998 -271.912588)
				)
			)
		)
	)
	(zone
		(layers "In1.Cu" "In2.Cu")
		(hatch none 0.5)
		(connect_pads
			(clearance 0)
		)
		(min_thickness 0.25)
		(keepout
			(tracks not_allowed)
			(vias allowed)
			(pads allowed)
			(copperpour not_allowed)
			(footprints allowed)
		)
		(placement
			(enabled no)
			(sheetname "")
		)
		(fill yes
			(thermal_gap 0.5)
			(thermal_bridge_width 0.5)
			(island_removal_mode 0)
		)
		(polygon
			(pts
				(arc
					(start 30.02153 -211.971382)
					(mid 30.036409 -212.007303)
					(end 30.07233 -212.022182)
				)
				(arc
					(start 31.47187 -212.022182)
					(mid 31.507791 -212.007303)
					(end 31.52267 -211.971382)
				)
				(arc
					(start 31.52267 -211.562442)
					(mid 31.507791 -211.526521)
					(end 31.47187 -211.511642)
				)
				(arc
					(start 30.07233 -211.511642)
					(mid 30.036409 -211.526521)
					(end 30.02153 -211.562442)
				)
			)
		)
	)
	(zone
		(layers "In1.Cu" "In2.Cu")
		(hatch none 0.5)
		(connect_pads
			(clearance 0)
		)
		(min_thickness 0.25)
		(keepout
			(tracks not_allowed)
			(vias allowed)
			(pads allowed)
			(copperpour not_allowed)
			(footprints allowed)
		)
		(placement
			(enabled no)
			(sheetname "")
		)
		(fill yes
			(thermal_gap 0.5)
			(thermal_bridge_width 0.5)
			(island_removal_mode 0)
		)
		(polygon
			(pts
				(arc
					(start 158.06293 -313.121294)
					(mid 158.077809 -313.157215)
					(end 158.11373 -313.172094)
				)
				(arc
					(start 159.51327 -313.172094)
					(mid 159.549191 -313.157215)
					(end 159.56407 -313.121294)
				)
				(arc
					(start 159.56407 -312.712354)
					(mid 159.549191 -312.676433)
					(end 159.51327 -312.661554)
				)
				(arc
					(start 158.11373 -312.661554)
					(mid 158.077809 -312.676433)
					(end 158.06293 -312.712354)
				)
			)
		)
	)
	(zone
		(layers "In1.Cu" "In2.Cu")
		(hatch none 0.5)
		(connect_pads
			(clearance 0)
		)
		(min_thickness 0.25)
		(keepout
			(tracks not_allowed)
			(vias allowed)
			(pads allowed)
			(copperpour not_allowed)
			(footprints allowed)
		)
		(placement
			(enabled no)
			(sheetname "")
		)
		(fill yes
			(thermal_gap 0.5)
			(thermal_bridge_width 0.5)
			(island_removal_mode 0)
		)
		(polygon
			(pts
				(arc
					(start 173.15053 -310.571388)
					(mid 173.165409 -310.607309)
					(end 173.20133 -310.622188)
				)
				(arc
					(start 174.60087 -310.622188)
					(mid 174.636791 -310.607309)
					(end 174.65167 -310.571388)
				)
				(arc
					(start 174.65167 -310.162448)
					(mid 174.636791 -310.126527)
					(end 174.60087 -310.111648)
				)
				(arc
					(start 173.20133 -310.111648)
					(mid 173.165409 -310.126527)
					(end 173.15053 -310.162448)
				)
			)
		)
	)
	(zone
		(layers "In1.Cu" "In2.Cu")
		(hatch none 0.5)
		(connect_pads
			(clearance 0)
		)
		(min_thickness 0.25)
		(keepout
			(tracks not_allowed)
			(vias allowed)
			(pads allowed)
			(copperpour not_allowed)
			(footprints allowed)
		)
		(placement
			(enabled no)
			(sheetname "")
		)
		(fill yes
			(thermal_gap 0.5)
			(thermal_bridge_width 0.5)
			(island_removal_mode 0)
		)
		(polygon
			(pts
				(arc
					(start 162.162998 -309.721504)
					(mid 162.177877 -309.757425)
					(end 162.213798 -309.772304)
				)
				(arc
					(start 163.613338 -309.772304)
					(mid 163.649259 -309.757425)
					(end 163.664138 -309.721504)
				)
				(arc
					(start 163.664138 -309.312564)
					(mid 163.649259 -309.276643)
					(end 163.613338 -309.261764)
				)
				(arc
					(start 162.213798 -309.261764)
					(mid 162.177877 -309.276643)
					(end 162.162998 -309.312564)
				)
			)
		)
	)
	(zone
		(layers "In1.Cu" "In2.Cu")
		(hatch none 0.5)
		(connect_pads
			(clearance 0)
		)
		(min_thickness 0.25)
		(keepout
			(tracks not_allowed)
			(vias allowed)
			(pads allowed)
			(copperpour not_allowed)
			(footprints allowed)
		)
		(placement
			(enabled no)
			(sheetname "")
		)
		(fill yes
			(thermal_gap 0.5)
			(thermal_bridge_width 0.5)
			(island_removal_mode 0)
		)
		(polygon
			(pts
				(arc
					(start 34.121598 -276.571456)
					(mid 34.136477 -276.607377)
					(end 34.172398 -276.622256)
				)
				(arc
					(start 35.571938 -276.622256)
					(mid 35.607859 -276.607377)
					(end 35.622738 -276.571456)
				)
				(arc
					(start 35.622738 -276.162516)
					(mid 35.607859 -276.126595)
					(end 35.571938 -276.111716)
				)
				(arc
					(start 34.172398 -276.111716)
					(mid 34.136477 -276.126595)
					(end 34.121598 -276.162516)
				)
			)
		)
	)
	(zone
		(layers "In1.Cu" "In2.Cu")
		(hatch none 0.5)
		(connect_pads
			(clearance 0)
		)
		(min_thickness 0.25)
		(keepout
			(tracks not_allowed)
			(vias allowed)
			(pads allowed)
			(copperpour not_allowed)
			(footprints allowed)
		)
		(placement
			(enabled no)
			(sheetname "")
		)
		(fill yes
			(thermal_gap 0.5)
			(thermal_bridge_width 0.5)
			(island_removal_mode 0)
		)
		(polygon
			(pts
				(arc
					(start 413.546798 -206.021432)
					(mid 413.561677 -206.057353)
					(end 413.597598 -206.072232)
				)
				(arc
					(start 414.997138 -206.072232)
					(mid 415.033059 -206.057353)
					(end 415.047938 -206.021432)
				)
				(arc
					(start 415.047938 -205.612492)
					(mid 415.033059 -205.576571)
					(end 414.997138 -205.561692)
				)
				(arc
					(start 413.597598 -205.561692)
					(mid 413.561677 -205.576571)
					(end 413.546798 -205.612492)
				)
			)
		)
	)
	(zone
		(layers "In1.Cu" "In2.Cu")
		(hatch none 0.5)
		(connect_pads
			(clearance 0)
		)
		(min_thickness 0.25)
		(keepout
			(tracks not_allowed)
			(vias allowed)
			(pads allowed)
			(copperpour not_allowed)
			(footprints allowed)
		)
		(placement
			(enabled no)
			(sheetname "")
		)
		(fill yes
			(thermal_gap 0.5)
			(thermal_bridge_width 0.5)
			(island_removal_mode 0)
		)
		(polygon
			(pts
				(arc
					(start 158.06293 -303.7713)
					(mid 158.077809 -303.807221)
					(end 158.11373 -303.8221)
				)
				(arc
					(start 159.51327 -303.8221)
					(mid 159.549191 -303.807221)
					(end 159.56407 -303.7713)
				)
				(arc
					(start 159.56407 -303.36236)
					(mid 159.549191 -303.326439)
					(end 159.51327 -303.31156)
				)
				(arc
					(start 158.11373 -303.31156)
					(mid 158.077809 -303.326439)
					(end 158.06293 -303.36236)
				)
			)
		)
	)
	(zone
		(layers "In1.Cu" "In2.Cu")
		(hatch none 0.5)
		(connect_pads
			(clearance 0)
		)
		(min_thickness 0.25)
		(keepout
			(tracks not_allowed)
			(vias allowed)
			(pads allowed)
			(copperpour not_allowed)
			(footprints allowed)
		)
		(placement
			(enabled no)
			(sheetname "")
		)
		(fill yes
			(thermal_gap 0.5)
			(thermal_bridge_width 0.5)
			(island_removal_mode 0)
		)
		(polygon
			(pts
				(arc
					(start 406.002998 -273.171412)
					(mid 406.017877 -273.207333)
					(end 406.053798 -273.222212)
				)
				(arc
					(start 407.453338 -273.222212)
					(mid 407.489259 -273.207333)
					(end 407.504138 -273.171412)
				)
				(arc
					(start 407.504138 -272.762472)
					(mid 407.489259 -272.726551)
					(end 407.453338 -272.711672)
				)
				(arc
					(start 406.053798 -272.711672)
					(mid 406.017877 -272.726551)
					(end 406.002998 -272.762472)
				)
			)
		)
	)
	(zone
		(layers "In1.Cu" "In2.Cu")
		(hatch none 0.5)
		(connect_pads
			(clearance 0)
		)
		(min_thickness 0.25)
		(keepout
			(tracks not_allowed)
			(vias allowed)
			(pads allowed)
			(copperpour not_allowed)
			(footprints allowed)
		)
		(placement
			(enabled no)
			(sheetname "")
		)
		(fill yes
			(thermal_gap 0.5)
			(thermal_bridge_width 0.5)
			(island_removal_mode 0)
		)
		(polygon
			(pts
				(arc
					(start 184.794398 -229.821486)
					(mid 184.809277 -229.857407)
					(end 184.845198 -229.872286)
				)
				(arc
					(start 186.244738 -229.872286)
					(mid 186.280659 -229.857407)
					(end 186.295538 -229.821486)
				)
				(arc
					(start 186.295538 -229.412546)
					(mid 186.280659 -229.376625)
					(end 186.244738 -229.361746)
				)
				(arc
					(start 184.845198 -229.361746)
					(mid 184.809277 -229.376625)
					(end 184.794398 -229.412546)
				)
			)
		)
	)
	(zone
		(layers "In1.Cu" "In2.Cu")
		(hatch none 0.5)
		(connect_pads
			(clearance 0)
		)
		(min_thickness 0.25)
		(keepout
			(tracks not_allowed)
			(vias allowed)
			(pads allowed)
			(copperpour not_allowed)
			(footprints allowed)
		)
		(placement
			(enabled no)
			(sheetname "")
		)
		(fill yes
			(thermal_gap 0.5)
			(thermal_bridge_width 0.5)
			(island_removal_mode 0)
		)
		(polygon
			(pts
				(arc
					(start 11.490198 -262.121396)
					(mid 11.505077 -262.157317)
					(end 11.540998 -262.172196)
				)
				(arc
					(start 12.940538 -262.172196)
					(mid 12.976459 -262.157317)
					(end 12.991338 -262.121396)
				)
				(arc
					(start 12.991338 -261.712456)
					(mid 12.976459 -261.676535)
					(end 12.940538 -261.661656)
				)
				(arc
					(start 11.540998 -261.661656)
					(mid 11.505077 -261.676535)
					(end 11.490198 -261.712456)
				)
			)
		)
	)
	(zone
		(layers "In1.Cu" "In2.Cu")
		(hatch none 0.5)
		(connect_pads
			(clearance 0)
		)
		(min_thickness 0.25)
		(keepout
			(tracks not_allowed)
			(vias allowed)
			(pads allowed)
			(copperpour not_allowed)
			(footprints allowed)
		)
		(placement
			(enabled no)
			(sheetname "")
		)
		(fill yes
			(thermal_gap 0.5)
			(thermal_bridge_width 0.5)
			(island_removal_mode 0)
		)
		(polygon
			(pts
				(arc
					(start 406.002998 -299.521372)
					(mid 406.017877 -299.557293)
					(end 406.053798 -299.572172)
				)
				(arc
					(start 407.453338 -299.572172)
					(mid 407.489259 -299.557293)
					(end 407.504138 -299.521372)
				)
				(arc
					(start 407.504138 -299.112432)
					(mid 407.489259 -299.076511)
					(end 407.453338 -299.061632)
				)
				(arc
					(start 406.053798 -299.061632)
					(mid 406.017877 -299.076511)
					(end 406.002998 -299.112432)
				)
			)
		)
	)
	(zone
		(layers "In1.Cu" "In2.Cu")
		(hatch none 0.5)
		(connect_pads
			(clearance 0)
		)
		(min_thickness 0.25)
		(keepout
			(tracks not_allowed)
			(vias allowed)
			(pads allowed)
			(copperpour not_allowed)
			(footprints allowed)
		)
		(placement
			(enabled no)
			(sheetname "")
		)
		(fill yes
			(thermal_gap 0.5)
			(thermal_bridge_width 0.5)
			(island_removal_mode 0)
		)
		(polygon
			(pts
				(arc
					(start 304.693066 -223.871536)
					(mid 304.707945 -223.907457)
					(end 304.743866 -223.922336)
				)
				(arc
					(start 306.143406 -223.922336)
					(mid 306.179327 -223.907457)
					(end 306.194206 -223.871536)
				)
				(arc
					(start 306.194206 -223.462596)
					(mid 306.179327 -223.426675)
					(end 306.143406 -223.411796)
				)
				(arc
					(start 304.743866 -223.411796)
					(mid 304.707945 -223.426675)
					(end 304.693066 -223.462596)
				)
			)
		)
	)
	(zone
		(layers "In1.Cu" "In2.Cu")
		(hatch none 0.5)
		(connect_pads
			(clearance 0)
		)
		(min_thickness 0.25)
		(keepout
			(tracks not_allowed)
			(vias allowed)
			(pads allowed)
			(copperpour not_allowed)
			(footprints allowed)
		)
		(placement
			(enabled no)
			(sheetname "")
		)
		(fill yes
			(thermal_gap 0.5)
			(thermal_bridge_width 0.5)
			(island_removal_mode 0)
		)
		(polygon
			(pts
				(arc
					(start 173.15053 -288.471356)
					(mid 173.165409 -288.507277)
					(end 173.20133 -288.522156)
				)
				(arc
					(start 174.60087 -288.522156)
					(mid 174.636791 -288.507277)
					(end 174.65167 -288.471356)
				)
				(arc
					(start 174.65167 -288.062416)
					(mid 174.636791 -288.026495)
					(end 174.60087 -288.011616)
				)
				(arc
					(start 173.20133 -288.011616)
					(mid 173.165409 -288.026495)
					(end 173.15053 -288.062416)
				)
			)
		)
	)
	(zone
		(layers "In1.Cu" "In2.Cu")
		(hatch none 0.5)
		(connect_pads
			(clearance 0)
		)
		(min_thickness 0.25)
		(keepout
			(tracks not_allowed)
			(vias allowed)
			(pads allowed)
			(copperpour not_allowed)
			(footprints allowed)
		)
		(placement
			(enabled no)
			(sheetname "")
		)
		(fill yes
			(thermal_gap 0.5)
			(thermal_bridge_width 0.5)
			(island_removal_mode 0)
		)
		(polygon
			(pts
				(arc
					(start 277.961598 -217.071448)
					(mid 277.976477 -217.107369)
					(end 278.012398 -217.122248)
				)
				(arc
					(start 279.411938 -217.122248)
					(mid 279.447859 -217.107369)
					(end 279.462738 -217.071448)
				)
				(arc
					(start 279.462738 -216.662508)
					(mid 279.447859 -216.626587)
					(end 279.411938 -216.611708)
				)
				(arc
					(start 278.012398 -216.611708)
					(mid 277.976477 -216.626587)
					(end 277.961598 -216.662508)
				)
			)
		)
	)
	(zone
		(layers "In1.Cu" "In2.Cu")
		(hatch none 0.5)
		(connect_pads
			(clearance 0)
		)
		(min_thickness 0.25)
		(keepout
			(tracks not_allowed)
			(vias allowed)
			(pads allowed)
			(copperpour not_allowed)
			(footprints allowed)
		)
		(placement
			(enabled no)
			(sheetname "")
		)
		(fill yes
			(thermal_gap 0.5)
			(thermal_bridge_width 0.5)
			(island_removal_mode 0)
		)
		(polygon
			(pts
				(arc
					(start 60.19673 -238.321342)
					(mid 60.211609 -238.357263)
					(end 60.24753 -238.372142)
				)
				(arc
					(start 61.64707 -238.372142)
					(mid 61.682991 -238.357263)
					(end 61.69787 -238.321342)
				)
				(arc
					(start 61.69787 -237.912402)
					(mid 61.682991 -237.876481)
					(end 61.64707 -237.861602)
				)
				(arc
					(start 60.24753 -237.861602)
					(mid 60.211609 -237.876481)
					(end 60.19673 -237.912402)
				)
			)
		)
	)
	(zone
		(layers "In1.Cu" "In2.Cu")
		(hatch none 0.5)
		(connect_pads
			(clearance 0)
		)
		(min_thickness 0.25)
		(keepout
			(tracks not_allowed)
			(vias allowed)
			(pads allowed)
			(copperpour not_allowed)
			(footprints allowed)
		)
		(placement
			(enabled no)
			(sheetname "")
		)
		(fill yes
			(thermal_gap 0.5)
			(thermal_bridge_width 0.5)
			(island_removal_mode 0)
		)
		(polygon
			(pts
				(arc
					(start 169.706798 -267.221462)
					(mid 169.721677 -267.257383)
					(end 169.757598 -267.272262)
				)
				(arc
					(start 171.157138 -267.272262)
					(mid 171.193059 -267.257383)
					(end 171.207938 -267.221462)
				)
				(arc
					(start 171.207938 -266.812522)
					(mid 171.193059 -266.776601)
					(end 171.157138 -266.761722)
				)
				(arc
					(start 169.757598 -266.761722)
					(mid 169.721677 -266.776601)
					(end 169.706798 -266.812522)
				)
			)
		)
	)
	(zone
		(layers "In1.Cu" "In2.Cu")
		(hatch none 0.5)
		(connect_pads
			(clearance 0)
		)
		(min_thickness 0.25)
		(keepout
			(tracks not_allowed)
			(vias allowed)
			(pads allowed)
			(copperpour not_allowed)
			(footprints allowed)
		)
		(placement
			(enabled no)
			(sheetname "")
		)
		(fill yes
			(thermal_gap 0.5)
			(thermal_bridge_width 0.5)
			(island_removal_mode 0)
		)
		(polygon
			(pts
				(arc
					(start 199.881998 -259.57149)
					(mid 199.896877 -259.607411)
					(end 199.932798 -259.62229)
				)
				(arc
					(start 201.332338 -259.62229)
					(mid 201.368259 -259.607411)
					(end 201.383138 -259.57149)
				)
				(arc
					(start 201.383138 -259.16255)
					(mid 201.368259 -259.126629)
					(end 201.332338 -259.11175)
				)
				(arc
					(start 199.932798 -259.11175)
					(mid 199.896877 -259.126629)
					(end 199.881998 -259.16255)
				)
			)
		)
	)
	(zone
		(layers "In1.Cu" "In2.Cu")
		(hatch none 0.5)
		(connect_pads
			(clearance 0)
		)
		(min_thickness 0.25)
		(keepout
			(tracks not_allowed)
			(vias allowed)
			(pads allowed)
			(copperpour not_allowed)
			(footprints allowed)
		)
		(placement
			(enabled no)
			(sheetname "")
		)
		(fill yes
			(thermal_gap 0.5)
			(thermal_bridge_width 0.5)
			(island_removal_mode 0)
		)
		(polygon
			(pts
				(arc
					(start 259.430266 -315.671454)
					(mid 259.445145 -315.707375)
					(end 259.481066 -315.722254)
				)
				(arc
					(start 260.880606 -315.722254)
					(mid 260.916527 -315.707375)
					(end 260.931406 -315.671454)
				)
				(arc
					(start 260.931406 -315.262514)
					(mid 260.916527 -315.226593)
					(end 260.880606 -315.211714)
				)
				(arc
					(start 259.481066 -315.211714)
					(mid 259.445145 -315.226593)
					(end 259.430266 -315.262514)
				)
			)
		)
	)
	(zone
		(layers "In1.Cu" "In2.Cu")
		(hatch none 0.5)
		(connect_pads
			(clearance 0)
		)
		(min_thickness 0.25)
		(keepout
			(tracks not_allowed)
			(vias allowed)
			(pads allowed)
			(copperpour not_allowed)
			(footprints allowed)
		)
		(placement
			(enabled no)
			(sheetname "")
		)
		(fill yes
			(thermal_gap 0.5)
			(thermal_bridge_width 0.5)
			(island_removal_mode 0)
		)
		(polygon
			(pts
				(arc
					(start 177.250598 -278.271478)
					(mid 177.265477 -278.307399)
					(end 177.301398 -278.322278)
				)
				(arc
					(start 178.700938 -278.322278)
					(mid 178.736859 -278.307399)
					(end 178.751738 -278.271478)
				)
				(arc
					(start 178.751738 -277.862538)
					(mid 178.736859 -277.826617)
					(end 178.700938 -277.811738)
				)
				(arc
					(start 177.301398 -277.811738)
					(mid 177.265477 -277.826617)
					(end 177.250598 -277.862538)
				)
			)
		)
	)
	(zone
		(layers "In1.Cu" "In2.Cu")
		(hatch none 0.5)
		(connect_pads
			(clearance 0)
		)
		(min_thickness 0.25)
		(keepout
			(tracks not_allowed)
			(vias allowed)
			(pads allowed)
			(copperpour not_allowed)
			(footprints allowed)
		)
		(placement
			(enabled no)
			(sheetname "")
		)
		(fill yes
			(thermal_gap 0.5)
			(thermal_bridge_width 0.5)
			(island_removal_mode 0)
		)
		(polygon
			(pts
				(arc
					(start 37.56533 -215.371426)
					(mid 37.580209 -215.407347)
					(end 37.61613 -215.422226)
				)
				(arc
					(start 39.01567 -215.422226)
					(mid 39.051591 -215.407347)
					(end 39.06647 -215.371426)
				)
				(arc
					(start 39.06647 -214.962486)
					(mid 39.051591 -214.926565)
					(end 39.01567 -214.911686)
				)
				(arc
					(start 37.61613 -214.911686)
					(mid 37.580209 -214.926565)
					(end 37.56533 -214.962486)
				)
			)
		)
	)
	(zone
		(layers "In1.Cu" "In2.Cu")
		(hatch none 0.5)
		(connect_pads
			(clearance 0)
		)
		(min_thickness 0.25)
		(keepout
			(tracks not_allowed)
			(vias allowed)
			(pads allowed)
			(copperpour not_allowed)
			(footprints allowed)
		)
		(placement
			(enabled no)
			(sheetname "")
		)
		(fill yes
			(thermal_gap 0.5)
			(thermal_bridge_width 0.5)
			(island_removal_mode 0)
		)
		(polygon
			(pts
				(arc
					(start 203.32573 -268.071346)
					(mid 203.340609 -268.107267)
					(end 203.37653 -268.122146)
				)
				(arc
					(start 204.77607 -268.122146)
					(mid 204.811991 -268.107267)
					(end 204.82687 -268.071346)
				)
				(arc
					(start 204.82687 -267.662406)
					(mid 204.811991 -267.626485)
					(end 204.77607 -267.611606)
				)
				(arc
					(start 203.37653 -267.611606)
					(mid 203.340609 -267.626485)
					(end 203.32573 -267.662406)
				)
			)
		)
	)
	(zone
		(layers "In1.Cu" "In2.Cu")
		(hatch none 0.5)
		(connect_pads
			(clearance 0)
		)
		(min_thickness 0.25)
		(keepout
			(tracks not_allowed)
			(vias allowed)
			(pads allowed)
			(copperpour not_allowed)
			(footprints allowed)
		)
		(placement
			(enabled no)
			(sheetname "")
		)
		(fill yes
			(thermal_gap 0.5)
			(thermal_bridge_width 0.5)
			(island_removal_mode 0)
		)
		(polygon
			(pts
				(arc
					(start 432.734466 -251.921518)
					(mid 432.749345 -251.957439)
					(end 432.785266 -251.972318)
				)
				(arc
					(start 434.184806 -251.972318)
					(mid 434.220727 -251.957439)
					(end 434.235606 -251.921518)
				)
				(arc
					(start 434.235606 -251.512578)
					(mid 434.220727 -251.476657)
					(end 434.184806 -251.461778)
				)
				(arc
					(start 432.785266 -251.461778)
					(mid 432.749345 -251.476657)
					(end 432.734466 -251.512578)
				)
			)
		)
	)
	(zone
		(layers "In1.Cu" "In2.Cu")
		(hatch none 0.5)
		(connect_pads
			(clearance 0)
		)
		(min_thickness 0.25)
		(keepout
			(tracks not_allowed)
			(vias allowed)
			(pads allowed)
			(copperpour not_allowed)
			(footprints allowed)
		)
		(placement
			(enabled no)
			(sheetname "")
		)
		(fill yes
			(thermal_gap 0.5)
			(thermal_bridge_width 0.5)
			(island_removal_mode 0)
		)
		(polygon
			(pts
				(arc
					(start 199.881998 -248.521474)
					(mid 199.896877 -248.557395)
					(end 199.932798 -248.572274)
				)
				(arc
					(start 201.332338 -248.572274)
					(mid 201.368259 -248.557395)
					(end 201.383138 -248.521474)
				)
				(arc
					(start 201.383138 -248.112534)
					(mid 201.368259 -248.076613)
					(end 201.332338 -248.061734)
				)
				(arc
					(start 199.932798 -248.061734)
					(mid 199.896877 -248.076613)
					(end 199.881998 -248.112534)
				)
			)
		)
	)
	(zone
		(layers "In1.Cu" "In2.Cu")
		(hatch none 0.5)
		(connect_pads
			(clearance 0)
		)
		(min_thickness 0.25)
		(keepout
			(tracks not_allowed)
			(vias allowed)
			(pads allowed)
			(copperpour not_allowed)
			(footprints allowed)
		)
		(placement
			(enabled no)
			(sheetname "")
		)
		(fill yes
			(thermal_gap 0.5)
			(thermal_bridge_width 0.5)
			(island_removal_mode 0)
		)
		(polygon
			(pts
				(arc
					(start 406.002998 -243.421408)
					(mid 406.017877 -243.457329)
					(end 406.053798 -243.472208)
				)
				(arc
					(start 407.453338 -243.472208)
					(mid 407.489259 -243.457329)
					(end 407.504138 -243.421408)
				)
				(arc
					(start 407.504138 -243.012468)
					(mid 407.489259 -242.976547)
					(end 407.453338 -242.961668)
				)
				(arc
					(start 406.053798 -242.961668)
					(mid 406.017877 -242.976547)
					(end 406.002998 -243.012468)
				)
			)
		)
	)
	(zone
		(layers "In1.Cu" "In2.Cu")
		(hatch none 0.5)
		(connect_pads
			(clearance 0)
		)
		(min_thickness 0.25)
		(keepout
			(tracks not_allowed)
			(vias allowed)
			(pads allowed)
			(copperpour not_allowed)
			(footprints allowed)
		)
		(placement
			(enabled no)
			(sheetname "")
		)
		(fill yes
			(thermal_gap 0.5)
			(thermal_bridge_width 0.5)
			(island_removal_mode 0)
		)
		(polygon
			(pts
				(arc
					(start 22.47773 -228.971348)
					(mid 22.492609 -229.007269)
					(end 22.52853 -229.022148)
				)
				(arc
					(start 23.92807 -229.022148)
					(mid 23.963991 -229.007269)
					(end 23.97887 -228.971348)
				)
				(arc
					(start 23.97887 -228.562408)
					(mid 23.963991 -228.526487)
					(end 23.92807 -228.511608)
				)
				(arc
					(start 22.52853 -228.511608)
					(mid 22.492609 -228.526487)
					(end 22.47773 -228.562408)
				)
			)
		)
	)
	(zone
		(layers "In1.Cu" "In2.Cu")
		(hatch none 0.5)
		(connect_pads
			(clearance 0)
		)
		(min_thickness 0.25)
		(keepout
			(tracks not_allowed)
			(vias allowed)
			(pads allowed)
			(copperpour not_allowed)
			(footprints allowed)
		)
		(placement
			(enabled no)
			(sheetname "")
		)
		(fill yes
			(thermal_gap 0.5)
			(thermal_bridge_width 0.5)
			(island_removal_mode 0)
		)
		(polygon
			(pts
				(arc
					(start 285.505398 -238.321342)
					(mid 285.520277 -238.357263)
					(end 285.556198 -238.372142)
				)
				(arc
					(start 286.955738 -238.372142)
					(mid 286.991659 -238.357263)
					(end 287.006538 -238.321342)
				)
				(arc
					(start 287.006538 -237.912402)
					(mid 286.991659 -237.876481)
					(end 286.955738 -237.861602)
				)
				(arc
					(start 285.556198 -237.861602)
					(mid 285.520277 -237.876481)
					(end 285.505398 -237.912402)
				)
			)
		)
	)
	(zone
		(layers "In1.Cu" "In2.Cu")
		(hatch none 0.5)
		(connect_pads
			(clearance 0)
		)
		(min_thickness 0.25)
		(keepout
			(tracks not_allowed)
			(vias allowed)
			(pads allowed)
			(copperpour not_allowed)
			(footprints allowed)
		)
		(placement
			(enabled no)
			(sheetname "")
		)
		(fill yes
			(thermal_gap 0.5)
			(thermal_bridge_width 0.5)
			(island_removal_mode 0)
		)
		(polygon
			(pts
				(arc
					(start 52.65293 -310.571388)
					(mid 52.667809 -310.607309)
					(end 52.70373 -310.622188)
				)
				(arc
					(start 54.10327 -310.622188)
					(mid 54.139191 -310.607309)
					(end 54.15407 -310.571388)
				)
				(arc
					(start 54.15407 -310.162448)
					(mid 54.139191 -310.126527)
					(end 54.10327 -310.111648)
				)
				(arc
					(start 52.70373 -310.111648)
					(mid 52.667809 -310.126527)
					(end 52.65293 -310.162448)
				)
			)
		)
	)
	(zone
		(layers "In1.Cu" "In2.Cu")
		(hatch none 0.5)
		(connect_pads
			(clearance 0)
		)
		(min_thickness 0.25)
		(keepout
			(tracks not_allowed)
			(vias allowed)
			(pads allowed)
			(copperpour not_allowed)
			(footprints allowed)
		)
		(placement
			(enabled no)
			(sheetname "")
		)
		(fill yes
			(thermal_gap 0.5)
			(thermal_bridge_width 0.5)
			(island_removal_mode 0)
		)
		(polygon
			(pts
				(arc
					(start 64.296798 -217.921332)
					(mid 64.311677 -217.957253)
					(end 64.347598 -217.972132)
				)
				(arc
					(start 65.747138 -217.972132)
					(mid 65.783059 -217.957253)
					(end 65.797938 -217.921332)
				)
				(arc
					(start 65.797938 -217.512392)
					(mid 65.783059 -217.476471)
					(end 65.747138 -217.461592)
				)
				(arc
					(start 64.347598 -217.461592)
					(mid 64.311677 -217.476471)
					(end 64.296798 -217.512392)
				)
			)
		)
	)
	(zone
		(layers "In1.Cu" "In2.Cu")
		(hatch none 0.5)
		(connect_pads
			(clearance 0)
		)
		(min_thickness 0.25)
		(keepout
			(tracks not_allowed)
			(vias allowed)
			(pads allowed)
			(copperpour not_allowed)
			(footprints allowed)
		)
		(placement
			(enabled no)
			(sheetname "")
		)
		(fill yes
			(thermal_gap 0.5)
			(thermal_bridge_width 0.5)
			(island_removal_mode 0)
		)
		(polygon
			(pts
				(arc
					(start 165.60673 -268.071346)
					(mid 165.621609 -268.107267)
					(end 165.65753 -268.122146)
				)
				(arc
					(start 167.05707 -268.122146)
					(mid 167.092991 -268.107267)
					(end 167.10787 -268.071346)
				)
				(arc
					(start 167.10787 -267.662406)
					(mid 167.092991 -267.626485)
					(end 167.05707 -267.611606)
				)
				(arc
					(start 165.65753 -267.611606)
					(mid 165.621609 -267.626485)
					(end 165.60673 -267.662406)
				)
			)
		)
	)
	(zone
		(layers "In1.Cu" "In2.Cu")
		(hatch none 0.5)
		(connect_pads
			(clearance 0)
		)
		(min_thickness 0.25)
		(keepout
			(tracks not_allowed)
			(vias allowed)
			(pads allowed)
			(copperpour not_allowed)
			(footprints allowed)
		)
		(placement
			(enabled no)
			(sheetname "")
		)
		(fill yes
			(thermal_gap 0.5)
			(thermal_bridge_width 0.5)
			(island_removal_mode 0)
		)
		(polygon
			(pts
				(arc
					(start 406.002998 -301.221394)
					(mid 406.017877 -301.257315)
					(end 406.053798 -301.272194)
				)
				(arc
					(start 407.453338 -301.272194)
					(mid 407.489259 -301.257315)
					(end 407.504138 -301.221394)
				)
				(arc
					(start 407.504138 -300.812454)
					(mid 407.489259 -300.776533)
					(end 407.453338 -300.761654)
				)
				(arc
					(start 406.053798 -300.761654)
					(mid 406.017877 -300.776533)
					(end 406.002998 -300.812454)
				)
			)
		)
	)
	(zone
		(layers "In1.Cu" "In2.Cu")
		(hatch none 0.5)
		(connect_pads
			(clearance 0)
		)
		(min_thickness 0.25)
		(keepout
			(tracks not_allowed)
			(vias allowed)
			(pads allowed)
			(copperpour not_allowed)
			(footprints allowed)
		)
		(placement
			(enabled no)
			(sheetname "")
		)
		(fill yes
			(thermal_gap 0.5)
			(thermal_bridge_width 0.5)
			(island_removal_mode 0)
		)
		(polygon
			(pts
				(arc
					(start 19.033998 -233.22153)
					(mid 19.048877 -233.257451)
					(end 19.084798 -233.27233)
				)
				(arc
					(start 20.484338 -233.27233)
					(mid 20.520259 -233.257451)
					(end 20.535138 -233.22153)
				)
				(arc
					(start 20.535138 -232.81259)
					(mid 20.520259 -232.776669)
					(end 20.484338 -232.76179)
				)
				(arc
					(start 19.084798 -232.76179)
					(mid 19.048877 -232.776669)
					(end 19.033998 -232.81259)
				)
			)
		)
	)
	(zone
		(layers "In1.Cu" "In2.Cu")
		(hatch none 0.5)
		(connect_pads
			(clearance 0)
		)
		(min_thickness 0.25)
		(keepout
			(tracks not_allowed)
			(vias allowed)
			(pads allowed)
			(copperpour not_allowed)
			(footprints allowed)
		)
		(placement
			(enabled no)
			(sheetname "")
		)
		(fill yes
			(thermal_gap 0.5)
			(thermal_bridge_width 0.5)
			(island_removal_mode 0)
		)
		(polygon
			(pts
				(arc
					(start 304.693066 -197.521322)
					(mid 304.707945 -197.557243)
					(end 304.743866 -197.572122)
				)
				(arc
					(start 306.143406 -197.572122)
					(mid 306.179327 -197.557243)
					(end 306.194206 -197.521322)
				)
				(arc
					(start 306.194206 -197.112382)
					(mid 306.179327 -197.076461)
					(end 306.143406 -197.061582)
				)
				(arc
					(start 304.743866 -197.061582)
					(mid 304.707945 -197.076461)
					(end 304.693066 -197.112382)
				)
			)
		)
	)
	(zone
		(layers "In1.Cu" "In2.Cu")
		(hatch none 0.5)
		(connect_pads
			(clearance 0)
		)
		(min_thickness 0.25)
		(keepout
			(tracks not_allowed)
			(vias allowed)
			(pads allowed)
			(copperpour not_allowed)
			(footprints allowed)
		)
		(placement
			(enabled no)
			(sheetname "")
		)
		(fill yes
			(thermal_gap 0.5)
			(thermal_bridge_width 0.5)
			(island_removal_mode 0)
		)
		(polygon
			(pts
				(arc
					(start 312.236866 -296.971466)
					(mid 312.251745 -297.007387)
					(end 312.287666 -297.022266)
				)
				(arc
					(start 313.687206 -297.022266)
					(mid 313.723127 -297.007387)
					(end 313.738006 -296.971466)
				)
				(arc
					(start 313.738006 -296.562526)
					(mid 313.723127 -296.526605)
					(end 313.687206 -296.511726)
				)
				(arc
					(start 312.287666 -296.511726)
					(mid 312.251745 -296.526605)
					(end 312.236866 -296.562526)
				)
			)
		)
	)
	(zone
		(layers "In1.Cu" "In2.Cu")
		(hatch none 0.5)
		(connect_pads
			(clearance 0)
		)
		(min_thickness 0.25)
		(keepout
			(tracks not_allowed)
			(vias allowed)
			(pads allowed)
			(copperpour not_allowed)
			(footprints allowed)
		)
		(placement
			(enabled no)
			(sheetname "")
		)
		(fill yes
			(thermal_gap 0.5)
			(thermal_bridge_width 0.5)
			(island_removal_mode 0)
		)
		(polygon
			(pts
				(arc
					(start 425.190666 -268.921484)
					(mid 425.205545 -268.957405)
					(end 425.241466 -268.972284)
				)
				(arc
					(start 426.641006 -268.972284)
					(mid 426.676927 -268.957405)
					(end 426.691806 -268.921484)
				)
				(arc
					(start 426.691806 -268.512544)
					(mid 426.676927 -268.476623)
					(end 426.641006 -268.461744)
				)
				(arc
					(start 425.241466 -268.461744)
					(mid 425.205545 -268.476623)
					(end 425.190666 -268.512544)
				)
			)
		)
	)
	(zone
		(layers "In1.Cu" "In2.Cu")
		(hatch none 0.5)
		(connect_pads
			(clearance 0)
		)
		(min_thickness 0.25)
		(keepout
			(tracks not_allowed)
			(vias allowed)
			(pads allowed)
			(copperpour not_allowed)
			(footprints allowed)
		)
		(placement
			(enabled no)
			(sheetname "")
		)
		(fill yes
			(thermal_gap 0.5)
			(thermal_bridge_width 0.5)
			(island_removal_mode 0)
		)
		(polygon
			(pts
				(arc
					(start 11.490198 -237.471458)
					(mid 11.505077 -237.507379)
					(end 11.540998 -237.522258)
				)
				(arc
					(start 12.940538 -237.522258)
					(mid 12.976459 -237.507379)
					(end 12.991338 -237.471458)
				)
				(arc
					(start 12.991338 -237.062518)
					(mid 12.976459 -237.026597)
					(end 12.940538 -237.011718)
				)
				(arc
					(start 11.540998 -237.011718)
					(mid 11.505077 -237.026597)
					(end 11.490198 -237.062518)
				)
			)
		)
	)
	(zone
		(layers "In1.Cu" "In2.Cu")
		(hatch none 0.5)
		(connect_pads
			(clearance 0)
		)
		(min_thickness 0.25)
		(keepout
			(tracks not_allowed)
			(vias allowed)
			(pads allowed)
			(copperpour not_allowed)
			(footprints allowed)
		)
		(placement
			(enabled no)
			(sheetname "")
		)
		(fill yes
			(thermal_gap 0.5)
			(thermal_bridge_width 0.5)
			(island_removal_mode 0)
		)
		(polygon
			(pts
				(arc
					(start 259.430266 -309.721504)
					(mid 259.445145 -309.757425)
					(end 259.481066 -309.772304)
				)
				(arc
					(start 260.880606 -309.772304)
					(mid 260.916527 -309.757425)
					(end 260.931406 -309.721504)
				)
				(arc
					(start 260.931406 -309.312564)
					(mid 260.916527 -309.276643)
					(end 260.880606 -309.261764)
				)
				(arc
					(start 259.481066 -309.261764)
					(mid 259.445145 -309.276643)
					(end 259.430266 -309.312564)
				)
			)
		)
	)
	(zone
		(layers "In1.Cu" "In2.Cu")
		(hatch none 0.5)
		(connect_pads
			(clearance 0)
		)
		(min_thickness 0.25)
		(keepout
			(tracks not_allowed)
			(vias allowed)
			(pads allowed)
			(copperpour not_allowed)
			(footprints allowed)
		)
		(placement
			(enabled no)
			(sheetname "")
		)
		(fill yes
			(thermal_gap 0.5)
			(thermal_bridge_width 0.5)
			(island_removal_mode 0)
		)
		(polygon
			(pts
				(arc
					(start 406.002998 -274.871434)
					(mid 406.017877 -274.907355)
					(end 406.053798 -274.922234)
				)
				(arc
					(start 407.453338 -274.922234)
					(mid 407.489259 -274.907355)
					(end 407.504138 -274.871434)
				)
				(arc
					(start 407.504138 -274.462494)
					(mid 407.489259 -274.426573)
					(end 407.453338 -274.411694)
				)
				(arc
					(start 406.053798 -274.411694)
					(mid 406.017877 -274.426573)
					(end 406.002998 -274.462494)
				)
			)
		)
	)
	(zone
		(layers "In1.Cu" "In2.Cu")
		(hatch none 0.5)
		(connect_pads
			(clearance 0)
		)
		(min_thickness 0.25)
		(keepout
			(tracks not_allowed)
			(vias allowed)
			(pads allowed)
			(copperpour not_allowed)
			(footprints allowed)
		)
		(placement
			(enabled no)
			(sheetname "")
		)
		(fill yes
			(thermal_gap 0.5)
			(thermal_bridge_width 0.5)
			(island_removal_mode 0)
		)
		(polygon
			(pts
				(arc
					(start 308.136798 -313.121294)
					(mid 308.151677 -313.157215)
					(end 308.187598 -313.172094)
				)
				(arc
					(start 309.587138 -313.172094)
					(mid 309.623059 -313.157215)
					(end 309.637938 -313.121294)
				)
				(arc
					(start 309.637938 -312.712354)
					(mid 309.623059 -312.676433)
					(end 309.587138 -312.661554)
				)
				(arc
					(start 308.187598 -312.661554)
					(mid 308.151677 -312.676433)
					(end 308.136798 -312.712354)
				)
			)
		)
	)
	(zone
		(layers "In1.Cu" "In2.Cu")
		(hatch none 0.5)
		(connect_pads
			(clearance 0)
		)
		(min_thickness 0.25)
		(keepout
			(tracks not_allowed)
			(vias allowed)
			(pads allowed)
			(copperpour not_allowed)
			(footprints allowed)
		)
		(placement
			(enabled no)
			(sheetname "")
		)
		(fill yes
			(thermal_gap 0.5)
			(thermal_bridge_width 0.5)
			(island_removal_mode 0)
		)
		(polygon
			(pts
				(arc
					(start 210.86953 -207.721454)
					(mid 210.884409 -207.757375)
					(end 210.92033 -207.772254)
				)
				(arc
					(start 212.31987 -207.772254)
					(mid 212.355791 -207.757375)
					(end 212.37067 -207.721454)
				)
				(arc
					(start 212.37067 -207.312514)
					(mid 212.355791 -207.276593)
					(end 212.31987 -207.261714)
				)
				(arc
					(start 210.92033 -207.261714)
					(mid 210.884409 -207.276593)
					(end 210.86953 -207.312514)
				)
			)
		)
	)
	(zone
		(layers "In1.Cu" "In2.Cu")
		(hatch none 0.5)
		(connect_pads
			(clearance 0)
		)
		(min_thickness 0.25)
		(keepout
			(tracks not_allowed)
			(vias allowed)
			(pads allowed)
			(copperpour not_allowed)
			(footprints allowed)
		)
		(placement
			(enabled no)
			(sheetname "")
		)
		(fill yes
			(thermal_gap 0.5)
			(thermal_bridge_width 0.5)
			(island_removal_mode 0)
		)
		(polygon
			(pts
				(arc
					(start 210.86953 -210.27136)
					(mid 210.884409 -210.307281)
					(end 210.92033 -210.32216)
				)
				(arc
					(start 212.31987 -210.32216)
					(mid 212.355791 -210.307281)
					(end 212.37067 -210.27136)
				)
				(arc
					(start 212.37067 -209.86242)
					(mid 212.355791 -209.826499)
					(end 212.31987 -209.81162)
				)
				(arc
					(start 210.92033 -209.81162)
					(mid 210.884409 -209.826499)
					(end 210.86953 -209.86242)
				)
			)
		)
	)
	(zone
		(layers "In1.Cu" "In2.Cu")
		(hatch none 0.5)
		(connect_pads
			(clearance 0)
		)
		(min_thickness 0.25)
		(keepout
			(tracks not_allowed)
			(vias allowed)
			(pads allowed)
			(copperpour not_allowed)
			(footprints allowed)
		)
		(placement
			(enabled no)
			(sheetname "")
		)
		(fill yes
			(thermal_gap 0.5)
			(thermal_bridge_width 0.5)
			(island_removal_mode 0)
		)
		(polygon
			(pts
				(arc
					(start 462.909666 -302.071532)
					(mid 462.924545 -302.107453)
					(end 462.960466 -302.122332)
				)
				(arc
					(start 464.360006 -302.122332)
					(mid 464.395927 -302.107453)
					(end 464.410806 -302.071532)
				)
				(arc
					(start 464.410806 -301.662592)
					(mid 464.395927 -301.626671)
					(end 464.360006 -301.611792)
				)
				(arc
					(start 462.960466 -301.611792)
					(mid 462.924545 -301.626671)
					(end 462.909666 -301.662592)
				)
			)
		)
	)
	(zone
		(layers "In1.Cu" "In2.Cu")
		(hatch none 0.5)
		(connect_pads
			(clearance 0)
		)
		(min_thickness 0.25)
		(keepout
			(tracks not_allowed)
			(vias allowed)
			(pads allowed)
			(copperpour not_allowed)
			(footprints allowed)
		)
		(placement
			(enabled no)
			(sheetname "")
		)
		(fill yes
			(thermal_gap 0.5)
			(thermal_bridge_width 0.5)
			(island_removal_mode 0)
		)
		(polygon
			(pts
				(arc
					(start 188.23813 -218.77147)
					(mid 188.253009 -218.807391)
					(end 188.28893 -218.82227)
				)
				(arc
					(start 189.68847 -218.82227)
					(mid 189.724391 -218.807391)
					(end 189.73927 -218.77147)
				)
				(arc
					(start 189.73927 -218.36253)
					(mid 189.724391 -218.326609)
					(end 189.68847 -218.31173)
				)
				(arc
					(start 188.28893 -218.31173)
					(mid 188.253009 -218.326609)
					(end 188.23813 -218.36253)
				)
			)
		)
	)
	(zone
		(layers "In1.Cu" "In2.Cu")
		(hatch none 0.5)
		(connect_pads
			(clearance 0)
		)
		(min_thickness 0.25)
		(keepout
			(tracks not_allowed)
			(vias allowed)
			(pads allowed)
			(copperpour not_allowed)
			(footprints allowed)
		)
		(placement
			(enabled no)
			(sheetname "")
		)
		(fill yes
			(thermal_gap 0.5)
			(thermal_bridge_width 0.5)
			(island_removal_mode 0)
		)
		(polygon
			(pts
				(arc
					(start 289.605466 -265.52144)
					(mid 289.620345 -265.557361)
					(end 289.656266 -265.57224)
				)
				(arc
					(start 291.055806 -265.57224)
					(mid 291.091727 -265.557361)
					(end 291.106606 -265.52144)
				)
				(arc
					(start 291.106606 -265.1125)
					(mid 291.091727 -265.076579)
					(end 291.055806 -265.0617)
				)
				(arc
					(start 289.656266 -265.0617)
					(mid 289.620345 -265.076579)
					(end 289.605466 -265.1125)
				)
			)
		)
	)
	(zone
		(layers "In1.Cu" "In2.Cu")
		(hatch none 0.5)
		(connect_pads
			(clearance 0)
		)
		(min_thickness 0.25)
		(keepout
			(tracks not_allowed)
			(vias allowed)
			(pads allowed)
			(copperpour not_allowed)
			(footprints allowed)
		)
		(placement
			(enabled no)
			(sheetname "")
		)
		(fill yes
			(thermal_gap 0.5)
			(thermal_bridge_width 0.5)
			(island_removal_mode 0)
		)
		(polygon
			(pts
				(arc
					(start 297.149266 -195.821554)
					(mid 297.164145 -195.857475)
					(end 297.200066 -195.872354)
				)
				(arc
					(start 298.599606 -195.872354)
					(mid 298.635527 -195.857475)
					(end 298.650406 -195.821554)
				)
				(arc
					(start 298.650406 -195.412614)
					(mid 298.635527 -195.376693)
					(end 298.599606 -195.361814)
				)
				(arc
					(start 297.200066 -195.361814)
					(mid 297.164145 -195.376693)
					(end 297.149266 -195.412614)
				)
			)
		)
	)
	(zone
		(layers "In1.Cu" "In2.Cu")
		(hatch none 0.5)
		(connect_pads
			(clearance 0)
		)
		(min_thickness 0.25)
		(keepout
			(tracks not_allowed)
			(vias allowed)
			(pads allowed)
			(copperpour not_allowed)
			(footprints allowed)
		)
		(placement
			(enabled no)
			(sheetname "")
		)
		(fill yes
			(thermal_gap 0.5)
			(thermal_bridge_width 0.5)
			(island_removal_mode 0)
		)
		(polygon
			(pts
				(arc
					(start 417.646866 -200.071482)
					(mid 417.661745 -200.107403)
					(end 417.697666 -200.122282)
				)
				(arc
					(start 419.097206 -200.122282)
					(mid 419.133127 -200.107403)
					(end 419.148006 -200.071482)
				)
				(arc
					(start 419.148006 -199.662542)
					(mid 419.133127 -199.626621)
					(end 419.097206 -199.611742)
				)
				(arc
					(start 417.697666 -199.611742)
					(mid 417.661745 -199.626621)
					(end 417.646866 -199.662542)
				)
			)
		)
	)
	(zone
		(layers "In1.Cu" "In2.Cu")
		(hatch none 0.5)
		(connect_pads
			(clearance 0)
		)
		(min_thickness 0.25)
		(keepout
			(tracks not_allowed)
			(vias allowed)
			(pads allowed)
			(copperpour not_allowed)
			(footprints allowed)
		)
		(placement
			(enabled no)
			(sheetname "")
		)
		(fill yes
			(thermal_gap 0.5)
			(thermal_bridge_width 0.5)
			(island_removal_mode 0)
		)
		(polygon
			(pts
				(arc
					(start 199.881998 -233.22153)
					(mid 199.896877 -233.257451)
					(end 199.932798 -233.27233)
				)
				(arc
					(start 201.332338 -233.27233)
					(mid 201.368259 -233.257451)
					(end 201.383138 -233.22153)
				)
				(arc
					(start 201.383138 -232.81259)
					(mid 201.368259 -232.776669)
					(end 201.332338 -232.76179)
				)
				(arc
					(start 199.932798 -232.76179)
					(mid 199.896877 -232.776669)
					(end 199.881998 -232.81259)
				)
			)
		)
	)
	(zone
		(layers "In1.Cu" "In2.Cu")
		(hatch none 0.5)
		(connect_pads
			(clearance 0)
		)
		(min_thickness 0.25)
		(keepout
			(tracks not_allowed)
			(vias allowed)
			(pads allowed)
			(copperpour not_allowed)
			(footprints allowed)
		)
		(placement
			(enabled no)
			(sheetname "")
		)
		(fill yes
			(thermal_gap 0.5)
			(thermal_bridge_width 0.5)
			(island_removal_mode 0)
		)
		(polygon
			(pts
				(arc
					(start 45.10913 -269.771368)
					(mid 45.124009 -269.807289)
					(end 45.15993 -269.822168)
				)
				(arc
					(start 46.55947 -269.822168)
					(mid 46.595391 -269.807289)
					(end 46.61027 -269.771368)
				)
				(arc
					(start 46.61027 -269.362428)
					(mid 46.595391 -269.326507)
					(end 46.55947 -269.311628)
				)
				(arc
					(start 45.15993 -269.311628)
					(mid 45.124009 -269.326507)
					(end 45.10913 -269.362428)
				)
			)
		)
	)
	(zone
		(layers "In1.Cu" "In2.Cu")
		(hatch none 0.5)
		(connect_pads
			(clearance 0)
		)
		(min_thickness 0.25)
		(keepout
			(tracks not_allowed)
			(vias allowed)
			(pads allowed)
			(copperpour not_allowed)
			(footprints allowed)
		)
		(placement
			(enabled no)
			(sheetname "")
		)
		(fill yes
			(thermal_gap 0.5)
			(thermal_bridge_width 0.5)
			(island_removal_mode 0)
		)
		(polygon
			(pts
				(arc
					(start 436.178198 -261.271512)
					(mid 436.193077 -261.307433)
					(end 436.228998 -261.322312)
				)
				(arc
					(start 437.628538 -261.322312)
					(mid 437.664459 -261.307433)
					(end 437.679338 -261.271512)
				)
				(arc
					(start 437.679338 -260.862572)
					(mid 437.664459 -260.826651)
					(end 437.628538 -260.811772)
				)
				(arc
					(start 436.228998 -260.811772)
					(mid 436.193077 -260.826651)
					(end 436.178198 -260.862572)
				)
			)
		)
	)
	(zone
		(layers "In1.Cu" "In2.Cu")
		(hatch none 0.5)
		(connect_pads
			(clearance 0)
		)
		(min_thickness 0.25)
		(keepout
			(tracks not_allowed)
			(vias allowed)
			(pads allowed)
			(copperpour not_allowed)
			(footprints allowed)
		)
		(placement
			(enabled no)
			(sheetname "")
		)
		(fill yes
			(thermal_gap 0.5)
			(thermal_bridge_width 0.5)
			(island_removal_mode 0)
		)
		(polygon
			(pts
				(arc
					(start 255.330198 -221.321376)
					(mid 255.345077 -221.357297)
					(end 255.380998 -221.372176)
				)
				(arc
					(start 256.780538 -221.372176)
					(mid 256.816459 -221.357297)
					(end 256.831338 -221.321376)
				)
				(arc
					(start 256.831338 -220.912436)
					(mid 256.816459 -220.876515)
					(end 256.780538 -220.861636)
				)
				(arc
					(start 255.380998 -220.861636)
					(mid 255.345077 -220.876515)
					(end 255.330198 -220.912436)
				)
			)
		)
	)
	(zone
		(layers "In1.Cu" "In2.Cu")
		(hatch none 0.5)
		(connect_pads
			(clearance 0)
		)
		(min_thickness 0.25)
		(keepout
			(tracks not_allowed)
			(vias allowed)
			(pads allowed)
			(copperpour not_allowed)
			(footprints allowed)
		)
		(placement
			(enabled no)
			(sheetname "")
		)
		(fill yes
			(thermal_gap 0.5)
			(thermal_bridge_width 0.5)
			(island_removal_mode 0)
		)
		(polygon
			(pts
				(arc
					(start 413.546798 -284.221428)
					(mid 413.561677 -284.257349)
					(end 413.597598 -284.272228)
				)
				(arc
					(start 414.997138 -284.272228)
					(mid 415.033059 -284.257349)
					(end 415.047938 -284.221428)
				)
				(arc
					(start 415.047938 -283.812488)
					(mid 415.033059 -283.776567)
					(end 414.997138 -283.761688)
				)
				(arc
					(start 413.597598 -283.761688)
					(mid 413.561677 -283.776567)
					(end 413.546798 -283.812488)
				)
			)
		)
	)
	(zone
		(layers "In1.Cu" "In2.Cu")
		(hatch none 0.5)
		(connect_pads
			(clearance 0)
		)
		(min_thickness 0.25)
		(keepout
			(tracks not_allowed)
			(vias allowed)
			(pads allowed)
			(copperpour not_allowed)
			(footprints allowed)
		)
		(placement
			(enabled no)
			(sheetname "")
		)
		(fill yes
			(thermal_gap 0.5)
			(thermal_bridge_width 0.5)
			(island_removal_mode 0)
		)
		(polygon
			(pts
				(arc
					(start 173.15053 -280.821384)
					(mid 173.165409 -280.857305)
					(end 173.20133 -280.872184)
				)
				(arc
					(start 174.60087 -280.872184)
					(mid 174.636791 -280.857305)
					(end 174.65167 -280.821384)
				)
				(arc
					(start 174.65167 -280.412444)
					(mid 174.636791 -280.376523)
					(end 174.60087 -280.361644)
				)
				(arc
					(start 173.20133 -280.361644)
					(mid 173.165409 -280.376523)
					(end 173.15053 -280.412444)
				)
			)
		)
	)
	(zone
		(layers "In1.Cu" "In2.Cu")
		(hatch none 0.5)
		(connect_pads
			(clearance 0)
		)
		(min_thickness 0.25)
		(keepout
			(tracks not_allowed)
			(vias allowed)
			(pads allowed)
			(copperpour not_allowed)
			(footprints allowed)
		)
		(placement
			(enabled no)
			(sheetname "")
		)
		(fill yes
			(thermal_gap 0.5)
			(thermal_bridge_width 0.5)
			(island_removal_mode 0)
		)
		(polygon
			(pts
				(arc
					(start 274.517866 -237.471458)
					(mid 274.532745 -237.507379)
					(end 274.568666 -237.522258)
				)
				(arc
					(start 275.968206 -237.522258)
					(mid 276.004127 -237.507379)
					(end 276.019006 -237.471458)
				)
				(arc
					(start 276.019006 -237.062518)
					(mid 276.004127 -237.026597)
					(end 275.968206 -237.011718)
				)
				(arc
					(start 274.568666 -237.011718)
					(mid 274.532745 -237.026597)
					(end 274.517866 -237.062518)
				)
			)
		)
	)
	(zone
		(layers "In1.Cu" "In2.Cu")
		(hatch none 0.5)
		(connect_pads
			(clearance 0)
		)
		(min_thickness 0.25)
		(keepout
			(tracks not_allowed)
			(vias allowed)
			(pads allowed)
			(copperpour not_allowed)
			(footprints allowed)
		)
		(placement
			(enabled no)
			(sheetname "")
		)
		(fill yes
			(thermal_gap 0.5)
			(thermal_bridge_width 0.5)
			(island_removal_mode 0)
		)
		(polygon
			(pts
				(arc
					(start 7.39013 -305.471322)
					(mid 7.405009 -305.507243)
					(end 7.44093 -305.522122)
				)
				(arc
					(start 8.84047 -305.522122)
					(mid 8.876391 -305.507243)
					(end 8.89127 -305.471322)
				)
				(arc
					(start 8.89127 -305.062382)
					(mid 8.876391 -305.026461)
					(end 8.84047 -305.011582)
				)
				(arc
					(start 7.44093 -305.011582)
					(mid 7.405009 -305.026461)
					(end 7.39013 -305.062382)
				)
			)
		)
	)
	(zone
		(layers "In1.Cu" "In2.Cu")
		(hatch none 0.5)
		(connect_pads
			(clearance 0)
		)
		(min_thickness 0.25)
		(keepout
			(tracks not_allowed)
			(vias allowed)
			(pads allowed)
			(copperpour not_allowed)
			(footprints allowed)
		)
		(placement
			(enabled no)
			(sheetname "")
		)
		(fill yes
			(thermal_gap 0.5)
			(thermal_bridge_width 0.5)
			(island_removal_mode 0)
		)
		(polygon
			(pts
				(arc
					(start 312.236866 -208.571338)
					(mid 312.251745 -208.607259)
					(end 312.287666 -208.622138)
				)
				(arc
					(start 313.687206 -208.622138)
					(mid 313.723127 -208.607259)
					(end 313.738006 -208.571338)
				)
				(arc
					(start 313.738006 -208.162398)
					(mid 313.723127 -208.126477)
					(end 313.687206 -208.111598)
				)
				(arc
					(start 312.287666 -208.111598)
					(mid 312.251745 -208.126477)
					(end 312.236866 -208.162398)
				)
			)
		)
	)
	(zone
		(layers "In1.Cu" "In2.Cu")
		(hatch none 0.5)
		(connect_pads
			(clearance 0)
		)
		(min_thickness 0.25)
		(keepout
			(tracks not_allowed)
			(vias allowed)
			(pads allowed)
			(copperpour not_allowed)
			(footprints allowed)
		)
		(placement
			(enabled no)
			(sheetname "")
		)
		(fill yes
			(thermal_gap 0.5)
			(thermal_bridge_width 0.5)
			(island_removal_mode 0)
		)
		(polygon
			(pts
				(arc
					(start 210.86953 -243.421408)
					(mid 210.884409 -243.457329)
					(end 210.92033 -243.472208)
				)
				(arc
					(start 212.31987 -243.472208)
					(mid 212.355791 -243.457329)
					(end 212.37067 -243.421408)
				)
				(arc
					(start 212.37067 -243.012468)
					(mid 212.355791 -242.976547)
					(end 212.31987 -242.961668)
				)
				(arc
					(start 210.92033 -242.961668)
					(mid 210.884409 -242.976547)
					(end 210.86953 -243.012468)
				)
			)
		)
	)
	(zone
		(layers "In1.Cu" "In2.Cu")
		(hatch none 0.5)
		(connect_pads
			(clearance 0)
		)
		(min_thickness 0.25)
		(keepout
			(tracks not_allowed)
			(vias allowed)
			(pads allowed)
			(copperpour not_allowed)
			(footprints allowed)
		)
		(placement
			(enabled no)
			(sheetname "")
		)
		(fill yes
			(thermal_gap 0.5)
			(thermal_bridge_width 0.5)
			(island_removal_mode 0)
		)
		(polygon
			(pts
				(arc
					(start 11.490198 -234.921298)
					(mid 11.505077 -234.957219)
					(end 11.540998 -234.972098)
				)
				(arc
					(start 12.940538 -234.972098)
					(mid 12.976459 -234.957219)
					(end 12.991338 -234.921298)
				)
				(arc
					(start 12.991338 -234.512358)
					(mid 12.976459 -234.476437)
					(end 12.940538 -234.461558)
				)
				(arc
					(start 11.540998 -234.461558)
					(mid 11.505077 -234.476437)
					(end 11.490198 -234.512358)
				)
			)
		)
	)
	(zone
		(layers "In1.Cu" "In2.Cu")
		(hatch none 0.5)
		(connect_pads
			(clearance 0)
		)
		(min_thickness 0.25)
		(keepout
			(tracks not_allowed)
			(vias allowed)
			(pads allowed)
			(copperpour not_allowed)
			(footprints allowed)
		)
		(placement
			(enabled no)
			(sheetname "")
		)
		(fill yes
			(thermal_gap 0.5)
			(thermal_bridge_width 0.5)
			(island_removal_mode 0)
		)
		(polygon
			(pts
				(arc
					(start 255.330198 -241.721386)
					(mid 255.345077 -241.757307)
					(end 255.380998 -241.772186)
				)
				(arc
					(start 256.780538 -241.772186)
					(mid 256.816459 -241.757307)
					(end 256.831338 -241.721386)
				)
				(arc
					(start 256.831338 -241.312446)
					(mid 256.816459 -241.276525)
					(end 256.780538 -241.261646)
				)
				(arc
					(start 255.380998 -241.261646)
					(mid 255.345077 -241.276525)
					(end 255.330198 -241.312446)
				)
			)
		)
	)
	(zone
		(layers "In1.Cu" "In2.Cu")
		(hatch none 0.5)
		(connect_pads
			(clearance 0)
		)
		(min_thickness 0.25)
		(keepout
			(tracks not_allowed)
			(vias allowed)
			(pads allowed)
			(copperpour not_allowed)
			(footprints allowed)
		)
		(placement
			(enabled no)
			(sheetname "")
		)
		(fill yes
			(thermal_gap 0.5)
			(thermal_bridge_width 0.5)
			(island_removal_mode 0)
		)
		(polygon
			(pts
				(arc
					(start 56.752998 -246.821452)
					(mid 56.767877 -246.857373)
					(end 56.803798 -246.872252)
				)
				(arc
					(start 58.203338 -246.872252)
					(mid 58.239259 -246.857373)
					(end 58.254138 -246.821452)
				)
				(arc
					(start 58.254138 -246.412512)
					(mid 58.239259 -246.376591)
					(end 58.203338 -246.361712)
				)
				(arc
					(start 56.803798 -246.361712)
					(mid 56.767877 -246.376591)
					(end 56.752998 -246.412512)
				)
			)
		)
	)
	(zone
		(layers "In1.Cu" "In2.Cu")
		(hatch none 0.5)
		(connect_pads
			(clearance 0)
		)
		(min_thickness 0.25)
		(keepout
			(tracks not_allowed)
			(vias allowed)
			(pads allowed)
			(copperpour not_allowed)
			(footprints allowed)
		)
		(placement
			(enabled no)
			(sheetname "")
		)
		(fill yes
			(thermal_gap 0.5)
			(thermal_bridge_width 0.5)
			(island_removal_mode 0)
		)
		(polygon
			(pts
				(arc
					(start 293.049198 -286.771334)
					(mid 293.064077 -286.807255)
					(end 293.099998 -286.822134)
				)
				(arc
					(start 294.499538 -286.822134)
					(mid 294.535459 -286.807255)
					(end 294.550338 -286.771334)
				)
				(arc
					(start 294.550338 -286.362394)
					(mid 294.535459 -286.326473)
					(end 294.499538 -286.311594)
				)
				(arc
					(start 293.099998 -286.311594)
					(mid 293.064077 -286.326473)
					(end 293.049198 -286.362394)
				)
			)
		)
	)
	(zone
		(layers "In1.Cu" "In2.Cu")
		(hatch none 0.5)
		(connect_pads
			(clearance 0)
		)
		(min_thickness 0.25)
		(keepout
			(tracks not_allowed)
			(vias allowed)
			(pads allowed)
			(copperpour not_allowed)
			(footprints allowed)
		)
		(placement
			(enabled no)
			(sheetname "")
		)
		(fill yes
			(thermal_gap 0.5)
			(thermal_bridge_width 0.5)
			(island_removal_mode 0)
		)
		(polygon
			(pts
				(arc
					(start 26.577798 -218.77147)
					(mid 26.592677 -218.807391)
					(end 26.628598 -218.82227)
				)
				(arc
					(start 28.028138 -218.82227)
					(mid 28.064059 -218.807391)
					(end 28.078938 -218.77147)
				)
				(arc
					(start 28.078938 -218.36253)
					(mid 28.064059 -218.326609)
					(end 28.028138 -218.31173)
				)
				(arc
					(start 26.628598 -218.31173)
					(mid 26.592677 -218.326609)
					(end 26.577798 -218.36253)
				)
			)
		)
	)
	(zone
		(layers "In1.Cu" "In2.Cu")
		(hatch none 0.5)
		(connect_pads
			(clearance 0)
		)
		(min_thickness 0.25)
		(keepout
			(tracks not_allowed)
			(vias allowed)
			(pads allowed)
			(copperpour not_allowed)
			(footprints allowed)
		)
		(placement
			(enabled no)
			(sheetname "")
		)
		(fill yes
			(thermal_gap 0.5)
			(thermal_bridge_width 0.5)
			(island_removal_mode 0)
		)
		(polygon
			(pts
				(arc
					(start 56.752998 -272.321528)
					(mid 56.767877 -272.357449)
					(end 56.803798 -272.372328)
				)
				(arc
					(start 58.203338 -272.372328)
					(mid 58.239259 -272.357449)
					(end 58.254138 -272.321528)
				)
				(arc
					(start 58.254138 -271.912588)
					(mid 58.239259 -271.876667)
					(end 58.203338 -271.861788)
				)
				(arc
					(start 56.803798 -271.861788)
					(mid 56.767877 -271.876667)
					(end 56.752998 -271.912588)
				)
			)
		)
	)
	(zone
		(layers "In1.Cu" "In2.Cu")
		(hatch none 0.5)
		(connect_pads
			(clearance 0)
		)
		(min_thickness 0.25)
		(keepout
			(tracks not_allowed)
			(vias allowed)
			(pads allowed)
			(copperpour not_allowed)
			(footprints allowed)
		)
		(placement
			(enabled no)
			(sheetname "")
		)
		(fill yes
			(thermal_gap 0.5)
			(thermal_bridge_width 0.5)
			(island_removal_mode 0)
		)
		(polygon
			(pts
				(arc
					(start 277.961598 -241.721386)
					(mid 277.976477 -241.757307)
					(end 278.012398 -241.772186)
				)
				(arc
					(start 279.411938 -241.772186)
					(mid 279.447859 -241.757307)
					(end 279.462738 -241.721386)
				)
				(arc
					(start 279.462738 -241.312446)
					(mid 279.447859 -241.276525)
					(end 279.411938 -241.261646)
				)
				(arc
					(start 278.012398 -241.261646)
					(mid 277.976477 -241.276525)
					(end 277.961598 -241.312446)
				)
			)
		)
	)
	(zone
		(layers "In1.Cu" "In2.Cu")
		(hatch none 0.5)
		(connect_pads
			(clearance 0)
		)
		(min_thickness 0.25)
		(keepout
			(tracks not_allowed)
			(vias allowed)
			(pads allowed)
			(copperpour not_allowed)
			(footprints allowed)
		)
		(placement
			(enabled no)
			(sheetname "")
		)
		(fill yes
			(thermal_gap 0.5)
			(thermal_bridge_width 0.5)
			(island_removal_mode 0)
		)
		(polygon
			(pts
				(arc
					(start 285.505398 -266.371324)
					(mid 285.520277 -266.407245)
					(end 285.556198 -266.422124)
				)
				(arc
					(start 286.955738 -266.422124)
					(mid 286.991659 -266.407245)
					(end 287.006538 -266.371324)
				)
				(arc
					(start 287.006538 -265.962384)
					(mid 286.991659 -265.926463)
					(end 286.955738 -265.911584)
				)
				(arc
					(start 285.556198 -265.911584)
					(mid 285.520277 -265.926463)
					(end 285.505398 -265.962384)
				)
			)
		)
	)
	(zone
		(layers "In1.Cu" "In2.Cu")
		(hatch none 0.5)
		(connect_pads
			(clearance 0)
		)
		(min_thickness 0.25)
		(keepout
			(tracks not_allowed)
			(vias allowed)
			(pads allowed)
			(copperpour not_allowed)
			(footprints allowed)
		)
		(placement
			(enabled no)
			(sheetname "")
		)
		(fill yes
			(thermal_gap 0.5)
			(thermal_bridge_width 0.5)
			(island_removal_mode 0)
		)
		(polygon
			(pts
				(arc
					(start 413.546798 -196.671438)
					(mid 413.561677 -196.707359)
					(end 413.597598 -196.722238)
				)
				(arc
					(start 414.997138 -196.722238)
					(mid 415.033059 -196.707359)
					(end 415.047938 -196.671438)
				)
				(arc
					(start 415.047938 -196.262498)
					(mid 415.033059 -196.226577)
					(end 414.997138 -196.211698)
				)
				(arc
					(start 413.597598 -196.211698)
					(mid 413.561677 -196.226577)
					(end 413.546798 -196.262498)
				)
			)
		)
	)
	(zone
		(layers "In1.Cu" "In2.Cu")
		(hatch none 0.5)
		(connect_pads
			(clearance 0)
		)
		(min_thickness 0.25)
		(keepout
			(tracks not_allowed)
			(vias allowed)
			(pads allowed)
			(copperpour not_allowed)
			(footprints allowed)
		)
		(placement
			(enabled no)
			(sheetname "")
		)
		(fill yes
			(thermal_gap 0.5)
			(thermal_bridge_width 0.5)
			(island_removal_mode 0)
		)
		(polygon
			(pts
				(arc
					(start 436.178198 -271.47139)
					(mid 436.193077 -271.507311)
					(end 436.228998 -271.52219)
				)
				(arc
					(start 437.628538 -271.52219)
					(mid 437.664459 -271.507311)
					(end 437.679338 -271.47139)
				)
				(arc
					(start 437.679338 -271.06245)
					(mid 437.664459 -271.026529)
					(end 437.628538 -271.01165)
				)
				(arc
					(start 436.228998 -271.01165)
					(mid 436.193077 -271.026529)
					(end 436.178198 -271.06245)
				)
			)
		)
	)
	(zone
		(layers "In1.Cu" "In2.Cu")
		(hatch none 0.5)
		(connect_pads
			(clearance 0)
		)
		(min_thickness 0.25)
		(keepout
			(tracks not_allowed)
			(vias allowed)
			(pads allowed)
			(copperpour not_allowed)
			(footprints allowed)
		)
		(placement
			(enabled no)
			(sheetname "")
		)
		(fill yes
			(thermal_gap 0.5)
			(thermal_bridge_width 0.5)
			(island_removal_mode 0)
		)
		(polygon
			(pts
				(arc
					(start 45.10913 -277.42134)
					(mid 45.124009 -277.457261)
					(end 45.15993 -277.47214)
				)
				(arc
					(start 46.55947 -277.47214)
					(mid 46.595391 -277.457261)
					(end 46.61027 -277.42134)
				)
				(arc
					(start 46.61027 -277.0124)
					(mid 46.595391 -276.976479)
					(end 46.55947 -276.9616)
				)
				(arc
					(start 45.15993 -276.9616)
					(mid 45.124009 -276.976479)
					(end 45.10913 -277.0124)
				)
			)
		)
	)
	(zone
		(layers "In1.Cu" "In2.Cu")
		(hatch none 0.5)
		(connect_pads
			(clearance 0)
		)
		(min_thickness 0.25)
		(keepout
			(tracks not_allowed)
			(vias allowed)
			(pads allowed)
			(copperpour not_allowed)
			(footprints allowed)
		)
		(placement
			(enabled no)
			(sheetname "")
		)
		(fill yes
			(thermal_gap 0.5)
			(thermal_bridge_width 0.5)
			(island_removal_mode 0)
		)
		(polygon
			(pts
				(arc
					(start 203.32573 -282.521406)
					(mid 203.340609 -282.557327)
					(end 203.37653 -282.572206)
				)
				(arc
					(start 204.77607 -282.572206)
					(mid 204.811991 -282.557327)
					(end 204.82687 -282.521406)
				)
				(arc
					(start 204.82687 -282.112466)
					(mid 204.811991 -282.076545)
					(end 204.77607 -282.061666)
				)
				(arc
					(start 203.37653 -282.061666)
					(mid 203.340609 -282.076545)
					(end 203.32573 -282.112466)
				)
			)
		)
	)
	(zone
		(layers "In1.Cu" "In2.Cu")
		(hatch none 0.5)
		(connect_pads
			(clearance 0)
		)
		(min_thickness 0.25)
		(keepout
			(tracks not_allowed)
			(vias allowed)
			(pads allowed)
			(copperpour not_allowed)
			(footprints allowed)
		)
		(placement
			(enabled no)
			(sheetname "")
		)
		(fill yes
			(thermal_gap 0.5)
			(thermal_bridge_width 0.5)
			(island_removal_mode 0)
		)
		(polygon
			(pts
				(arc
					(start 270.417798 -277.42134)
					(mid 270.432677 -277.457261)
					(end 270.468598 -277.47214)
				)
				(arc
					(start 271.868138 -277.47214)
					(mid 271.904059 -277.457261)
					(end 271.918938 -277.42134)
				)
				(arc
					(start 271.918938 -277.0124)
					(mid 271.904059 -276.976479)
					(end 271.868138 -276.9616)
				)
				(arc
					(start 270.468598 -276.9616)
					(mid 270.432677 -276.976479)
					(end 270.417798 -277.0124)
				)
			)
		)
	)
	(zone
		(layers "In1.Cu" "In2.Cu")
		(hatch none 0.5)
		(connect_pads
			(clearance 0)
		)
		(min_thickness 0.25)
		(keepout
			(tracks not_allowed)
			(vias allowed)
			(pads allowed)
			(copperpour not_allowed)
			(footprints allowed)
		)
		(placement
			(enabled no)
			(sheetname "")
		)
		(fill yes
			(thermal_gap 0.5)
			(thermal_bridge_width 0.5)
			(island_removal_mode 0)
		)
		(polygon
			(pts
				(arc
					(start 165.60673 -213.671404)
					(mid 165.621609 -213.707325)
					(end 165.65753 -213.722204)
				)
				(arc
					(start 167.05707 -213.722204)
					(mid 167.092991 -213.707325)
					(end 167.10787 -213.671404)
				)
				(arc
					(start 167.10787 -213.262464)
					(mid 167.092991 -213.226543)
					(end 167.05707 -213.211664)
				)
				(arc
					(start 165.65753 -213.211664)
					(mid 165.621609 -213.226543)
					(end 165.60673 -213.262464)
				)
			)
		)
	)
	(zone
		(layers "In1.Cu" "In2.Cu")
		(hatch none 0.5)
		(connect_pads
			(clearance 0)
		)
		(min_thickness 0.25)
		(keepout
			(tracks not_allowed)
			(vias allowed)
			(pads allowed)
			(copperpour not_allowed)
			(footprints allowed)
		)
		(placement
			(enabled no)
			(sheetname "")
		)
		(fill yes
			(thermal_gap 0.5)
			(thermal_bridge_width 0.5)
			(island_removal_mode 0)
		)
		(polygon
			(pts
				(arc
					(start 26.577798 -283.371544)
					(mid 26.592677 -283.407465)
					(end 26.628598 -283.422344)
				)
				(arc
					(start 28.028138 -283.422344)
					(mid 28.064059 -283.407465)
					(end 28.078938 -283.371544)
				)
				(arc
					(start 28.078938 -282.962604)
					(mid 28.064059 -282.926683)
					(end 28.028138 -282.911804)
				)
				(arc
					(start 26.628598 -282.911804)
					(mid 26.592677 -282.926683)
					(end 26.577798 -282.962604)
				)
			)
		)
	)
	(zone
		(layers "In1.Cu" "In2.Cu")
		(hatch none 0.5)
		(connect_pads
			(clearance 0)
		)
		(min_thickness 0.25)
		(keepout
			(tracks not_allowed)
			(vias allowed)
			(pads allowed)
			(copperpour not_allowed)
			(footprints allowed)
		)
		(placement
			(enabled no)
			(sheetname "")
		)
		(fill yes
			(thermal_gap 0.5)
			(thermal_bridge_width 0.5)
			(island_removal_mode 0)
		)
		(polygon
			(pts
				(arc
					(start 199.881998 -267.221462)
					(mid 199.896877 -267.257383)
					(end 199.932798 -267.272262)
				)
				(arc
					(start 201.332338 -267.272262)
					(mid 201.368259 -267.257383)
					(end 201.383138 -267.221462)
				)
				(arc
					(start 201.383138 -266.812522)
					(mid 201.368259 -266.776601)
					(end 201.332338 -266.761722)
				)
				(arc
					(start 199.932798 -266.761722)
					(mid 199.896877 -266.776601)
					(end 199.881998 -266.812522)
				)
			)
		)
	)
	(zone
		(layers "In1.Cu" "In2.Cu")
		(hatch none 0.5)
		(connect_pads
			(clearance 0)
		)
		(min_thickness 0.25)
		(keepout
			(tracks not_allowed)
			(vias allowed)
			(pads allowed)
			(copperpour not_allowed)
			(footprints allowed)
		)
		(placement
			(enabled no)
			(sheetname "")
		)
		(fill yes
			(thermal_gap 0.5)
			(thermal_bridge_width 0.5)
			(island_removal_mode 0)
		)
		(polygon
			(pts
				(arc
					(start 413.546798 -221.321376)
					(mid 413.561677 -221.357297)
					(end 413.597598 -221.372176)
				)
				(arc
					(start 414.997138 -221.372176)
					(mid 415.033059 -221.357297)
					(end 415.047938 -221.321376)
				)
				(arc
					(start 415.047938 -220.912436)
					(mid 415.033059 -220.876515)
					(end 414.997138 -220.861636)
				)
				(arc
					(start 413.597598 -220.861636)
					(mid 413.561677 -220.876515)
					(end 413.546798 -220.912436)
				)
			)
		)
	)
	(zone
		(layers "In1.Cu" "In2.Cu")
		(hatch none 0.5)
		(connect_pads
			(clearance 0)
		)
		(min_thickness 0.25)
		(keepout
			(tracks not_allowed)
			(vias allowed)
			(pads allowed)
			(copperpour not_allowed)
			(footprints allowed)
		)
		(placement
			(enabled no)
			(sheetname "")
		)
		(fill yes
			(thermal_gap 0.5)
			(thermal_bridge_width 0.5)
			(island_removal_mode 0)
		)
		(polygon
			(pts
				(arc
					(start 300.592998 -244.271292)
					(mid 300.607877 -244.307213)
					(end 300.643798 -244.322092)
				)
				(arc
					(start 302.043338 -244.322092)
					(mid 302.079259 -244.307213)
					(end 302.094138 -244.271292)
				)
				(arc
					(start 302.094138 -243.862352)
					(mid 302.079259 -243.826431)
					(end 302.043338 -243.811552)
				)
				(arc
					(start 300.643798 -243.811552)
					(mid 300.607877 -243.826431)
					(end 300.592998 -243.862352)
				)
			)
		)
	)
	(zone
		(layers "In1.Cu" "In2.Cu")
		(hatch none 0.5)
		(connect_pads
			(clearance 0)
		)
		(min_thickness 0.25)
		(keepout
			(tracks not_allowed)
			(vias allowed)
			(pads allowed)
			(copperpour not_allowed)
			(footprints allowed)
		)
		(placement
			(enabled no)
			(sheetname "")
		)
		(fill yes
			(thermal_gap 0.5)
			(thermal_bridge_width 0.5)
			(island_removal_mode 0)
		)
		(polygon
			(pts
				(arc
					(start 41.665398 -203.471526)
					(mid 41.680277 -203.507447)
					(end 41.716198 -203.522326)
				)
				(arc
					(start 43.115738 -203.522326)
					(mid 43.151659 -203.507447)
					(end 43.166538 -203.471526)
				)
				(arc
					(start 43.166538 -203.062586)
					(mid 43.151659 -203.026665)
					(end 43.115738 -203.011786)
				)
				(arc
					(start 41.716198 -203.011786)
					(mid 41.680277 -203.026665)
					(end 41.665398 -203.062586)
				)
			)
		)
	)
	(zone
		(layers "In1.Cu" "In2.Cu")
		(hatch none 0.5)
		(connect_pads
			(clearance 0)
		)
		(min_thickness 0.25)
		(keepout
			(tracks not_allowed)
			(vias allowed)
			(pads allowed)
			(copperpour not_allowed)
			(footprints allowed)
		)
		(placement
			(enabled no)
			(sheetname "")
		)
		(fill yes
			(thermal_gap 0.5)
			(thermal_bridge_width 0.5)
			(island_removal_mode 0)
		)
		(polygon
			(pts
				(arc
					(start 312.236866 -231.521508)
					(mid 312.251745 -231.557429)
					(end 312.287666 -231.572308)
				)
				(arc
					(start 313.687206 -231.572308)
					(mid 313.723127 -231.557429)
					(end 313.738006 -231.521508)
				)
				(arc
					(start 313.738006 -231.112568)
					(mid 313.723127 -231.076647)
					(end 313.687206 -231.061768)
				)
				(arc
					(start 312.287666 -231.061768)
					(mid 312.251745 -231.076647)
					(end 312.236866 -231.112568)
				)
			)
		)
	)
	(zone
		(layers "In1.Cu" "In2.Cu")
		(hatch none 0.5)
		(connect_pads
			(clearance 0)
		)
		(min_thickness 0.25)
		(keepout
			(tracks not_allowed)
			(vias allowed)
			(pads allowed)
			(copperpour not_allowed)
			(footprints allowed)
		)
		(placement
			(enabled no)
			(sheetname "")
		)
		(fill yes
			(thermal_gap 0.5)
			(thermal_bridge_width 0.5)
			(island_removal_mode 0)
		)
		(polygon
			(pts
				(arc
					(start 34.121598 -309.721504)
					(mid 34.136477 -309.757425)
					(end 34.172398 -309.772304)
				)
				(arc
					(start 35.571938 -309.772304)
					(mid 35.607859 -309.757425)
					(end 35.622738 -309.721504)
				)
				(arc
					(start 35.622738 -309.312564)
					(mid 35.607859 -309.276643)
					(end 35.571938 -309.261764)
				)
				(arc
					(start 34.172398 -309.261764)
					(mid 34.136477 -309.276643)
					(end 34.121598 -309.312564)
				)
			)
		)
	)
	(zone
		(layers "In1.Cu" "In2.Cu")
		(hatch none 0.5)
		(connect_pads
			(clearance 0)
		)
		(min_thickness 0.25)
		(keepout
			(tracks not_allowed)
			(vias allowed)
			(pads allowed)
			(copperpour not_allowed)
			(footprints allowed)
		)
		(placement
			(enabled no)
			(sheetname "")
		)
		(fill yes
			(thermal_gap 0.5)
			(thermal_bridge_width 0.5)
			(island_removal_mode 0)
		)
		(polygon
			(pts
				(arc
					(start 428.634398 -273.171412)
					(mid 428.649277 -273.207333)
					(end 428.685198 -273.222212)
				)
				(arc
					(start 430.084738 -273.222212)
					(mid 430.120659 -273.207333)
					(end 430.135538 -273.171412)
				)
				(arc
					(start 430.135538 -272.762472)
					(mid 430.120659 -272.726551)
					(end 430.084738 -272.711672)
				)
				(arc
					(start 428.685198 -272.711672)
					(mid 428.649277 -272.726551)
					(end 428.634398 -272.762472)
				)
			)
		)
	)
	(zone
		(layers "In1.Cu" "In2.Cu")
		(hatch none 0.5)
		(connect_pads
			(clearance 0)
		)
		(min_thickness 0.25)
		(keepout
			(tracks not_allowed)
			(vias allowed)
			(pads allowed)
			(copperpour not_allowed)
			(footprints allowed)
		)
		(placement
			(enabled no)
			(sheetname "")
		)
		(fill yes
			(thermal_gap 0.5)
			(thermal_bridge_width 0.5)
			(island_removal_mode 0)
		)
		(polygon
			(pts
				(arc
					(start 308.136798 -196.671438)
					(mid 308.151677 -196.707359)
					(end 308.187598 -196.722238)
				)
				(arc
					(start 309.587138 -196.722238)
					(mid 309.623059 -196.707359)
					(end 309.637938 -196.671438)
				)
				(arc
					(start 309.637938 -196.262498)
					(mid 309.623059 -196.226577)
					(end 309.587138 -196.211698)
				)
				(arc
					(start 308.187598 -196.211698)
					(mid 308.151677 -196.226577)
					(end 308.136798 -196.262498)
				)
			)
		)
	)
	(zone
		(layers "In1.Cu" "In2.Cu")
		(hatch none 0.5)
		(connect_pads
			(clearance 0)
		)
		(min_thickness 0.25)
		(keepout
			(tracks not_allowed)
			(vias allowed)
			(pads allowed)
			(copperpour not_allowed)
			(footprints allowed)
		)
		(placement
			(enabled no)
			(sheetname "")
		)
		(fill yes
			(thermal_gap 0.5)
			(thermal_bridge_width 0.5)
			(island_removal_mode 0)
		)
		(polygon
			(pts
				(arc
					(start 436.178198 -268.071346)
					(mid 436.193077 -268.107267)
					(end 436.228998 -268.122146)
				)
				(arc
					(start 437.628538 -268.122146)
					(mid 437.664459 -268.107267)
					(end 437.679338 -268.071346)
				)
				(arc
					(start 437.679338 -267.662406)
					(mid 437.664459 -267.626485)
					(end 437.628538 -267.611606)
				)
				(arc
					(start 436.228998 -267.611606)
					(mid 436.193077 -267.626485)
					(end 436.178198 -267.662406)
				)
			)
		)
	)
	(zone
		(layers "In1.Cu" "In2.Cu")
		(hatch none 0.5)
		(connect_pads
			(clearance 0)
		)
		(min_thickness 0.25)
		(keepout
			(tracks not_allowed)
			(vias allowed)
			(pads allowed)
			(copperpour not_allowed)
			(footprints allowed)
		)
		(placement
			(enabled no)
			(sheetname "")
		)
		(fill yes
			(thermal_gap 0.5)
			(thermal_bridge_width 0.5)
			(island_removal_mode 0)
		)
		(polygon
			(pts
				(arc
					(start 210.86953 -262.971534)
					(mid 210.884409 -263.007455)
					(end 210.92033 -263.022334)
				)
				(arc
					(start 212.31987 -263.022334)
					(mid 212.355791 -263.007455)
					(end 212.37067 -262.971534)
				)
				(arc
					(start 212.37067 -262.562594)
					(mid 212.355791 -262.526673)
					(end 212.31987 -262.511794)
				)
				(arc
					(start 210.92033 -262.511794)
					(mid 210.884409 -262.526673)
					(end 210.86953 -262.562594)
				)
			)
		)
	)
	(zone
		(layers "In1.Cu" "In2.Cu")
		(hatch none 0.5)
		(connect_pads
			(clearance 0)
		)
		(min_thickness 0.25)
		(keepout
			(tracks not_allowed)
			(vias allowed)
			(pads allowed)
			(copperpour not_allowed)
			(footprints allowed)
		)
		(placement
			(enabled no)
			(sheetname "")
		)
		(fill yes
			(thermal_gap 0.5)
			(thermal_bridge_width 0.5)
			(island_removal_mode 0)
		)
		(polygon
			(pts
				(arc
					(start 52.65293 -209.421476)
					(mid 52.667809 -209.457397)
					(end 52.70373 -209.472276)
				)
				(arc
					(start 54.10327 -209.472276)
					(mid 54.139191 -209.457397)
					(end 54.15407 -209.421476)
				)
				(arc
					(start 54.15407 -209.012536)
					(mid 54.139191 -208.976615)
					(end 54.10327 -208.961736)
				)
				(arc
					(start 52.70373 -208.961736)
					(mid 52.667809 -208.976615)
					(end 52.65293 -209.012536)
				)
			)
		)
	)
	(zone
		(layers "In1.Cu" "In2.Cu")
		(hatch none 0.5)
		(connect_pads
			(clearance 0)
		)
		(min_thickness 0.25)
		(keepout
			(tracks not_allowed)
			(vias allowed)
			(pads allowed)
			(copperpour not_allowed)
			(footprints allowed)
		)
		(placement
			(enabled no)
			(sheetname "")
		)
		(fill yes
			(thermal_gap 0.5)
			(thermal_bridge_width 0.5)
			(island_removal_mode 0)
		)
		(polygon
			(pts
				(arc
					(start 7.39013 -274.871434)
					(mid 7.405009 -274.907355)
					(end 7.44093 -274.922234)
				)
				(arc
					(start 8.84047 -274.922234)
					(mid 8.876391 -274.907355)
					(end 8.89127 -274.871434)
				)
				(arc
					(start 8.89127 -274.462494)
					(mid 8.876391 -274.426573)
					(end 8.84047 -274.411694)
				)
				(arc
					(start 7.44093 -274.411694)
					(mid 7.405009 -274.426573)
					(end 7.39013 -274.462494)
				)
			)
		)
	)
	(zone
		(layers "In1.Cu" "In2.Cu")
		(hatch none 0.5)
		(connect_pads
			(clearance 0)
		)
		(min_thickness 0.25)
		(keepout
			(tracks not_allowed)
			(vias allowed)
			(pads allowed)
			(copperpour not_allowed)
			(footprints allowed)
		)
		(placement
			(enabled no)
			(sheetname "")
		)
		(fill yes
			(thermal_gap 0.5)
			(thermal_bridge_width 0.5)
			(island_removal_mode 0)
		)
		(polygon
			(pts
				(arc
					(start 421.090598 -211.971382)
					(mid 421.105477 -212.007303)
					(end 421.141398 -212.022182)
				)
				(arc
					(start 422.540938 -212.022182)
					(mid 422.576859 -212.007303)
					(end 422.591738 -211.971382)
				)
				(arc
					(start 422.591738 -211.562442)
					(mid 422.576859 -211.526521)
					(end 422.540938 -211.511642)
				)
				(arc
					(start 421.141398 -211.511642)
					(mid 421.105477 -211.526521)
					(end 421.090598 -211.562442)
				)
			)
		)
	)
	(zone
		(layers "In1.Cu" "In2.Cu")
		(hatch none 0.5)
		(connect_pads
			(clearance 0)
		)
		(min_thickness 0.25)
		(keepout
			(tracks not_allowed)
			(vias allowed)
			(pads allowed)
			(copperpour not_allowed)
			(footprints allowed)
		)
		(placement
			(enabled no)
			(sheetname "")
		)
		(fill yes
			(thermal_gap 0.5)
			(thermal_bridge_width 0.5)
			(island_removal_mode 0)
		)
		(polygon
			(pts
				(arc
					(start 214.969598 -218.77147)
					(mid 214.984477 -218.807391)
					(end 215.020398 -218.82227)
				)
				(arc
					(start 216.419938 -218.82227)
					(mid 216.455859 -218.807391)
					(end 216.470738 -218.77147)
				)
				(arc
					(start 216.470738 -218.36253)
					(mid 216.455859 -218.326609)
					(end 216.419938 -218.31173)
				)
				(arc
					(start 215.020398 -218.31173)
					(mid 214.984477 -218.326609)
					(end 214.969598 -218.36253)
				)
			)
		)
	)
	(zone
		(layers "In1.Cu" "In2.Cu")
		(hatch none 0.5)
		(connect_pads
			(clearance 0)
		)
		(min_thickness 0.25)
		(keepout
			(tracks not_allowed)
			(vias allowed)
			(pads allowed)
			(copperpour not_allowed)
			(footprints allowed)
		)
		(placement
			(enabled no)
			(sheetname "")
		)
		(fill yes
			(thermal_gap 0.5)
			(thermal_bridge_width 0.5)
			(island_removal_mode 0)
		)
		(polygon
			(pts
				(arc
					(start 45.10913 -206.021432)
					(mid 45.124009 -206.057353)
					(end 45.15993 -206.072232)
				)
				(arc
					(start 46.55947 -206.072232)
					(mid 46.595391 -206.057353)
					(end 46.61027 -206.021432)
				)
				(arc
					(start 46.61027 -205.612492)
					(mid 46.595391 -205.576571)
					(end 46.55947 -205.561692)
				)
				(arc
					(start 45.15993 -205.561692)
					(mid 45.124009 -205.576571)
					(end 45.10913 -205.612492)
				)
			)
		)
	)
	(zone
		(layers "In1.Cu" "In2.Cu")
		(hatch none 0.5)
		(connect_pads
			(clearance 0)
		)
		(min_thickness 0.25)
		(keepout
			(tracks not_allowed)
			(vias allowed)
			(pads allowed)
			(copperpour not_allowed)
			(footprints allowed)
		)
		(placement
			(enabled no)
			(sheetname "")
		)
		(fill yes
			(thermal_gap 0.5)
			(thermal_bridge_width 0.5)
			(island_removal_mode 0)
		)
		(polygon
			(pts
				(arc
					(start 312.236866 -263.821418)
					(mid 312.251745 -263.857339)
					(end 312.287666 -263.872218)
				)
				(arc
					(start 313.687206 -263.872218)
					(mid 313.723127 -263.857339)
					(end 313.738006 -263.821418)
				)
				(arc
					(start 313.738006 -263.412478)
					(mid 313.723127 -263.376557)
					(end 313.687206 -263.361678)
				)
				(arc
					(start 312.287666 -263.361678)
					(mid 312.251745 -263.376557)
					(end 312.236866 -263.412478)
				)
			)
		)
	)
	(zone
		(layers "In1.Cu" "In2.Cu")
		(hatch none 0.5)
		(connect_pads
			(clearance 0)
		)
		(min_thickness 0.25)
		(keepout
			(tracks not_allowed)
			(vias allowed)
			(pads allowed)
			(copperpour not_allowed)
			(footprints allowed)
		)
		(placement
			(enabled no)
			(sheetname "")
		)
		(fill yes
			(thermal_gap 0.5)
			(thermal_bridge_width 0.5)
			(island_removal_mode 0)
		)
		(polygon
			(pts
				(arc
					(start 52.65293 -293.571422)
					(mid 52.667809 -293.607343)
					(end 52.70373 -293.622222)
				)
				(arc
					(start 54.10327 -293.622222)
					(mid 54.139191 -293.607343)
					(end 54.15407 -293.571422)
				)
				(arc
					(start 54.15407 -293.162482)
					(mid 54.139191 -293.126561)
					(end 54.10327 -293.111682)
				)
				(arc
					(start 52.70373 -293.111682)
					(mid 52.667809 -293.126561)
					(end 52.65293 -293.162482)
				)
			)
		)
	)
	(zone
		(layers "In1.Cu" "In2.Cu")
		(hatch none 0.5)
		(connect_pads
			(clearance 0)
		)
		(min_thickness 0.25)
		(keepout
			(tracks not_allowed)
			(vias allowed)
			(pads allowed)
			(copperpour not_allowed)
			(footprints allowed)
		)
		(placement
			(enabled no)
			(sheetname "")
		)
		(fill yes
			(thermal_gap 0.5)
			(thermal_bridge_width 0.5)
			(island_removal_mode 0)
		)
		(polygon
			(pts
				(arc
					(start 52.65293 -261.271512)
					(mid 52.667809 -261.307433)
					(end 52.70373 -261.322312)
				)
				(arc
					(start 54.10327 -261.322312)
					(mid 54.139191 -261.307433)
					(end 54.15407 -261.271512)
				)
				(arc
					(start 54.15407 -260.862572)
					(mid 54.139191 -260.826651)
					(end 54.10327 -260.811772)
				)
				(arc
					(start 52.70373 -260.811772)
					(mid 52.667809 -260.826651)
					(end 52.65293 -260.862572)
				)
			)
		)
	)
	(zone
		(layers "In1.Cu" "In2.Cu")
		(hatch none 0.5)
		(connect_pads
			(clearance 0)
		)
		(min_thickness 0.25)
		(keepout
			(tracks not_allowed)
			(vias allowed)
			(pads allowed)
			(copperpour not_allowed)
			(footprints allowed)
		)
		(placement
			(enabled no)
			(sheetname "")
		)
		(fill yes
			(thermal_gap 0.5)
			(thermal_bridge_width 0.5)
			(island_removal_mode 0)
		)
		(polygon
			(pts
				(arc
					(start 192.338198 -311.421526)
					(mid 192.353077 -311.457447)
					(end 192.388998 -311.472326)
				)
				(arc
					(start 193.788538 -311.472326)
					(mid 193.824459 -311.457447)
					(end 193.839338 -311.421526)
				)
				(arc
					(start 193.839338 -311.012586)
					(mid 193.824459 -310.976665)
					(end 193.788538 -310.961786)
				)
				(arc
					(start 192.388998 -310.961786)
					(mid 192.353077 -310.976665)
					(end 192.338198 -311.012586)
				)
			)
		)
	)
	(zone
		(layers "In1.Cu" "In2.Cu")
		(hatch none 0.5)
		(connect_pads
			(clearance 0)
		)
		(min_thickness 0.25)
		(keepout
			(tracks not_allowed)
			(vias allowed)
			(pads allowed)
			(copperpour not_allowed)
			(footprints allowed)
		)
		(placement
			(enabled no)
			(sheetname "")
		)
		(fill yes
			(thermal_gap 0.5)
			(thermal_bridge_width 0.5)
			(island_removal_mode 0)
		)
		(polygon
			(pts
				(arc
					(start 277.961598 -271.47139)
					(mid 277.976477 -271.507311)
					(end 278.012398 -271.52219)
				)
				(arc
					(start 279.411938 -271.52219)
					(mid 279.447859 -271.507311)
					(end 279.462738 -271.47139)
				)
				(arc
					(start 279.462738 -271.06245)
					(mid 279.447859 -271.026529)
					(end 279.411938 -271.01165)
				)
				(arc
					(start 278.012398 -271.01165)
					(mid 277.976477 -271.026529)
					(end 277.961598 -271.06245)
				)
			)
		)
	)
	(zone
		(layers "In1.Cu" "In2.Cu")
		(hatch none 0.5)
		(connect_pads
			(clearance 0)
		)
		(min_thickness 0.25)
		(keepout
			(tracks not_allowed)
			(vias allowed)
			(pads allowed)
			(copperpour not_allowed)
			(footprints allowed)
		)
		(placement
			(enabled no)
			(sheetname "")
		)
		(fill yes
			(thermal_gap 0.5)
			(thermal_bridge_width 0.5)
			(island_removal_mode 0)
		)
		(polygon
			(pts
				(arc
					(start 14.93393 -271.47139)
					(mid 14.948809 -271.507311)
					(end 14.98473 -271.52219)
				)
				(arc
					(start 16.38427 -271.52219)
					(mid 16.420191 -271.507311)
					(end 16.43507 -271.47139)
				)
				(arc
					(start 16.43507 -271.06245)
					(mid 16.420191 -271.026529)
					(end 16.38427 -271.01165)
				)
				(arc
					(start 14.98473 -271.01165)
					(mid 14.948809 -271.026529)
					(end 14.93393 -271.06245)
				)
			)
		)
	)
	(zone
		(layers "In1.Cu" "In2.Cu")
		(hatch none 0.5)
		(connect_pads
			(clearance 0)
		)
		(min_thickness 0.25)
		(keepout
			(tracks not_allowed)
			(vias allowed)
			(pads allowed)
			(copperpour not_allowed)
			(footprints allowed)
		)
		(placement
			(enabled no)
			(sheetname "")
		)
		(fill yes
			(thermal_gap 0.5)
			(thermal_bridge_width 0.5)
			(island_removal_mode 0)
		)
		(polygon
			(pts
				(arc
					(start 413.546798 -313.121294)
					(mid 413.561677 -313.157215)
					(end 413.597598 -313.172094)
				)
				(arc
					(start 414.997138 -313.172094)
					(mid 415.033059 -313.157215)
					(end 415.047938 -313.121294)
				)
				(arc
					(start 415.047938 -312.712354)
					(mid 415.033059 -312.676433)
					(end 414.997138 -312.661554)
				)
				(arc
					(start 413.597598 -312.661554)
					(mid 413.561677 -312.676433)
					(end 413.546798 -312.712354)
				)
			)
		)
	)
	(zone
		(layers "In1.Cu" "In2.Cu")
		(hatch none 0.5)
		(connect_pads
			(clearance 0)
		)
		(min_thickness 0.25)
		(keepout
			(tracks not_allowed)
			(vias allowed)
			(pads allowed)
			(copperpour not_allowed)
			(footprints allowed)
		)
		(placement
			(enabled no)
			(sheetname "")
		)
		(fill yes
			(thermal_gap 0.5)
			(thermal_bridge_width 0.5)
			(island_removal_mode 0)
		)
		(polygon
			(pts
				(arc
					(start 45.10913 -228.121464)
					(mid 45.124009 -228.157385)
					(end 45.15993 -228.172264)
				)
				(arc
					(start 46.55947 -228.172264)
					(mid 46.595391 -228.157385)
					(end 46.61027 -228.121464)
				)
				(arc
					(start 46.61027 -227.712524)
					(mid 46.595391 -227.676603)
					(end 46.55947 -227.661724)
				)
				(arc
					(start 45.15993 -227.661724)
					(mid 45.124009 -227.676603)
					(end 45.10913 -227.712524)
				)
			)
		)
	)
	(zone
		(layers "In1.Cu" "In2.Cu")
		(hatch none 0.5)
		(connect_pads
			(clearance 0)
		)
		(min_thickness 0.25)
		(keepout
			(tracks not_allowed)
			(vias allowed)
			(pads allowed)
			(copperpour not_allowed)
			(footprints allowed)
		)
		(placement
			(enabled no)
			(sheetname "")
		)
		(fill yes
			(thermal_gap 0.5)
			(thermal_bridge_width 0.5)
			(island_removal_mode 0)
		)
		(polygon
			(pts
				(arc
					(start 214.969598 -292.721538)
					(mid 214.984477 -292.757459)
					(end 215.020398 -292.772338)
				)
				(arc
					(start 216.419938 -292.772338)
					(mid 216.455859 -292.757459)
					(end 216.470738 -292.721538)
				)
				(arc
					(start 216.470738 -292.312598)
					(mid 216.455859 -292.276677)
					(end 216.419938 -292.261798)
				)
				(arc
					(start 215.020398 -292.261798)
					(mid 214.984477 -292.276677)
					(end 214.969598 -292.312598)
				)
			)
		)
	)
	(zone
		(layers "In1.Cu" "In2.Cu")
		(hatch none 0.5)
		(connect_pads
			(clearance 0)
		)
		(min_thickness 0.25)
		(keepout
			(tracks not_allowed)
			(vias allowed)
			(pads allowed)
			(copperpour not_allowed)
			(footprints allowed)
		)
		(placement
			(enabled no)
			(sheetname "")
		)
		(fill yes
			(thermal_gap 0.5)
			(thermal_bridge_width 0.5)
			(island_removal_mode 0)
		)
		(polygon
			(pts
				(arc
					(start 312.236866 -211.121498)
					(mid 312.251745 -211.157419)
					(end 312.287666 -211.172298)
				)
				(arc
					(start 313.687206 -211.172298)
					(mid 313.723127 -211.157419)
					(end 313.738006 -211.121498)
				)
				(arc
					(start 313.738006 -210.712558)
					(mid 313.723127 -210.676637)
					(end 313.687206 -210.661758)
				)
				(arc
					(start 312.287666 -210.661758)
					(mid 312.251745 -210.676637)
					(end 312.236866 -210.712558)
				)
			)
		)
	)
	(zone
		(layers "In1.Cu" "In2.Cu")
		(hatch none 0.5)
		(connect_pads
			(clearance 0)
		)
		(min_thickness 0.25)
		(keepout
			(tracks not_allowed)
			(vias allowed)
			(pads allowed)
			(copperpour not_allowed)
			(footprints allowed)
		)
		(placement
			(enabled no)
			(sheetname "")
		)
		(fill yes
			(thermal_gap 0.5)
			(thermal_bridge_width 0.5)
			(island_removal_mode 0)
		)
		(polygon
			(pts
				(arc
					(start 266.974066 -295.271444)
					(mid 266.988945 -295.307365)
					(end 267.024866 -295.322244)
				)
				(arc
					(start 268.424406 -295.322244)
					(mid 268.460327 -295.307365)
					(end 268.475206 -295.271444)
				)
				(arc
					(start 268.475206 -294.862504)
					(mid 268.460327 -294.826583)
					(end 268.424406 -294.811704)
				)
				(arc
					(start 267.024866 -294.811704)
					(mid 266.988945 -294.826583)
					(end 266.974066 -294.862504)
				)
			)
		)
	)
	(zone
		(layers "In1.Cu" "In2.Cu")
		(hatch none 0.5)
		(connect_pads
			(clearance 0)
		)
		(min_thickness 0.25)
		(keepout
			(tracks not_allowed)
			(vias allowed)
			(pads allowed)
			(copperpour not_allowed)
			(footprints allowed)
		)
		(placement
			(enabled no)
			(sheetname "")
		)
		(fill yes
			(thermal_gap 0.5)
			(thermal_bridge_width 0.5)
			(island_removal_mode 0)
		)
		(polygon
			(pts
				(arc
					(start 428.634398 -252.771402)
					(mid 428.649277 -252.807323)
					(end 428.685198 -252.822202)
				)
				(arc
					(start 430.084738 -252.822202)
					(mid 430.120659 -252.807323)
					(end 430.135538 -252.771402)
				)
				(arc
					(start 430.135538 -252.362462)
					(mid 430.120659 -252.326541)
					(end 430.084738 -252.311662)
				)
				(arc
					(start 428.685198 -252.311662)
					(mid 428.649277 -252.326541)
					(end 428.634398 -252.362462)
				)
			)
		)
	)
	(zone
		(layers "In1.Cu" "In2.Cu")
		(hatch none 0.5)
		(connect_pads
			(clearance 0)
		)
		(min_thickness 0.25)
		(keepout
			(tracks not_allowed)
			(vias allowed)
			(pads allowed)
			(copperpour not_allowed)
			(footprints allowed)
		)
		(placement
			(enabled no)
			(sheetname "")
		)
		(fill yes
			(thermal_gap 0.5)
			(thermal_bridge_width 0.5)
			(island_removal_mode 0)
		)
		(polygon
			(pts
				(arc
					(start 282.061666 -312.27141)
					(mid 282.076545 -312.307331)
					(end 282.112466 -312.32221)
				)
				(arc
					(start 283.512006 -312.32221)
					(mid 283.547927 -312.307331)
					(end 283.562806 -312.27141)
				)
				(arc
					(start 283.562806 -311.86247)
					(mid 283.547927 -311.826549)
					(end 283.512006 -311.81167)
				)
				(arc
					(start 282.112466 -311.81167)
					(mid 282.076545 -311.826549)
					(end 282.061666 -311.86247)
				)
			)
		)
	)
	(zone
		(layers "In1.Cu" "In2.Cu")
		(hatch none 0.5)
		(connect_pads
			(clearance 0)
		)
		(min_thickness 0.25)
		(keepout
			(tracks not_allowed)
			(vias allowed)
			(pads allowed)
			(copperpour not_allowed)
			(footprints allowed)
		)
		(placement
			(enabled no)
			(sheetname "")
		)
		(fill yes
			(thermal_gap 0.5)
			(thermal_bridge_width 0.5)
			(island_removal_mode 0)
		)
		(polygon
			(pts
				(arc
					(start 199.881998 -250.221496)
					(mid 199.896877 -250.257417)
					(end 199.932798 -250.272296)
				)
				(arc
					(start 201.332338 -250.272296)
					(mid 201.368259 -250.257417)
					(end 201.383138 -250.221496)
				)
				(arc
					(start 201.383138 -249.812556)
					(mid 201.368259 -249.776635)
					(end 201.332338 -249.761756)
				)
				(arc
					(start 199.932798 -249.761756)
					(mid 199.896877 -249.776635)
					(end 199.881998 -249.812556)
				)
			)
		)
	)
	(zone
		(layers "In1.Cu" "In2.Cu")
		(hatch none 0.5)
		(connect_pads
			(clearance 0)
		)
		(min_thickness 0.25)
		(keepout
			(tracks not_allowed)
			(vias allowed)
			(pads allowed)
			(copperpour not_allowed)
			(footprints allowed)
		)
		(placement
			(enabled no)
			(sheetname "")
		)
		(fill yes
			(thermal_gap 0.5)
			(thermal_bridge_width 0.5)
			(island_removal_mode 0)
		)
		(polygon
			(pts
				(arc
					(start 308.136798 -303.7713)
					(mid 308.151677 -303.807221)
					(end 308.187598 -303.8221)
				)
				(arc
					(start 309.587138 -303.8221)
					(mid 309.623059 -303.807221)
					(end 309.637938 -303.7713)
				)
				(arc
					(start 309.637938 -303.36236)
					(mid 309.623059 -303.326439)
					(end 309.587138 -303.31156)
				)
				(arc
					(start 308.187598 -303.31156)
					(mid 308.151677 -303.326439)
					(end 308.136798 -303.36236)
				)
			)
		)
	)
	(zone
		(layers "In1.Cu" "In2.Cu")
		(hatch none 0.5)
		(connect_pads
			(clearance 0)
		)
		(min_thickness 0.25)
		(keepout
			(tracks not_allowed)
			(vias allowed)
			(pads allowed)
			(copperpour not_allowed)
			(footprints allowed)
		)
		(placement
			(enabled no)
			(sheetname "")
		)
		(fill yes
			(thermal_gap 0.5)
			(thermal_bridge_width 0.5)
			(island_removal_mode 0)
		)
		(polygon
			(pts
				(arc
					(start 282.061666 -292.721538)
					(mid 282.076545 -292.757459)
					(end 282.112466 -292.772338)
				)
				(arc
					(start 283.512006 -292.772338)
					(mid 283.547927 -292.757459)
					(end 283.562806 -292.721538)
				)
				(arc
					(start 283.562806 -292.312598)
					(mid 283.547927 -292.276677)
					(end 283.512006 -292.261798)
				)
				(arc
					(start 282.112466 -292.261798)
					(mid 282.076545 -292.276677)
					(end 282.061666 -292.312598)
				)
			)
		)
	)
	(zone
		(layers "In1.Cu" "In2.Cu")
		(hatch none 0.5)
		(connect_pads
			(clearance 0)
		)
		(min_thickness 0.25)
		(keepout
			(tracks not_allowed)
			(vias allowed)
			(pads allowed)
			(copperpour not_allowed)
			(footprints allowed)
		)
		(placement
			(enabled no)
			(sheetname "")
		)
		(fill yes
			(thermal_gap 0.5)
			(thermal_bridge_width 0.5)
			(island_removal_mode 0)
		)
		(polygon
			(pts
				(arc
					(start 169.706798 -217.921332)
					(mid 169.721677 -217.957253)
					(end 169.757598 -217.972132)
				)
				(arc
					(start 171.157138 -217.972132)
					(mid 171.193059 -217.957253)
					(end 171.207938 -217.921332)
				)
				(arc
					(start 171.207938 -217.512392)
					(mid 171.193059 -217.476471)
					(end 171.157138 -217.461592)
				)
				(arc
					(start 169.757598 -217.461592)
					(mid 169.721677 -217.476471)
					(end 169.706798 -217.512392)
				)
			)
		)
	)
	(zone
		(layers "In1.Cu" "In2.Cu")
		(hatch none 0.5)
		(connect_pads
			(clearance 0)
		)
		(min_thickness 0.25)
		(keepout
			(tracks not_allowed)
			(vias allowed)
			(pads allowed)
			(copperpour not_allowed)
			(footprints allowed)
		)
		(placement
			(enabled no)
			(sheetname "")
		)
		(fill yes
			(thermal_gap 0.5)
			(thermal_bridge_width 0.5)
			(island_removal_mode 0)
		)
		(polygon
			(pts
				(arc
					(start 188.23813 -240.021364)
					(mid 188.253009 -240.057285)
					(end 188.28893 -240.072164)
				)
				(arc
					(start 189.68847 -240.072164)
					(mid 189.724391 -240.057285)
					(end 189.73927 -240.021364)
				)
				(arc
					(start 189.73927 -239.612424)
					(mid 189.724391 -239.576503)
					(end 189.68847 -239.561624)
				)
				(arc
					(start 188.28893 -239.561624)
					(mid 188.253009 -239.576503)
					(end 188.23813 -239.612424)
				)
			)
		)
	)
	(zone
		(layers "In1.Cu" "In2.Cu")
		(hatch none 0.5)
		(connect_pads
			(clearance 0)
		)
		(min_thickness 0.25)
		(keepout
			(tracks not_allowed)
			(vias allowed)
			(pads allowed)
			(copperpour not_allowed)
			(footprints allowed)
		)
		(placement
			(enabled no)
			(sheetname "")
		)
		(fill yes
			(thermal_gap 0.5)
			(thermal_bridge_width 0.5)
			(island_removal_mode 0)
		)
		(polygon
			(pts
				(arc
					(start 406.002998 -206.021432)
					(mid 406.017877 -206.057353)
					(end 406.053798 -206.072232)
				)
				(arc
					(start 407.453338 -206.072232)
					(mid 407.489259 -206.057353)
					(end 407.504138 -206.021432)
				)
				(arc
					(start 407.504138 -205.612492)
					(mid 407.489259 -205.576571)
					(end 407.453338 -205.561692)
				)
				(arc
					(start 406.053798 -205.561692)
					(mid 406.017877 -205.576571)
					(end 406.002998 -205.612492)
				)
			)
		)
	)
	(zone
		(layers "In1.Cu" "In2.Cu")
		(hatch none 0.5)
		(connect_pads
			(clearance 0)
		)
		(min_thickness 0.25)
		(keepout
			(tracks not_allowed)
			(vias allowed)
			(pads allowed)
			(copperpour not_allowed)
			(footprints allowed)
		)
		(placement
			(enabled no)
			(sheetname "")
		)
		(fill yes
			(thermal_gap 0.5)
			(thermal_bridge_width 0.5)
			(island_removal_mode 0)
		)
		(polygon
			(pts
				(arc
					(start 41.665398 -201.771504)
					(mid 41.680277 -201.807425)
					(end 41.716198 -201.822304)
				)
				(arc
					(start 43.115738 -201.822304)
					(mid 43.151659 -201.807425)
					(end 43.166538 -201.771504)
				)
				(arc
					(start 43.166538 -201.362564)
					(mid 43.151659 -201.326643)
					(end 43.115738 -201.311764)
				)
				(arc
					(start 41.716198 -201.311764)
					(mid 41.680277 -201.326643)
					(end 41.665398 -201.362564)
				)
			)
		)
	)
	(zone
		(layers "In1.Cu" "In2.Cu")
		(hatch none 0.5)
		(connect_pads
			(clearance 0)
		)
		(min_thickness 0.25)
		(keepout
			(tracks not_allowed)
			(vias allowed)
			(pads allowed)
			(copperpour not_allowed)
			(footprints allowed)
		)
		(placement
			(enabled no)
			(sheetname "")
		)
		(fill yes
			(thermal_gap 0.5)
			(thermal_bridge_width 0.5)
			(island_removal_mode 0)
		)
		(polygon
			(pts
				(arc
					(start 458.809598 -226.421442)
					(mid 458.824477 -226.457363)
					(end 458.860398 -226.472242)
				)
				(arc
					(start 460.259938 -226.472242)
					(mid 460.295859 -226.457363)
					(end 460.310738 -226.421442)
				)
				(arc
					(start 460.310738 -226.012502)
					(mid 460.295859 -225.976581)
					(end 460.259938 -225.961702)
				)
				(arc
					(start 458.860398 -225.961702)
					(mid 458.824477 -225.976581)
					(end 458.809598 -226.012502)
				)
			)
		)
	)
	(zone
		(layers "In1.Cu" "In2.Cu")
		(hatch none 0.5)
		(connect_pads
			(clearance 0)
		)
		(min_thickness 0.25)
		(keepout
			(tracks not_allowed)
			(vias allowed)
			(pads allowed)
			(copperpour not_allowed)
			(footprints allowed)
		)
		(placement
			(enabled no)
			(sheetname "")
		)
		(fill yes
			(thermal_gap 0.5)
			(thermal_bridge_width 0.5)
			(island_removal_mode 0)
		)
		(polygon
			(pts
				(arc
					(start 262.873998 -251.07138)
					(mid 262.888877 -251.107301)
					(end 262.924798 -251.12218)
				)
				(arc
					(start 264.324338 -251.12218)
					(mid 264.360259 -251.107301)
					(end 264.375138 -251.07138)
				)
				(arc
					(start 264.375138 -250.66244)
					(mid 264.360259 -250.626519)
					(end 264.324338 -250.61164)
				)
				(arc
					(start 262.924798 -250.61164)
					(mid 262.888877 -250.626519)
					(end 262.873998 -250.66244)
				)
			)
		)
	)
	(zone
		(layers "In1.Cu" "In2.Cu")
		(hatch none 0.5)
		(connect_pads
			(clearance 0)
		)
		(min_thickness 0.25)
		(keepout
			(tracks not_allowed)
			(vias allowed)
			(pads allowed)
			(copperpour not_allowed)
			(footprints allowed)
		)
		(placement
			(enabled no)
			(sheetname "")
		)
		(fill yes
			(thermal_gap 0.5)
			(thermal_bridge_width 0.5)
			(island_removal_mode 0)
		)
		(polygon
			(pts
				(arc
					(start 300.592998 -215.371426)
					(mid 300.607877 -215.407347)
					(end 300.643798 -215.422226)
				)
				(arc
					(start 302.043338 -215.422226)
					(mid 302.079259 -215.407347)
					(end 302.094138 -215.371426)
				)
				(arc
					(start 302.094138 -214.962486)
					(mid 302.079259 -214.926565)
					(end 302.043338 -214.911686)
				)
				(arc
					(start 300.643798 -214.911686)
					(mid 300.607877 -214.926565)
					(end 300.592998 -214.962486)
				)
			)
		)
	)
	(zone
		(layers "In1.Cu" "In2.Cu")
		(hatch none 0.5)
		(connect_pads
			(clearance 0)
		)
		(min_thickness 0.25)
		(keepout
			(tracks not_allowed)
			(vias allowed)
			(pads allowed)
			(copperpour not_allowed)
			(footprints allowed)
		)
		(placement
			(enabled no)
			(sheetname "")
		)
		(fill yes
			(thermal_gap 0.5)
			(thermal_bridge_width 0.5)
			(island_removal_mode 0)
		)
		(polygon
			(pts
				(arc
					(start 432.734466 -239.17148)
					(mid 432.749345 -239.207401)
					(end 432.785266 -239.22228)
				)
				(arc
					(start 434.184806 -239.22228)
					(mid 434.220727 -239.207401)
					(end 434.235606 -239.17148)
				)
				(arc
					(start 434.235606 -238.76254)
					(mid 434.220727 -238.726619)
					(end 434.184806 -238.71174)
				)
				(arc
					(start 432.785266 -238.71174)
					(mid 432.749345 -238.726619)
					(end 432.734466 -238.76254)
				)
			)
		)
	)
	(zone
		(layers "In1.Cu" "In2.Cu")
		(hatch none 0.5)
		(connect_pads
			(clearance 0)
		)
		(min_thickness 0.25)
		(keepout
			(tracks not_allowed)
			(vias allowed)
			(pads allowed)
			(copperpour not_allowed)
			(footprints allowed)
		)
		(placement
			(enabled no)
			(sheetname "")
		)
		(fill yes
			(thermal_gap 0.5)
			(thermal_bridge_width 0.5)
			(island_removal_mode 0)
		)
		(polygon
			(pts
				(arc
					(start 451.265798 -307.171344)
					(mid 451.280677 -307.207265)
					(end 451.316598 -307.222144)
				)
				(arc
					(start 452.716138 -307.222144)
					(mid 452.752059 -307.207265)
					(end 452.766938 -307.171344)
				)
				(arc
					(start 452.766938 -306.762404)
					(mid 452.752059 -306.726483)
					(end 452.716138 -306.711604)
				)
				(arc
					(start 451.316598 -306.711604)
					(mid 451.280677 -306.726483)
					(end 451.265798 -306.762404)
				)
			)
		)
	)
	(zone
		(layers "In1.Cu" "In2.Cu")
		(hatch none 0.5)
		(connect_pads
			(clearance 0)
		)
		(min_thickness 0.25)
		(keepout
			(tracks not_allowed)
			(vias allowed)
			(pads allowed)
			(copperpour not_allowed)
			(footprints allowed)
		)
		(placement
			(enabled no)
			(sheetname "")
		)
		(fill yes
			(thermal_gap 0.5)
			(thermal_bridge_width 0.5)
			(island_removal_mode 0)
		)
		(polygon
			(pts
				(arc
					(start 22.47773 -215.371426)
					(mid 22.492609 -215.407347)
					(end 22.52853 -215.422226)
				)
				(arc
					(start 23.92807 -215.422226)
					(mid 23.963991 -215.407347)
					(end 23.97887 -215.371426)
				)
				(arc
					(start 23.97887 -214.962486)
					(mid 23.963991 -214.926565)
					(end 23.92807 -214.911686)
				)
				(arc
					(start 22.52853 -214.911686)
					(mid 22.492609 -214.926565)
					(end 22.47773 -214.962486)
				)
			)
		)
	)
	(zone
		(layers "In1.Cu" "In2.Cu")
		(hatch none 0.5)
		(connect_pads
			(clearance 0)
		)
		(min_thickness 0.25)
		(keepout
			(tracks not_allowed)
			(vias allowed)
			(pads allowed)
			(copperpour not_allowed)
			(footprints allowed)
		)
		(placement
			(enabled no)
			(sheetname "")
		)
		(fill yes
			(thermal_gap 0.5)
			(thermal_bridge_width 0.5)
			(island_removal_mode 0)
		)
		(polygon
			(pts
				(arc
					(start 443.721998 -228.971348)
					(mid 443.736877 -229.007269)
					(end 443.772798 -229.022148)
				)
				(arc
					(start 445.172338 -229.022148)
					(mid 445.208259 -229.007269)
					(end 445.223138 -228.971348)
				)
				(arc
					(start 445.223138 -228.562408)
					(mid 445.208259 -228.526487)
					(end 445.172338 -228.511608)
				)
				(arc
					(start 443.772798 -228.511608)
					(mid 443.736877 -228.526487)
					(end 443.721998 -228.562408)
				)
			)
		)
	)
	(zone
		(layers "In1.Cu" "In2.Cu")
		(hatch none 0.5)
		(connect_pads
			(clearance 0)
		)
		(min_thickness 0.25)
		(keepout
			(tracks not_allowed)
			(vias allowed)
			(pads allowed)
			(copperpour not_allowed)
			(footprints allowed)
		)
		(placement
			(enabled no)
			(sheetname "")
		)
		(fill yes
			(thermal_gap 0.5)
			(thermal_bridge_width 0.5)
			(island_removal_mode 0)
		)
		(polygon
			(pts
				(arc
					(start 7.39013 -213.671404)
					(mid 7.405009 -213.707325)
					(end 7.44093 -213.722204)
				)
				(arc
					(start 8.84047 -213.722204)
					(mid 8.876391 -213.707325)
					(end 8.89127 -213.671404)
				)
				(arc
					(start 8.89127 -213.262464)
					(mid 8.876391 -213.226543)
					(end 8.84047 -213.211664)
				)
				(arc
					(start 7.44093 -213.211664)
					(mid 7.405009 -213.226543)
					(end 7.39013 -213.262464)
				)
			)
		)
	)
	(zone
		(layers "In1.Cu" "In2.Cu")
		(hatch none 0.5)
		(connect_pads
			(clearance 0)
		)
		(min_thickness 0.25)
		(keepout
			(tracks not_allowed)
			(vias allowed)
			(pads allowed)
			(copperpour not_allowed)
			(footprints allowed)
		)
		(placement
			(enabled no)
			(sheetname "")
		)
		(fill yes
			(thermal_gap 0.5)
			(thermal_bridge_width 0.5)
			(island_removal_mode 0)
		)
		(polygon
			(pts
				(arc
					(start 14.93393 -221.321376)
					(mid 14.948809 -221.357297)
					(end 14.98473 -221.372176)
				)
				(arc
					(start 16.38427 -221.372176)
					(mid 16.420191 -221.357297)
					(end 16.43507 -221.321376)
				)
				(arc
					(start 16.43507 -220.912436)
					(mid 16.420191 -220.876515)
					(end 16.38427 -220.861636)
				)
				(arc
					(start 14.98473 -220.861636)
					(mid 14.948809 -220.876515)
					(end 14.93393 -220.912436)
				)
			)
		)
	)
	(zone
		(layers "In1.Cu" "In2.Cu")
		(hatch none 0.5)
		(connect_pads
			(clearance 0)
		)
		(min_thickness 0.25)
		(keepout
			(tracks not_allowed)
			(vias allowed)
			(pads allowed)
			(copperpour not_allowed)
			(footprints allowed)
		)
		(placement
			(enabled no)
			(sheetname "")
		)
		(fill yes
			(thermal_gap 0.5)
			(thermal_bridge_width 0.5)
			(island_removal_mode 0)
		)
		(polygon
			(pts
				(arc
					(start 207.425798 -228.121464)
					(mid 207.440677 -228.157385)
					(end 207.476598 -228.172264)
				)
				(arc
					(start 208.876138 -228.172264)
					(mid 208.912059 -228.157385)
					(end 208.926938 -228.121464)
				)
				(arc
					(start 208.926938 -227.712524)
					(mid 208.912059 -227.676603)
					(end 208.876138 -227.661724)
				)
				(arc
					(start 207.476598 -227.661724)
					(mid 207.440677 -227.676603)
					(end 207.425798 -227.712524)
				)
			)
		)
	)
	(zone
		(layers "In1.Cu" "In2.Cu")
		(hatch none 0.5)
		(connect_pads
			(clearance 0)
		)
		(min_thickness 0.25)
		(keepout
			(tracks not_allowed)
			(vias allowed)
			(pads allowed)
			(copperpour not_allowed)
			(footprints allowed)
		)
		(placement
			(enabled no)
			(sheetname "")
		)
		(fill yes
			(thermal_gap 0.5)
			(thermal_bridge_width 0.5)
			(island_removal_mode 0)
		)
		(polygon
			(pts
				(arc
					(start 432.734466 -274.871434)
					(mid 432.749345 -274.907355)
					(end 432.785266 -274.922234)
				)
				(arc
					(start 434.184806 -274.922234)
					(mid 434.220727 -274.907355)
					(end 434.235606 -274.871434)
				)
				(arc
					(start 434.235606 -274.462494)
					(mid 434.220727 -274.426573)
					(end 434.184806 -274.411694)
				)
				(arc
					(start 432.785266 -274.411694)
					(mid 432.749345 -274.426573)
					(end 432.734466 -274.462494)
				)
			)
		)
	)
	(zone
		(layers "In1.Cu" "In2.Cu")
		(hatch none 0.5)
		(connect_pads
			(clearance 0)
		)
		(min_thickness 0.25)
		(keepout
			(tracks not_allowed)
			(vias allowed)
			(pads allowed)
			(copperpour not_allowed)
			(footprints allowed)
		)
		(placement
			(enabled no)
			(sheetname "")
		)
		(fill yes
			(thermal_gap 0.5)
			(thermal_bridge_width 0.5)
			(island_removal_mode 0)
		)
		(polygon
			(pts
				(arc
					(start 14.93393 -232.371392)
					(mid 14.948809 -232.407313)
					(end 14.98473 -232.422192)
				)
				(arc
					(start 16.38427 -232.422192)
					(mid 16.420191 -232.407313)
					(end 16.43507 -232.371392)
				)
				(arc
					(start 16.43507 -231.962452)
					(mid 16.420191 -231.926531)
					(end 16.38427 -231.911652)
				)
				(arc
					(start 14.98473 -231.911652)
					(mid 14.948809 -231.926531)
					(end 14.93393 -231.962452)
				)
			)
		)
	)
	(zone
		(layers "In1.Cu" "In2.Cu")
		(hatch none 0.5)
		(connect_pads
			(clearance 0)
		)
		(min_thickness 0.25)
		(keepout
			(tracks not_allowed)
			(vias allowed)
			(pads allowed)
			(copperpour not_allowed)
			(footprints allowed)
		)
		(placement
			(enabled no)
			(sheetname "")
		)
		(fill yes
			(thermal_gap 0.5)
			(thermal_bridge_width 0.5)
			(island_removal_mode 0)
		)
		(polygon
			(pts
				(arc
					(start 14.93393 -219.621354)
					(mid 14.948809 -219.657275)
					(end 14.98473 -219.672154)
				)
				(arc
					(start 16.38427 -219.672154)
					(mid 16.420191 -219.657275)
					(end 16.43507 -219.621354)
				)
				(arc
					(start 16.43507 -219.212414)
					(mid 16.420191 -219.176493)
					(end 16.38427 -219.161614)
				)
				(arc
					(start 14.98473 -219.161614)
					(mid 14.948809 -219.176493)
					(end 14.93393 -219.212414)
				)
			)
		)
	)
	(zone
		(layers "In1.Cu" "In2.Cu")
		(hatch none 0.5)
		(connect_pads
			(clearance 0)
		)
		(min_thickness 0.25)
		(keepout
			(tracks not_allowed)
			(vias allowed)
			(pads allowed)
			(copperpour not_allowed)
			(footprints allowed)
		)
		(placement
			(enabled no)
			(sheetname "")
		)
		(fill yes
			(thermal_gap 0.5)
			(thermal_bridge_width 0.5)
			(island_removal_mode 0)
		)
		(polygon
			(pts
				(arc
					(start 259.430266 -267.221462)
					(mid 259.445145 -267.257383)
					(end 259.481066 -267.272262)
				)
				(arc
					(start 260.880606 -267.272262)
					(mid 260.916527 -267.257383)
					(end 260.931406 -267.221462)
				)
				(arc
					(start 260.931406 -266.812522)
					(mid 260.916527 -266.776601)
					(end 260.880606 -266.761722)
				)
				(arc
					(start 259.481066 -266.761722)
					(mid 259.445145 -266.776601)
					(end 259.430266 -266.812522)
				)
			)
		)
	)
	(zone
		(layers "In1.Cu" "In2.Cu")
		(hatch none 0.5)
		(connect_pads
			(clearance 0)
		)
		(min_thickness 0.25)
		(keepout
			(tracks not_allowed)
			(vias allowed)
			(pads allowed)
			(copperpour not_allowed)
			(footprints allowed)
		)
		(placement
			(enabled no)
			(sheetname "")
		)
		(fill yes
			(thermal_gap 0.5)
			(thermal_bridge_width 0.5)
			(island_removal_mode 0)
		)
		(polygon
			(pts
				(arc
					(start 289.605466 -214.521542)
					(mid 289.620345 -214.557463)
					(end 289.656266 -214.572342)
				)
				(arc
					(start 291.055806 -214.572342)
					(mid 291.091727 -214.557463)
					(end 291.106606 -214.521542)
				)
				(arc
					(start 291.106606 -214.112602)
					(mid 291.091727 -214.076681)
					(end 291.055806 -214.061802)
				)
				(arc
					(start 289.656266 -214.061802)
					(mid 289.620345 -214.076681)
					(end 289.605466 -214.112602)
				)
			)
		)
	)
	(zone
		(layers "In1.Cu" "In2.Cu")
		(hatch none 0.5)
		(connect_pads
			(clearance 0)
		)
		(min_thickness 0.25)
		(keepout
			(tracks not_allowed)
			(vias allowed)
			(pads allowed)
			(copperpour not_allowed)
			(footprints allowed)
		)
		(placement
			(enabled no)
			(sheetname "")
		)
		(fill yes
			(thermal_gap 0.5)
			(thermal_bridge_width 0.5)
			(island_removal_mode 0)
		)
		(polygon
			(pts
				(arc
					(start 199.881998 -199.221344)
					(mid 199.896877 -199.257265)
					(end 199.932798 -199.272144)
				)
				(arc
					(start 201.332338 -199.272144)
					(mid 201.368259 -199.257265)
					(end 201.383138 -199.221344)
				)
				(arc
					(start 201.383138 -198.812404)
					(mid 201.368259 -198.776483)
					(end 201.332338 -198.761604)
				)
				(arc
					(start 199.932798 -198.761604)
					(mid 199.896877 -198.776483)
					(end 199.881998 -198.812404)
				)
			)
		)
	)
	(zone
		(layers "In1.Cu" "In2.Cu")
		(hatch none 0.5)
		(connect_pads
			(clearance 0)
		)
		(min_thickness 0.25)
		(keepout
			(tracks not_allowed)
			(vias allowed)
			(pads allowed)
			(copperpour not_allowed)
			(footprints allowed)
		)
		(placement
			(enabled no)
			(sheetname "")
		)
		(fill yes
			(thermal_gap 0.5)
			(thermal_bridge_width 0.5)
			(island_removal_mode 0)
		)
		(polygon
			(pts
				(arc
					(start 188.23813 -282.521406)
					(mid 188.253009 -282.557327)
					(end 188.28893 -282.572206)
				)
				(arc
					(start 189.68847 -282.572206)
					(mid 189.724391 -282.557327)
					(end 189.73927 -282.521406)
				)
				(arc
					(start 189.73927 -282.112466)
					(mid 189.724391 -282.076545)
					(end 189.68847 -282.061666)
				)
				(arc
					(start 188.28893 -282.061666)
					(mid 188.253009 -282.076545)
					(end 188.23813 -282.112466)
				)
			)
		)
	)
	(zone
		(layers "In1.Cu" "In2.Cu")
		(hatch none 0.5)
		(connect_pads
			(clearance 0)
		)
		(min_thickness 0.25)
		(keepout
			(tracks not_allowed)
			(vias allowed)
			(pads allowed)
			(copperpour not_allowed)
			(footprints allowed)
		)
		(placement
			(enabled no)
			(sheetname "")
		)
		(fill yes
			(thermal_gap 0.5)
			(thermal_bridge_width 0.5)
			(island_removal_mode 0)
		)
		(polygon
			(pts
				(arc
					(start 406.002998 -291.8714)
					(mid 406.017877 -291.907321)
					(end 406.053798 -291.9222)
				)
				(arc
					(start 407.453338 -291.9222)
					(mid 407.489259 -291.907321)
					(end 407.504138 -291.8714)
				)
				(arc
					(start 407.504138 -291.46246)
					(mid 407.489259 -291.426539)
					(end 407.453338 -291.41166)
				)
				(arc
					(start 406.053798 -291.41166)
					(mid 406.017877 -291.426539)
					(end 406.002998 -291.46246)
				)
			)
		)
	)
	(zone
		(layers "In1.Cu" "In2.Cu")
		(hatch none 0.5)
		(connect_pads
			(clearance 0)
		)
		(min_thickness 0.25)
		(keepout
			(tracks not_allowed)
			(vias allowed)
			(pads allowed)
			(copperpour not_allowed)
			(footprints allowed)
		)
		(placement
			(enabled no)
			(sheetname "")
		)
		(fill yes
			(thermal_gap 0.5)
			(thermal_bridge_width 0.5)
			(island_removal_mode 0)
		)
		(polygon
			(pts
				(arc
					(start 165.60673 -307.171344)
					(mid 165.621609 -307.207265)
					(end 165.65753 -307.222144)
				)
				(arc
					(start 167.05707 -307.222144)
					(mid 167.092991 -307.207265)
					(end 167.10787 -307.171344)
				)
				(arc
					(start 167.10787 -306.762404)
					(mid 167.092991 -306.726483)
					(end 167.05707 -306.711604)
				)
				(arc
					(start 165.65753 -306.711604)
					(mid 165.621609 -306.726483)
					(end 165.60673 -306.762404)
				)
			)
		)
	)
	(zone
		(layers "In1.Cu" "In2.Cu")
		(hatch none 0.5)
		(connect_pads
			(clearance 0)
		)
		(min_thickness 0.25)
		(keepout
			(tracks not_allowed)
			(vias allowed)
			(pads allowed)
			(copperpour not_allowed)
			(footprints allowed)
		)
		(placement
			(enabled no)
			(sheetname "")
		)
		(fill yes
			(thermal_gap 0.5)
			(thermal_bridge_width 0.5)
			(island_removal_mode 0)
		)
		(polygon
			(pts
				(arc
					(start 188.23813 -308.871366)
					(mid 188.253009 -308.907287)
					(end 188.28893 -308.922166)
				)
				(arc
					(start 189.68847 -308.922166)
					(mid 189.724391 -308.907287)
					(end 189.73927 -308.871366)
				)
				(arc
					(start 189.73927 -308.462426)
					(mid 189.724391 -308.426505)
					(end 189.68847 -308.411626)
				)
				(arc
					(start 188.28893 -308.411626)
					(mid 188.253009 -308.426505)
					(end 188.23813 -308.462426)
				)
			)
		)
	)
	(zone
		(layers "In1.Cu" "In2.Cu")
		(hatch none 0.5)
		(connect_pads
			(clearance 0)
		)
		(min_thickness 0.25)
		(keepout
			(tracks not_allowed)
			(vias allowed)
			(pads allowed)
			(copperpour not_allowed)
			(footprints allowed)
		)
		(placement
			(enabled no)
			(sheetname "")
		)
		(fill yes
			(thermal_gap 0.5)
			(thermal_bridge_width 0.5)
			(island_removal_mode 0)
		)
		(polygon
			(pts
				(arc
					(start 436.178198 -241.721386)
					(mid 436.193077 -241.757307)
					(end 436.228998 -241.772186)
				)
				(arc
					(start 437.628538 -241.772186)
					(mid 437.664459 -241.757307)
					(end 437.679338 -241.721386)
				)
				(arc
					(start 437.679338 -241.312446)
					(mid 437.664459 -241.276525)
					(end 437.628538 -241.261646)
				)
				(arc
					(start 436.228998 -241.261646)
					(mid 436.193077 -241.276525)
					(end 436.178198 -241.312446)
				)
			)
		)
	)
	(zone
		(layers "In1.Cu" "In2.Cu")
		(hatch none 0.5)
		(connect_pads
			(clearance 0)
		)
		(min_thickness 0.25)
		(keepout
			(tracks not_allowed)
			(vias allowed)
			(pads allowed)
			(copperpour not_allowed)
			(footprints allowed)
		)
		(placement
			(enabled no)
			(sheetname "")
		)
		(fill yes
			(thermal_gap 0.5)
			(thermal_bridge_width 0.5)
			(island_removal_mode 0)
		)
		(polygon
			(pts
				(arc
					(start 195.78193 -241.721386)
					(mid 195.796809 -241.757307)
					(end 195.83273 -241.772186)
				)
				(arc
					(start 197.23227 -241.772186)
					(mid 197.268191 -241.757307)
					(end 197.28307 -241.721386)
				)
				(arc
					(start 197.28307 -241.312446)
					(mid 197.268191 -241.276525)
					(end 197.23227 -241.261646)
				)
				(arc
					(start 195.83273 -241.261646)
					(mid 195.796809 -241.276525)
					(end 195.78193 -241.312446)
				)
			)
		)
	)
	(zone
		(layers "In1.Cu" "In2.Cu")
		(hatch none 0.5)
		(connect_pads
			(clearance 0)
		)
		(min_thickness 0.25)
		(keepout
			(tracks not_allowed)
			(vias allowed)
			(pads allowed)
			(copperpour not_allowed)
			(footprints allowed)
		)
		(placement
			(enabled no)
			(sheetname "")
		)
		(fill yes
			(thermal_gap 0.5)
			(thermal_bridge_width 0.5)
			(island_removal_mode 0)
		)
		(polygon
			(pts
				(arc
					(start 184.794398 -289.321494)
					(mid 184.809277 -289.357415)
					(end 184.845198 -289.372294)
				)
				(arc
					(start 186.244738 -289.372294)
					(mid 186.280659 -289.357415)
					(end 186.295538 -289.321494)
				)
				(arc
					(start 186.295538 -288.912554)
					(mid 186.280659 -288.876633)
					(end 186.244738 -288.861754)
				)
				(arc
					(start 184.845198 -288.861754)
					(mid 184.809277 -288.876633)
					(end 184.794398 -288.912554)
				)
			)
		)
	)
	(zone
		(layers "In1.Cu" "In2.Cu")
		(hatch none 0.5)
		(connect_pads
			(clearance 0)
		)
		(min_thickness 0.25)
		(keepout
			(tracks not_allowed)
			(vias allowed)
			(pads allowed)
			(copperpour not_allowed)
			(footprints allowed)
		)
		(placement
			(enabled no)
			(sheetname "")
		)
		(fill yes
			(thermal_gap 0.5)
			(thermal_bridge_width 0.5)
			(island_removal_mode 0)
		)
		(polygon
			(pts
				(arc
					(start 199.881998 -291.021516)
					(mid 199.896877 -291.057437)
					(end 199.932798 -291.072316)
				)
				(arc
					(start 201.332338 -291.072316)
					(mid 201.368259 -291.057437)
					(end 201.383138 -291.021516)
				)
				(arc
					(start 201.383138 -290.612576)
					(mid 201.368259 -290.576655)
					(end 201.332338 -290.561776)
				)
				(arc
					(start 199.932798 -290.561776)
					(mid 199.896877 -290.576655)
					(end 199.881998 -290.612576)
				)
			)
		)
	)
	(zone
		(layers "In1.Cu" "In2.Cu")
		(hatch none 0.5)
		(connect_pads
			(clearance 0)
		)
		(min_thickness 0.25)
		(keepout
			(tracks not_allowed)
			(vias allowed)
			(pads allowed)
			(copperpour not_allowed)
			(footprints allowed)
		)
		(placement
			(enabled no)
			(sheetname "")
		)
		(fill yes
			(thermal_gap 0.5)
			(thermal_bridge_width 0.5)
			(island_removal_mode 0)
		)
		(polygon
			(pts
				(arc
					(start 293.049198 -262.971534)
					(mid 293.064077 -263.007455)
					(end 293.099998 -263.022334)
				)
				(arc
					(start 294.499538 -263.022334)
					(mid 294.535459 -263.007455)
					(end 294.550338 -262.971534)
				)
				(arc
					(start 294.550338 -262.562594)
					(mid 294.535459 -262.526673)
					(end 294.499538 -262.511794)
				)
				(arc
					(start 293.099998 -262.511794)
					(mid 293.064077 -262.526673)
					(end 293.049198 -262.562594)
				)
			)
		)
	)
	(zone
		(layers "In1.Cu" "In2.Cu")
		(hatch none 0.5)
		(connect_pads
			(clearance 0)
		)
		(min_thickness 0.25)
		(keepout
			(tracks not_allowed)
			(vias allowed)
			(pads allowed)
			(copperpour not_allowed)
			(footprints allowed)
		)
		(placement
			(enabled no)
			(sheetname "")
		)
		(fill yes
			(thermal_gap 0.5)
			(thermal_bridge_width 0.5)
			(island_removal_mode 0)
		)
		(polygon
			(pts
				(arc
					(start 282.061666 -237.471458)
					(mid 282.076545 -237.507379)
					(end 282.112466 -237.522258)
				)
				(arc
					(start 283.512006 -237.522258)
					(mid 283.547927 -237.507379)
					(end 283.562806 -237.471458)
				)
				(arc
					(start 283.562806 -237.062518)
					(mid 283.547927 -237.026597)
					(end 283.512006 -237.011718)
				)
				(arc
					(start 282.112466 -237.011718)
					(mid 282.076545 -237.026597)
					(end 282.061666 -237.062518)
				)
			)
		)
	)
	(zone
		(layers "In1.Cu" "In2.Cu")
		(hatch none 0.5)
		(connect_pads
			(clearance 0)
		)
		(min_thickness 0.25)
		(keepout
			(tracks not_allowed)
			(vias allowed)
			(pads allowed)
			(copperpour not_allowed)
			(footprints allowed)
		)
		(placement
			(enabled no)
			(sheetname "")
		)
		(fill yes
			(thermal_gap 0.5)
			(thermal_bridge_width 0.5)
			(island_removal_mode 0)
		)
		(polygon
			(pts
				(arc
					(start 447.822066 -281.671522)
					(mid 447.836945 -281.707443)
					(end 447.872866 -281.722322)
				)
				(arc
					(start 449.272406 -281.722322)
					(mid 449.308327 -281.707443)
					(end 449.323206 -281.671522)
				)
				(arc
					(start 449.323206 -281.262582)
					(mid 449.308327 -281.226661)
					(end 449.272406 -281.211782)
				)
				(arc
					(start 447.872866 -281.211782)
					(mid 447.836945 -281.226661)
					(end 447.822066 -281.262582)
				)
			)
		)
	)
	(zone
		(layers "In1.Cu" "In2.Cu")
		(hatch none 0.5)
		(connect_pads
			(clearance 0)
		)
		(min_thickness 0.25)
		(keepout
			(tracks not_allowed)
			(vias allowed)
			(pads allowed)
			(copperpour not_allowed)
			(footprints allowed)
		)
		(placement
			(enabled no)
			(sheetname "")
		)
		(fill yes
			(thermal_gap 0.5)
			(thermal_bridge_width 0.5)
			(island_removal_mode 0)
		)
		(polygon
			(pts
				(arc
					(start 26.577798 -302.071532)
					(mid 26.592677 -302.107453)
					(end 26.628598 -302.122332)
				)
				(arc
					(start 28.028138 -302.122332)
					(mid 28.064059 -302.107453)
					(end 28.078938 -302.071532)
				)
				(arc
					(start 28.078938 -301.662592)
					(mid 28.064059 -301.626671)
					(end 28.028138 -301.611792)
				)
				(arc
					(start 26.628598 -301.611792)
					(mid 26.592677 -301.626671)
					(end 26.577798 -301.662592)
				)
			)
		)
	)
	(zone
		(layers "In1.Cu" "In2.Cu")
		(hatch none 0.5)
		(connect_pads
			(clearance 0)
		)
		(min_thickness 0.25)
		(keepout
			(tracks not_allowed)
			(vias allowed)
			(pads allowed)
			(copperpour not_allowed)
			(footprints allowed)
		)
		(placement
			(enabled no)
			(sheetname "")
		)
		(fill yes
			(thermal_gap 0.5)
			(thermal_bridge_width 0.5)
			(island_removal_mode 0)
		)
		(polygon
			(pts
				(arc
					(start 293.049198 -209.421476)
					(mid 293.064077 -209.457397)
					(end 293.099998 -209.472276)
				)
				(arc
					(start 294.499538 -209.472276)
					(mid 294.535459 -209.457397)
					(end 294.550338 -209.421476)
				)
				(arc
					(start 294.550338 -209.012536)
					(mid 294.535459 -208.976615)
					(end 294.499538 -208.961736)
				)
				(arc
					(start 293.099998 -208.961736)
					(mid 293.064077 -208.976615)
					(end 293.049198 -209.012536)
				)
			)
		)
	)
	(zone
		(layers "In1.Cu" "In2.Cu")
		(hatch none 0.5)
		(connect_pads
			(clearance 0)
		)
		(min_thickness 0.25)
		(keepout
			(tracks not_allowed)
			(vias allowed)
			(pads allowed)
			(copperpour not_allowed)
			(footprints allowed)
		)
		(placement
			(enabled no)
			(sheetname "")
		)
		(fill yes
			(thermal_gap 0.5)
			(thermal_bridge_width 0.5)
			(island_removal_mode 0)
		)
		(polygon
			(pts
				(arc
					(start 443.721998 -269.771368)
					(mid 443.736877 -269.807289)
					(end 443.772798 -269.822168)
				)
				(arc
					(start 445.172338 -269.822168)
					(mid 445.208259 -269.807289)
					(end 445.223138 -269.771368)
				)
				(arc
					(start 445.223138 -269.362428)
					(mid 445.208259 -269.326507)
					(end 445.172338 -269.311628)
				)
				(arc
					(start 443.772798 -269.311628)
					(mid 443.736877 -269.326507)
					(end 443.721998 -269.362428)
				)
			)
		)
	)
	(zone
		(layers "In1.Cu" "In2.Cu")
		(hatch none 0.5)
		(connect_pads
			(clearance 0)
		)
		(min_thickness 0.25)
		(keepout
			(tracks not_allowed)
			(vias allowed)
			(pads allowed)
			(copperpour not_allowed)
			(footprints allowed)
		)
		(placement
			(enabled no)
			(sheetname "")
		)
		(fill yes
			(thermal_gap 0.5)
			(thermal_bridge_width 0.5)
			(island_removal_mode 0)
		)
		(polygon
			(pts
				(arc
					(start 440.278266 -208.571338)
					(mid 440.293145 -208.607259)
					(end 440.329066 -208.622138)
				)
				(arc
					(start 441.728606 -208.622138)
					(mid 441.764527 -208.607259)
					(end 441.779406 -208.571338)
				)
				(arc
					(start 441.779406 -208.162398)
					(mid 441.764527 -208.126477)
					(end 441.728606 -208.111598)
				)
				(arc
					(start 440.329066 -208.111598)
					(mid 440.293145 -208.126477)
					(end 440.278266 -208.162398)
				)
			)
		)
	)
	(zone
		(layers "In1.Cu" "In2.Cu")
		(hatch none 0.5)
		(connect_pads
			(clearance 0)
		)
		(min_thickness 0.25)
		(keepout
			(tracks not_allowed)
			(vias allowed)
			(pads allowed)
			(copperpour not_allowed)
			(footprints allowed)
		)
		(placement
			(enabled no)
			(sheetname "")
		)
		(fill yes
			(thermal_gap 0.5)
			(thermal_bridge_width 0.5)
			(island_removal_mode 0)
		)
		(polygon
			(pts
				(arc
					(start 436.178198 -251.07138)
					(mid 436.193077 -251.107301)
					(end 436.228998 -251.12218)
				)
				(arc
					(start 437.628538 -251.12218)
					(mid 437.664459 -251.107301)
					(end 437.679338 -251.07138)
				)
				(arc
					(start 437.679338 -250.66244)
					(mid 437.664459 -250.626519)
					(end 437.628538 -250.61164)
				)
				(arc
					(start 436.228998 -250.61164)
					(mid 436.193077 -250.626519)
					(end 436.178198 -250.66244)
				)
			)
		)
	)
	(zone
		(layers "In1.Cu" "In2.Cu")
		(hatch none 0.5)
		(connect_pads
			(clearance 0)
		)
		(min_thickness 0.25)
		(keepout
			(tracks not_allowed)
			(vias allowed)
			(pads allowed)
			(copperpour not_allowed)
			(footprints allowed)
		)
		(placement
			(enabled no)
			(sheetname "")
		)
		(fill yes
			(thermal_gap 0.5)
			(thermal_bridge_width 0.5)
			(island_removal_mode 0)
		)
		(polygon
			(pts
				(arc
					(start 49.209198 -291.021516)
					(mid 49.224077 -291.057437)
					(end 49.259998 -291.072316)
				)
				(arc
					(start 50.659538 -291.072316)
					(mid 50.695459 -291.057437)
					(end 50.710338 -291.021516)
				)
				(arc
					(start 50.710338 -290.612576)
					(mid 50.695459 -290.576655)
					(end 50.659538 -290.561776)
				)
				(arc
					(start 49.259998 -290.561776)
					(mid 49.224077 -290.576655)
					(end 49.209198 -290.612576)
				)
			)
		)
	)
	(zone
		(layers "In1.Cu" "In2.Cu")
		(hatch none 0.5)
		(connect_pads
			(clearance 0)
		)
		(min_thickness 0.25)
		(keepout
			(tracks not_allowed)
			(vias allowed)
			(pads allowed)
			(copperpour not_allowed)
			(footprints allowed)
		)
		(placement
			(enabled no)
			(sheetname "")
		)
		(fill yes
			(thermal_gap 0.5)
			(thermal_bridge_width 0.5)
			(island_removal_mode 0)
		)
		(polygon
			(pts
				(arc
					(start 417.646866 -270.621506)
					(mid 417.661745 -270.657427)
					(end 417.697666 -270.672306)
				)
				(arc
					(start 419.097206 -270.672306)
					(mid 419.133127 -270.657427)
					(end 419.148006 -270.621506)
				)
				(arc
					(start 419.148006 -270.212566)
					(mid 419.133127 -270.176645)
					(end 419.097206 -270.161766)
				)
				(arc
					(start 417.697666 -270.161766)
					(mid 417.661745 -270.176645)
					(end 417.646866 -270.212566)
				)
			)
		)
	)
	(zone
		(layers "In1.Cu" "In2.Cu")
		(hatch none 0.5)
		(connect_pads
			(clearance 0)
		)
		(min_thickness 0.25)
		(keepout
			(tracks not_allowed)
			(vias allowed)
			(pads allowed)
			(copperpour not_allowed)
			(footprints allowed)
		)
		(placement
			(enabled no)
			(sheetname "")
		)
		(fill yes
			(thermal_gap 0.5)
			(thermal_bridge_width 0.5)
			(island_removal_mode 0)
		)
		(polygon
			(pts
				(arc
					(start 169.706798 -274.02155)
					(mid 169.721677 -274.057471)
					(end 169.757598 -274.07235)
				)
				(arc
					(start 171.157138 -274.07235)
					(mid 171.193059 -274.057471)
					(end 171.207938 -274.02155)
				)
				(arc
					(start 171.207938 -273.61261)
					(mid 171.193059 -273.576689)
					(end 171.157138 -273.56181)
				)
				(arc
					(start 169.757598 -273.56181)
					(mid 169.721677 -273.576689)
					(end 169.706798 -273.61261)
				)
			)
		)
	)
	(zone
		(layers "In1.Cu" "In2.Cu")
		(hatch none 0.5)
		(connect_pads
			(clearance 0)
		)
		(min_thickness 0.25)
		(keepout
			(tracks not_allowed)
			(vias allowed)
			(pads allowed)
			(copperpour not_allowed)
			(footprints allowed)
		)
		(placement
			(enabled no)
			(sheetname "")
		)
		(fill yes
			(thermal_gap 0.5)
			(thermal_bridge_width 0.5)
			(island_removal_mode 0)
		)
		(polygon
			(pts
				(arc
					(start 436.178198 -293.571422)
					(mid 436.193077 -293.607343)
					(end 436.228998 -293.622222)
				)
				(arc
					(start 437.628538 -293.622222)
					(mid 437.664459 -293.607343)
					(end 437.679338 -293.571422)
				)
				(arc
					(start 437.679338 -293.162482)
					(mid 437.664459 -293.126561)
					(end 437.628538 -293.111682)
				)
				(arc
					(start 436.228998 -293.111682)
					(mid 436.193077 -293.126561)
					(end 436.178198 -293.162482)
				)
			)
		)
	)
	(zone
		(layers "In1.Cu" "In2.Cu")
		(hatch none 0.5)
		(connect_pads
			(clearance 0)
		)
		(min_thickness 0.25)
		(keepout
			(tracks not_allowed)
			(vias allowed)
			(pads allowed)
			(copperpour not_allowed)
			(footprints allowed)
		)
		(placement
			(enabled no)
			(sheetname "")
		)
		(fill yes
			(thermal_gap 0.5)
			(thermal_bridge_width 0.5)
			(island_removal_mode 0)
		)
		(polygon
			(pts
				(arc
					(start 210.86953 -269.771368)
					(mid 210.884409 -269.807289)
					(end 210.92033 -269.822168)
				)
				(arc
					(start 212.31987 -269.822168)
					(mid 212.355791 -269.807289)
					(end 212.37067 -269.771368)
				)
				(arc
					(start 212.37067 -269.362428)
					(mid 212.355791 -269.326507)
					(end 212.31987 -269.311628)
				)
				(arc
					(start 210.92033 -269.311628)
					(mid 210.884409 -269.326507)
					(end 210.86953 -269.362428)
				)
			)
		)
	)
	(zone
		(layers "In1.Cu" "In2.Cu")
		(hatch none 0.5)
		(connect_pads
			(clearance 0)
		)
		(min_thickness 0.25)
		(keepout
			(tracks not_allowed)
			(vias allowed)
			(pads allowed)
			(copperpour not_allowed)
			(footprints allowed)
		)
		(placement
			(enabled no)
			(sheetname "")
		)
		(fill yes
			(thermal_gap 0.5)
			(thermal_bridge_width 0.5)
			(island_removal_mode 0)
		)
		(polygon
			(pts
				(arc
					(start 458.809598 -288.471356)
					(mid 458.824477 -288.507277)
					(end 458.860398 -288.522156)
				)
				(arc
					(start 460.259938 -288.522156)
					(mid 460.295859 -288.507277)
					(end 460.310738 -288.471356)
				)
				(arc
					(start 460.310738 -288.062416)
					(mid 460.295859 -288.026495)
					(end 460.259938 -288.011616)
				)
				(arc
					(start 458.860398 -288.011616)
					(mid 458.824477 -288.026495)
					(end 458.809598 -288.062416)
				)
			)
		)
	)
	(zone
		(layers "In1.Cu" "In2.Cu")
		(hatch none 0.5)
		(connect_pads
			(clearance 0)
		)
		(min_thickness 0.25)
		(keepout
			(tracks not_allowed)
			(vias allowed)
			(pads allowed)
			(copperpour not_allowed)
			(footprints allowed)
		)
		(placement
			(enabled no)
			(sheetname "")
		)
		(fill yes
			(thermal_gap 0.5)
			(thermal_bridge_width 0.5)
			(island_removal_mode 0)
		)
		(polygon
			(pts
				(arc
					(start 173.15053 -261.271512)
					(mid 173.165409 -261.307433)
					(end 173.20133 -261.322312)
				)
				(arc
					(start 174.60087 -261.322312)
					(mid 174.636791 -261.307433)
					(end 174.65167 -261.271512)
				)
				(arc
					(start 174.65167 -260.862572)
					(mid 174.636791 -260.826651)
					(end 174.60087 -260.811772)
				)
				(arc
					(start 173.20133 -260.811772)
					(mid 173.165409 -260.826651)
					(end 173.15053 -260.862572)
				)
			)
		)
	)
	(zone
		(layers "In1.Cu" "In2.Cu")
		(hatch none 0.5)
		(connect_pads
			(clearance 0)
		)
		(min_thickness 0.25)
		(keepout
			(tracks not_allowed)
			(vias allowed)
			(pads allowed)
			(copperpour not_allowed)
			(footprints allowed)
		)
		(placement
			(enabled no)
			(sheetname "")
		)
		(fill yes
			(thermal_gap 0.5)
			(thermal_bridge_width 0.5)
			(island_removal_mode 0)
		)
		(polygon
			(pts
				(arc
					(start 177.250598 -225.571304)
					(mid 177.265477 -225.607225)
					(end 177.301398 -225.622104)
				)
				(arc
					(start 178.700938 -225.622104)
					(mid 178.736859 -225.607225)
					(end 178.751738 -225.571304)
				)
				(arc
					(start 178.751738 -225.162364)
					(mid 178.736859 -225.126443)
					(end 178.700938 -225.111564)
				)
				(arc
					(start 177.301398 -225.111564)
					(mid 177.265477 -225.126443)
					(end 177.250598 -225.162364)
				)
			)
		)
	)
	(zone
		(layers "In1.Cu" "In2.Cu")
		(hatch none 0.5)
		(connect_pads
			(clearance 0)
		)
		(min_thickness 0.25)
		(keepout
			(tracks not_allowed)
			(vias allowed)
			(pads allowed)
			(copperpour not_allowed)
			(footprints allowed)
		)
		(placement
			(enabled no)
			(sheetname "")
		)
		(fill yes
			(thermal_gap 0.5)
			(thermal_bridge_width 0.5)
			(island_removal_mode 0)
		)
		(polygon
			(pts
				(arc
					(start 52.65293 -221.321376)
					(mid 52.667809 -221.357297)
					(end 52.70373 -221.372176)
				)
				(arc
					(start 54.10327 -221.372176)
					(mid 54.139191 -221.357297)
					(end 54.15407 -221.321376)
				)
				(arc
					(start 54.15407 -220.912436)
					(mid 54.139191 -220.876515)
					(end 54.10327 -220.861636)
				)
				(arc
					(start 52.70373 -220.861636)
					(mid 52.667809 -220.876515)
					(end 52.65293 -220.912436)
				)
			)
		)
	)
	(zone
		(layers "In1.Cu" "In2.Cu")
		(hatch none 0.5)
		(connect_pads
			(clearance 0)
		)
		(min_thickness 0.25)
		(keepout
			(tracks not_allowed)
			(vias allowed)
			(pads allowed)
			(copperpour not_allowed)
			(footprints allowed)
		)
		(placement
			(enabled no)
			(sheetname "")
		)
		(fill yes
			(thermal_gap 0.5)
			(thermal_bridge_width 0.5)
			(island_removal_mode 0)
		)
		(polygon
			(pts
				(arc
					(start 192.338198 -239.17148)
					(mid 192.353077 -239.207401)
					(end 192.388998 -239.22228)
				)
				(arc
					(start 193.788538 -239.22228)
					(mid 193.824459 -239.207401)
					(end 193.839338 -239.17148)
				)
				(arc
					(start 193.839338 -238.76254)
					(mid 193.824459 -238.726619)
					(end 193.788538 -238.71174)
				)
				(arc
					(start 192.388998 -238.71174)
					(mid 192.353077 -238.726619)
					(end 192.338198 -238.76254)
				)
			)
		)
	)
	(zone
		(layers "In1.Cu" "In2.Cu")
		(hatch none 0.5)
		(connect_pads
			(clearance 0)
		)
		(min_thickness 0.25)
		(keepout
			(tracks not_allowed)
			(vias allowed)
			(pads allowed)
			(copperpour not_allowed)
			(footprints allowed)
		)
		(placement
			(enabled no)
			(sheetname "")
		)
		(fill yes
			(thermal_gap 0.5)
			(thermal_bridge_width 0.5)
			(island_removal_mode 0)
		)
		(polygon
			(pts
				(arc
					(start 165.60673 -313.121294)
					(mid 165.621609 -313.157215)
					(end 165.65753 -313.172094)
				)
				(arc
					(start 167.05707 -313.172094)
					(mid 167.092991 -313.157215)
					(end 167.10787 -313.121294)
				)
				(arc
					(start 167.10787 -312.712354)
					(mid 167.092991 -312.676433)
					(end 167.05707 -312.661554)
				)
				(arc
					(start 165.65753 -312.661554)
					(mid 165.621609 -312.676433)
					(end 165.60673 -312.712354)
				)
			)
		)
	)
	(zone
		(layers "In1.Cu" "In2.Cu")
		(hatch none 0.5)
		(connect_pads
			(clearance 0)
		)
		(min_thickness 0.25)
		(keepout
			(tracks not_allowed)
			(vias allowed)
			(pads allowed)
			(copperpour not_allowed)
			(footprints allowed)
		)
		(placement
			(enabled no)
			(sheetname "")
		)
		(fill yes
			(thermal_gap 0.5)
			(thermal_bridge_width 0.5)
			(island_removal_mode 0)
		)
		(polygon
			(pts
				(arc
					(start 304.693066 -217.921332)
					(mid 304.707945 -217.957253)
					(end 304.743866 -217.972132)
				)
				(arc
					(start 306.143406 -217.972132)
					(mid 306.179327 -217.957253)
					(end 306.194206 -217.921332)
				)
				(arc
					(start 306.194206 -217.512392)
					(mid 306.179327 -217.476471)
					(end 306.143406 -217.461592)
				)
				(arc
					(start 304.743866 -217.461592)
					(mid 304.707945 -217.476471)
					(end 304.693066 -217.512392)
				)
			)
		)
	)
	(zone
		(layers "In1.Cu" "In2.Cu")
		(hatch none 0.5)
		(connect_pads
			(clearance 0)
		)
		(min_thickness 0.25)
		(keepout
			(tracks not_allowed)
			(vias allowed)
			(pads allowed)
			(copperpour not_allowed)
			(footprints allowed)
		)
		(placement
			(enabled no)
			(sheetname "")
		)
		(fill yes
			(thermal_gap 0.5)
			(thermal_bridge_width 0.5)
			(island_removal_mode 0)
		)
		(polygon
			(pts
				(arc
					(start 34.121598 -311.421526)
					(mid 34.136477 -311.457447)
					(end 34.172398 -311.472326)
				)
				(arc
					(start 35.571938 -311.472326)
					(mid 35.607859 -311.457447)
					(end 35.622738 -311.421526)
				)
				(arc
					(start 35.622738 -311.012586)
					(mid 35.607859 -310.976665)
					(end 35.571938 -310.961786)
				)
				(arc
					(start 34.172398 -310.961786)
					(mid 34.136477 -310.976665)
					(end 34.121598 -311.012586)
				)
			)
		)
	)
	(zone
		(layers "In1.Cu" "In2.Cu")
		(hatch none 0.5)
		(connect_pads
			(clearance 0)
		)
		(min_thickness 0.25)
		(keepout
			(tracks not_allowed)
			(vias allowed)
			(pads allowed)
			(copperpour not_allowed)
			(footprints allowed)
		)
		(placement
			(enabled no)
			(sheetname "")
		)
		(fill yes
			(thermal_gap 0.5)
			(thermal_bridge_width 0.5)
			(island_removal_mode 0)
		)
		(polygon
			(pts
				(arc
					(start 297.149266 -214.521542)
					(mid 297.164145 -214.557463)
					(end 297.200066 -214.572342)
				)
				(arc
					(start 298.599606 -214.572342)
					(mid 298.635527 -214.557463)
					(end 298.650406 -214.521542)
				)
				(arc
					(start 298.650406 -214.112602)
					(mid 298.635527 -214.076681)
					(end 298.599606 -214.061802)
				)
				(arc
					(start 297.200066 -214.061802)
					(mid 297.164145 -214.076681)
					(end 297.149266 -214.112602)
				)
			)
		)
	)
	(zone
		(layers "In1.Cu" "In2.Cu")
		(hatch none 0.5)
		(connect_pads
			(clearance 0)
		)
		(min_thickness 0.25)
		(keepout
			(tracks not_allowed)
			(vias allowed)
			(pads allowed)
			(copperpour not_allowed)
			(footprints allowed)
		)
		(placement
			(enabled no)
			(sheetname "")
		)
		(fill yes
			(thermal_gap 0.5)
			(thermal_bridge_width 0.5)
			(island_removal_mode 0)
		)
		(polygon
			(pts
				(arc
					(start 413.546798 -200.921366)
					(mid 413.561677 -200.957287)
					(end 413.597598 -200.972166)
				)
				(arc
					(start 414.997138 -200.972166)
					(mid 415.033059 -200.957287)
					(end 415.047938 -200.921366)
				)
				(arc
					(start 415.047938 -200.512426)
					(mid 415.033059 -200.476505)
					(end 414.997138 -200.461626)
				)
				(arc
					(start 413.597598 -200.461626)
					(mid 413.561677 -200.476505)
					(end 413.546798 -200.512426)
				)
			)
		)
	)
	(zone
		(layers "In1.Cu" "In2.Cu")
		(hatch none 0.5)
		(connect_pads
			(clearance 0)
		)
		(min_thickness 0.25)
		(keepout
			(tracks not_allowed)
			(vias allowed)
			(pads allowed)
			(copperpour not_allowed)
			(footprints allowed)
		)
		(placement
			(enabled no)
			(sheetname "")
		)
		(fill yes
			(thermal_gap 0.5)
			(thermal_bridge_width 0.5)
			(island_removal_mode 0)
		)
		(polygon
			(pts
				(arc
					(start 282.061666 -306.32146)
					(mid 282.076545 -306.357381)
					(end 282.112466 -306.37226)
				)
				(arc
					(start 283.512006 -306.37226)
					(mid 283.547927 -306.357381)
					(end 283.562806 -306.32146)
				)
				(arc
					(start 283.562806 -305.91252)
					(mid 283.547927 -305.876599)
					(end 283.512006 -305.86172)
				)
				(arc
					(start 282.112466 -305.86172)
					(mid 282.076545 -305.876599)
					(end 282.061666 -305.91252)
				)
			)
		)
	)
	(zone
		(layers "In1.Cu" "In2.Cu")
		(hatch none 0.5)
		(connect_pads
			(clearance 0)
		)
		(min_thickness 0.25)
		(keepout
			(tracks not_allowed)
			(vias allowed)
			(pads allowed)
			(copperpour not_allowed)
			(footprints allowed)
		)
		(placement
			(enabled no)
			(sheetname "")
		)
		(fill yes
			(thermal_gap 0.5)
			(thermal_bridge_width 0.5)
			(island_removal_mode 0)
		)
		(polygon
			(pts
				(arc
					(start 162.162998 -259.57149)
					(mid 162.177877 -259.607411)
					(end 162.213798 -259.62229)
				)
				(arc
					(start 163.613338 -259.62229)
					(mid 163.649259 -259.607411)
					(end 163.664138 -259.57149)
				)
				(arc
					(start 163.664138 -259.16255)
					(mid 163.649259 -259.126629)
					(end 163.613338 -259.11175)
				)
				(arc
					(start 162.213798 -259.11175)
					(mid 162.177877 -259.126629)
					(end 162.162998 -259.16255)
				)
			)
		)
	)
	(zone
		(layers "In1.Cu" "In2.Cu")
		(hatch none 0.5)
		(connect_pads
			(clearance 0)
		)
		(min_thickness 0.25)
		(keepout
			(tracks not_allowed)
			(vias allowed)
			(pads allowed)
			(copperpour not_allowed)
			(footprints allowed)
		)
		(placement
			(enabled no)
			(sheetname "")
		)
		(fill yes
			(thermal_gap 0.5)
			(thermal_bridge_width 0.5)
			(island_removal_mode 0)
		)
		(polygon
			(pts
				(arc
					(start 26.577798 -263.821418)
					(mid 26.592677 -263.857339)
					(end 26.628598 -263.872218)
				)
				(arc
					(start 28.028138 -263.872218)
					(mid 28.064059 -263.857339)
					(end 28.078938 -263.821418)
				)
				(arc
					(start 28.078938 -263.412478)
					(mid 28.064059 -263.376557)
					(end 28.028138 -263.361678)
				)
				(arc
					(start 26.628598 -263.361678)
					(mid 26.592677 -263.376557)
					(end 26.577798 -263.412478)
				)
			)
		)
	)
	(zone
		(layers "In1.Cu" "In2.Cu")
		(hatch none 0.5)
		(connect_pads
			(clearance 0)
		)
		(min_thickness 0.25)
		(keepout
			(tracks not_allowed)
			(vias allowed)
			(pads allowed)
			(copperpour not_allowed)
			(footprints allowed)
		)
		(placement
			(enabled no)
			(sheetname "")
		)
		(fill yes
			(thermal_gap 0.5)
			(thermal_bridge_width 0.5)
			(island_removal_mode 0)
		)
		(polygon
			(pts
				(arc
					(start 297.149266 -302.921416)
					(mid 297.164145 -302.957337)
					(end 297.200066 -302.972216)
				)
				(arc
					(start 298.599606 -302.972216)
					(mid 298.635527 -302.957337)
					(end 298.650406 -302.921416)
				)
				(arc
					(start 298.650406 -302.512476)
					(mid 298.635527 -302.476555)
					(end 298.599606 -302.461676)
				)
				(arc
					(start 297.200066 -302.461676)
					(mid 297.164145 -302.476555)
					(end 297.149266 -302.512476)
				)
			)
		)
	)
	(zone
		(layers "In1.Cu" "In2.Cu")
		(hatch none 0.5)
		(connect_pads
			(clearance 0)
		)
		(min_thickness 0.25)
		(keepout
			(tracks not_allowed)
			(vias allowed)
			(pads allowed)
			(copperpour not_allowed)
			(footprints allowed)
		)
		(placement
			(enabled no)
			(sheetname "")
		)
		(fill yes
			(thermal_gap 0.5)
			(thermal_bridge_width 0.5)
			(island_removal_mode 0)
		)
		(polygon
			(pts
				(arc
					(start 432.734466 -302.921416)
					(mid 432.749345 -302.957337)
					(end 432.785266 -302.972216)
				)
				(arc
					(start 434.184806 -302.972216)
					(mid 434.220727 -302.957337)
					(end 434.235606 -302.921416)
				)
				(arc
					(start 434.235606 -302.512476)
					(mid 434.220727 -302.476555)
					(end 434.184806 -302.461676)
				)
				(arc
					(start 432.785266 -302.461676)
					(mid 432.749345 -302.476555)
					(end 432.734466 -302.512476)
				)
			)
		)
	)
	(zone
		(layers "In1.Cu" "In2.Cu")
		(hatch none 0.5)
		(connect_pads
			(clearance 0)
		)
		(min_thickness 0.25)
		(keepout
			(tracks not_allowed)
			(vias allowed)
			(pads allowed)
			(copperpour not_allowed)
			(footprints allowed)
		)
		(placement
			(enabled no)
			(sheetname "")
		)
		(fill yes
			(thermal_gap 0.5)
			(thermal_bridge_width 0.5)
			(island_removal_mode 0)
		)
		(polygon
			(pts
				(arc
					(start 184.794398 -233.22153)
					(mid 184.809277 -233.257451)
					(end 184.845198 -233.27233)
				)
				(arc
					(start 186.244738 -233.27233)
					(mid 186.280659 -233.257451)
					(end 186.295538 -233.22153)
				)
				(arc
					(start 186.295538 -232.81259)
					(mid 186.280659 -232.776669)
					(end 186.244738 -232.76179)
				)
				(arc
					(start 184.845198 -232.76179)
					(mid 184.809277 -232.776669)
					(end 184.794398 -232.81259)
				)
			)
		)
	)
	(zone
		(layers "In1.Cu" "In2.Cu")
		(hatch none 0.5)
		(connect_pads
			(clearance 0)
		)
		(min_thickness 0.25)
		(keepout
			(tracks not_allowed)
			(vias allowed)
			(pads allowed)
			(copperpour not_allowed)
			(footprints allowed)
		)
		(placement
			(enabled no)
			(sheetname "")
		)
		(fill yes
			(thermal_gap 0.5)
			(thermal_bridge_width 0.5)
			(island_removal_mode 0)
		)
		(polygon
			(pts
				(arc
					(start 45.10913 -247.671336)
					(mid 45.124009 -247.707257)
					(end 45.15993 -247.722136)
				)
				(arc
					(start 46.55947 -247.722136)
					(mid 46.595391 -247.707257)
					(end 46.61027 -247.671336)
				)
				(arc
					(start 46.61027 -247.262396)
					(mid 46.595391 -247.226475)
					(end 46.55947 -247.211596)
				)
				(arc
					(start 45.15993 -247.211596)
					(mid 45.124009 -247.226475)
					(end 45.10913 -247.262396)
				)
			)
		)
	)
	(zone
		(layers "In1.Cu" "In2.Cu")
		(hatch none 0.5)
		(connect_pads
			(clearance 0)
		)
		(min_thickness 0.25)
		(keepout
			(tracks not_allowed)
			(vias allowed)
			(pads allowed)
			(copperpour not_allowed)
			(footprints allowed)
		)
		(placement
			(enabled no)
			(sheetname "")
		)
		(fill yes
			(thermal_gap 0.5)
			(thermal_bridge_width 0.5)
			(island_removal_mode 0)
		)
		(polygon
			(pts
				(arc
					(start 158.06293 -308.871366)
					(mid 158.077809 -308.907287)
					(end 158.11373 -308.922166)
				)
				(arc
					(start 159.51327 -308.922166)
					(mid 159.549191 -308.907287)
					(end 159.56407 -308.871366)
				)
				(arc
					(start 159.56407 -308.462426)
					(mid 159.549191 -308.426505)
					(end 159.51327 -308.411626)
				)
				(arc
					(start 158.11373 -308.411626)
					(mid 158.077809 -308.426505)
					(end 158.06293 -308.462426)
				)
			)
		)
	)
	(zone
		(layers "In1.Cu" "In2.Cu")
		(hatch none 0.5)
		(connect_pads
			(clearance 0)
		)
		(min_thickness 0.25)
		(keepout
			(tracks not_allowed)
			(vias allowed)
			(pads allowed)
			(copperpour not_allowed)
			(footprints allowed)
		)
		(placement
			(enabled no)
			(sheetname "")
		)
		(fill yes
			(thermal_gap 0.5)
			(thermal_bridge_width 0.5)
			(island_removal_mode 0)
		)
		(polygon
			(pts
				(arc
					(start 421.090598 -294.421306)
					(mid 421.105477 -294.457227)
					(end 421.141398 -294.472106)
				)
				(arc
					(start 422.540938 -294.472106)
					(mid 422.576859 -294.457227)
					(end 422.591738 -294.421306)
				)
				(arc
					(start 422.591738 -294.012366)
					(mid 422.576859 -293.976445)
					(end 422.540938 -293.961566)
				)
				(arc
					(start 421.141398 -293.961566)
					(mid 421.105477 -293.976445)
					(end 421.090598 -294.012366)
				)
			)
		)
	)
	(zone
		(layers "In1.Cu" "In2.Cu")
		(hatch none 0.5)
		(connect_pads
			(clearance 0)
		)
		(min_thickness 0.25)
		(keepout
			(tracks not_allowed)
			(vias allowed)
			(pads allowed)
			(copperpour not_allowed)
			(footprints allowed)
		)
		(placement
			(enabled no)
			(sheetname "")
		)
		(fill yes
			(thermal_gap 0.5)
			(thermal_bridge_width 0.5)
			(island_removal_mode 0)
		)
		(polygon
			(pts
				(arc
					(start 417.646866 -296.971466)
					(mid 417.661745 -297.007387)
					(end 417.697666 -297.022266)
				)
				(arc
					(start 419.097206 -297.022266)
					(mid 419.133127 -297.007387)
					(end 419.148006 -296.971466)
				)
				(arc
					(start 419.148006 -296.562526)
					(mid 419.133127 -296.526605)
					(end 419.097206 -296.511726)
				)
				(arc
					(start 417.697666 -296.511726)
					(mid 417.661745 -296.526605)
					(end 417.646866 -296.562526)
				)
			)
		)
	)
	(zone
		(layers "In1.Cu" "In2.Cu")
		(hatch none 0.5)
		(connect_pads
			(clearance 0)
		)
		(min_thickness 0.25)
		(keepout
			(tracks not_allowed)
			(vias allowed)
			(pads allowed)
			(copperpour not_allowed)
			(footprints allowed)
		)
		(placement
			(enabled no)
			(sheetname "")
		)
		(fill yes
			(thermal_gap 0.5)
			(thermal_bridge_width 0.5)
			(island_removal_mode 0)
		)
		(polygon
			(pts
				(arc
					(start 173.15053 -282.521406)
					(mid 173.165409 -282.557327)
					(end 173.20133 -282.572206)
				)
				(arc
					(start 174.60087 -282.572206)
					(mid 174.636791 -282.557327)
					(end 174.65167 -282.521406)
				)
				(arc
					(start 174.65167 -282.112466)
					(mid 174.636791 -282.076545)
					(end 174.60087 -282.061666)
				)
				(arc
					(start 173.20133 -282.061666)
					(mid 173.165409 -282.076545)
					(end 173.15053 -282.112466)
				)
			)
		)
	)
	(zone
		(layers "In1.Cu" "In2.Cu")
		(hatch none 0.5)
		(connect_pads
			(clearance 0)
		)
		(min_thickness 0.25)
		(keepout
			(tracks not_allowed)
			(vias allowed)
			(pads allowed)
			(copperpour not_allowed)
			(footprints allowed)
		)
		(placement
			(enabled no)
			(sheetname "")
		)
		(fill yes
			(thermal_gap 0.5)
			(thermal_bridge_width 0.5)
			(island_removal_mode 0)
		)
		(polygon
			(pts
				(arc
					(start 262.873998 -204.32141)
					(mid 262.888877 -204.357331)
					(end 262.924798 -204.37221)
				)
				(arc
					(start 264.324338 -204.37221)
					(mid 264.360259 -204.357331)
					(end 264.375138 -204.32141)
				)
				(arc
					(start 264.375138 -203.91247)
					(mid 264.360259 -203.876549)
					(end 264.324338 -203.86167)
				)
				(arc
					(start 262.924798 -203.86167)
					(mid 262.888877 -203.876549)
					(end 262.873998 -203.91247)
				)
			)
		)
	)
	(zone
		(layers "In1.Cu" "In2.Cu")
		(hatch none 0.5)
		(connect_pads
			(clearance 0)
		)
		(min_thickness 0.25)
		(keepout
			(tracks not_allowed)
			(vias allowed)
			(pads allowed)
			(copperpour not_allowed)
			(footprints allowed)
		)
		(placement
			(enabled no)
			(sheetname "")
		)
		(fill yes
			(thermal_gap 0.5)
			(thermal_bridge_width 0.5)
			(island_removal_mode 0)
		)
		(polygon
			(pts
				(arc
					(start 266.974066 -304.621438)
					(mid 266.988945 -304.657359)
					(end 267.024866 -304.672238)
				)
				(arc
					(start 268.424406 -304.672238)
					(mid 268.460327 -304.657359)
					(end 268.475206 -304.621438)
				)
				(arc
					(start 268.475206 -304.212498)
					(mid 268.460327 -304.176577)
					(end 268.424406 -304.161698)
				)
				(arc
					(start 267.024866 -304.161698)
					(mid 266.988945 -304.176577)
					(end 266.974066 -304.212498)
				)
			)
		)
	)
	(zone
		(layers "In1.Cu" "In2.Cu")
		(hatch none 0.5)
		(connect_pads
			(clearance 0)
		)
		(min_thickness 0.25)
		(keepout
			(tracks not_allowed)
			(vias allowed)
			(pads allowed)
			(copperpour not_allowed)
			(footprints allowed)
		)
		(placement
			(enabled no)
			(sheetname "")
		)
		(fill yes
			(thermal_gap 0.5)
			(thermal_bridge_width 0.5)
			(island_removal_mode 0)
		)
		(polygon
			(pts
				(arc
					(start 192.338198 -228.121464)
					(mid 192.353077 -228.157385)
					(end 192.388998 -228.172264)
				)
				(arc
					(start 193.788538 -228.172264)
					(mid 193.824459 -228.157385)
					(end 193.839338 -228.121464)
				)
				(arc
					(start 193.839338 -227.712524)
					(mid 193.824459 -227.676603)
					(end 193.788538 -227.661724)
				)
				(arc
					(start 192.388998 -227.661724)
					(mid 192.353077 -227.676603)
					(end 192.338198 -227.712524)
				)
			)
		)
	)
	(zone
		(layers "In1.Cu" "In2.Cu")
		(hatch none 0.5)
		(connect_pads
			(clearance 0)
		)
		(min_thickness 0.25)
		(keepout
			(tracks not_allowed)
			(vias allowed)
			(pads allowed)
			(copperpour not_allowed)
			(footprints allowed)
		)
		(placement
			(enabled no)
			(sheetname "")
		)
		(fill yes
			(thermal_gap 0.5)
			(thermal_bridge_width 0.5)
			(island_removal_mode 0)
		)
		(polygon
			(pts
				(arc
					(start 30.02153 -207.721454)
					(mid 30.036409 -207.757375)
					(end 30.07233 -207.772254)
				)
				(arc
					(start 31.47187 -207.772254)
					(mid 31.507791 -207.757375)
					(end 31.52267 -207.721454)
				)
				(arc
					(start 31.52267 -207.312514)
					(mid 31.507791 -207.276593)
					(end 31.47187 -207.261714)
				)
				(arc
					(start 30.07233 -207.261714)
					(mid 30.036409 -207.276593)
					(end 30.02153 -207.312514)
				)
			)
		)
	)
	(zone
		(layers "In1.Cu" "In2.Cu")
		(hatch none 0.5)
		(connect_pads
			(clearance 0)
		)
		(min_thickness 0.25)
		(keepout
			(tracks not_allowed)
			(vias allowed)
			(pads allowed)
			(copperpour not_allowed)
			(footprints allowed)
		)
		(placement
			(enabled no)
			(sheetname "")
		)
		(fill yes
			(thermal_gap 0.5)
			(thermal_bridge_width 0.5)
			(island_removal_mode 0)
		)
		(polygon
			(pts
				(arc
					(start 158.06293 -245.971314)
					(mid 158.077809 -246.007235)
					(end 158.11373 -246.022114)
				)
				(arc
					(start 159.51327 -246.022114)
					(mid 159.549191 -246.007235)
					(end 159.56407 -245.971314)
				)
				(arc
					(start 159.56407 -245.562374)
					(mid 159.549191 -245.526453)
					(end 159.51327 -245.511574)
				)
				(arc
					(start 158.11373 -245.511574)
					(mid 158.077809 -245.526453)
					(end 158.06293 -245.562374)
				)
			)
		)
	)
	(zone
		(layers "In1.Cu" "In2.Cu")
		(hatch none 0.5)
		(connect_pads
			(clearance 0)
		)
		(min_thickness 0.25)
		(keepout
			(tracks not_allowed)
			(vias allowed)
			(pads allowed)
			(copperpour not_allowed)
			(footprints allowed)
		)
		(placement
			(enabled no)
			(sheetname "")
		)
		(fill yes
			(thermal_gap 0.5)
			(thermal_bridge_width 0.5)
			(island_removal_mode 0)
		)
		(polygon
			(pts
				(arc
					(start 440.278266 -270.621506)
					(mid 440.293145 -270.657427)
					(end 440.329066 -270.672306)
				)
				(arc
					(start 441.728606 -270.672306)
					(mid 441.764527 -270.657427)
					(end 441.779406 -270.621506)
				)
				(arc
					(start 441.779406 -270.212566)
					(mid 441.764527 -270.176645)
					(end 441.728606 -270.161766)
				)
				(arc
					(start 440.329066 -270.161766)
					(mid 440.293145 -270.176645)
					(end 440.278266 -270.212566)
				)
			)
		)
	)
	(zone
		(layers "In1.Cu" "In2.Cu")
		(hatch none 0.5)
		(connect_pads
			(clearance 0)
		)
		(min_thickness 0.25)
		(keepout
			(tracks not_allowed)
			(vias allowed)
			(pads allowed)
			(copperpour not_allowed)
			(footprints allowed)
		)
		(placement
			(enabled no)
			(sheetname "")
		)
		(fill yes
			(thermal_gap 0.5)
			(thermal_bridge_width 0.5)
			(island_removal_mode 0)
		)
		(polygon
			(pts
				(arc
					(start 37.56533 -217.071448)
					(mid 37.580209 -217.107369)
					(end 37.61613 -217.122248)
				)
				(arc
					(start 39.01567 -217.122248)
					(mid 39.051591 -217.107369)
					(end 39.06647 -217.071448)
				)
				(arc
					(start 39.06647 -216.662508)
					(mid 39.051591 -216.626587)
					(end 39.01567 -216.611708)
				)
				(arc
					(start 37.61613 -216.611708)
					(mid 37.580209 -216.626587)
					(end 37.56533 -216.662508)
				)
			)
		)
	)
	(zone
		(layers "In1.Cu" "In2.Cu")
		(hatch none 0.5)
		(connect_pads
			(clearance 0)
		)
		(min_thickness 0.25)
		(keepout
			(tracks not_allowed)
			(vias allowed)
			(pads allowed)
			(copperpour not_allowed)
			(footprints allowed)
		)
		(placement
			(enabled no)
			(sheetname "")
		)
		(fill yes
			(thermal_gap 0.5)
			(thermal_bridge_width 0.5)
			(island_removal_mode 0)
		)
		(polygon
			(pts
				(arc
					(start 297.149266 -245.12143)
					(mid 297.164145 -245.157351)
					(end 297.200066 -245.17223)
				)
				(arc
					(start 298.599606 -245.17223)
					(mid 298.635527 -245.157351)
					(end 298.650406 -245.12143)
				)
				(arc
					(start 298.650406 -244.71249)
					(mid 298.635527 -244.676569)
					(end 298.599606 -244.66169)
				)
				(arc
					(start 297.200066 -244.66169)
					(mid 297.164145 -244.676569)
					(end 297.149266 -244.71249)
				)
			)
		)
	)
	(zone
		(layers "In1.Cu" "In2.Cu")
		(hatch none 0.5)
		(connect_pads
			(clearance 0)
		)
		(min_thickness 0.25)
		(keepout
			(tracks not_allowed)
			(vias allowed)
			(pads allowed)
			(copperpour not_allowed)
			(footprints allowed)
		)
		(placement
			(enabled no)
			(sheetname "")
		)
		(fill yes
			(thermal_gap 0.5)
			(thermal_bridge_width 0.5)
			(island_removal_mode 0)
		)
		(polygon
			(pts
				(arc
					(start 462.909666 -251.921518)
					(mid 462.924545 -251.957439)
					(end 462.960466 -251.972318)
				)
				(arc
					(start 464.360006 -251.972318)
					(mid 464.395927 -251.957439)
					(end 464.410806 -251.921518)
				)
				(arc
					(start 464.410806 -251.512578)
					(mid 464.395927 -251.476657)
					(end 464.360006 -251.461778)
				)
				(arc
					(start 462.960466 -251.461778)
					(mid 462.924545 -251.476657)
					(end 462.909666 -251.512578)
				)
			)
		)
	)
	(zone
		(layers "In1.Cu" "In2.Cu")
		(hatch none 0.5)
		(connect_pads
			(clearance 0)
		)
		(min_thickness 0.25)
		(keepout
			(tracks not_allowed)
			(vias allowed)
			(pads allowed)
			(copperpour not_allowed)
			(footprints allowed)
		)
		(placement
			(enabled no)
			(sheetname "")
		)
		(fill yes
			(thermal_gap 0.5)
			(thermal_bridge_width 0.5)
			(island_removal_mode 0)
		)
		(polygon
			(pts
				(arc
					(start 436.178198 -308.871366)
					(mid 436.193077 -308.907287)
					(end 436.228998 -308.922166)
				)
				(arc
					(start 437.628538 -308.922166)
					(mid 437.664459 -308.907287)
					(end 437.679338 -308.871366)
				)
				(arc
					(start 437.679338 -308.462426)
					(mid 437.664459 -308.426505)
					(end 437.628538 -308.411626)
				)
				(arc
					(start 436.228998 -308.411626)
					(mid 436.193077 -308.426505)
					(end 436.178198 -308.462426)
				)
			)
		)
	)
	(zone
		(layers "In1.Cu" "In2.Cu")
		(hatch none 0.5)
		(connect_pads
			(clearance 0)
		)
		(min_thickness 0.25)
		(keepout
			(tracks not_allowed)
			(vias allowed)
			(pads allowed)
			(copperpour not_allowed)
			(footprints allowed)
		)
		(placement
			(enabled no)
			(sheetname "")
		)
		(fill yes
			(thermal_gap 0.5)
			(thermal_bridge_width 0.5)
			(island_removal_mode 0)
		)
		(polygon
			(pts
				(arc
					(start 308.136798 -237.471458)
					(mid 308.151677 -237.507379)
					(end 308.187598 -237.522258)
				)
				(arc
					(start 309.587138 -237.522258)
					(mid 309.623059 -237.507379)
					(end 309.637938 -237.471458)
				)
				(arc
					(start 309.637938 -237.062518)
					(mid 309.623059 -237.026597)
					(end 309.587138 -237.011718)
				)
				(arc
					(start 308.187598 -237.011718)
					(mid 308.151677 -237.026597)
					(end 308.136798 -237.062518)
				)
			)
		)
	)
	(zone
		(layers "In1.Cu" "In2.Cu")
		(hatch none 0.5)
		(connect_pads
			(clearance 0)
		)
		(min_thickness 0.25)
		(keepout
			(tracks not_allowed)
			(vias allowed)
			(pads allowed)
			(copperpour not_allowed)
			(footprints allowed)
		)
		(placement
			(enabled no)
			(sheetname "")
		)
		(fill yes
			(thermal_gap 0.5)
			(thermal_bridge_width 0.5)
			(island_removal_mode 0)
		)
		(polygon
			(pts
				(arc
					(start 259.430266 -308.021482)
					(mid 259.445145 -308.057403)
					(end 259.481066 -308.072282)
				)
				(arc
					(start 260.880606 -308.072282)
					(mid 260.916527 -308.057403)
					(end 260.931406 -308.021482)
				)
				(arc
					(start 260.931406 -307.612542)
					(mid 260.916527 -307.576621)
					(end 260.880606 -307.561742)
				)
				(arc
					(start 259.481066 -307.561742)
					(mid 259.445145 -307.576621)
					(end 259.430266 -307.612542)
				)
			)
		)
	)
	(zone
		(layers "In1.Cu" "In2.Cu")
		(hatch none 0.5)
		(connect_pads
			(clearance 0)
		)
		(min_thickness 0.25)
		(keepout
			(tracks not_allowed)
			(vias allowed)
			(pads allowed)
			(copperpour not_allowed)
			(footprints allowed)
		)
		(placement
			(enabled no)
			(sheetname "")
		)
		(fill yes
			(thermal_gap 0.5)
			(thermal_bridge_width 0.5)
			(island_removal_mode 0)
		)
		(polygon
			(pts
				(arc
					(start 300.592998 -307.171344)
					(mid 300.607877 -307.207265)
					(end 300.643798 -307.222144)
				)
				(arc
					(start 302.043338 -307.222144)
					(mid 302.079259 -307.207265)
					(end 302.094138 -307.171344)
				)
				(arc
					(start 302.094138 -306.762404)
					(mid 302.079259 -306.726483)
					(end 302.043338 -306.711604)
				)
				(arc
					(start 300.643798 -306.711604)
					(mid 300.607877 -306.726483)
					(end 300.592998 -306.762404)
				)
			)
		)
	)
	(zone
		(layers "In1.Cu" "In2.Cu")
		(hatch none 0.5)
		(connect_pads
			(clearance 0)
		)
		(min_thickness 0.25)
		(keepout
			(tracks not_allowed)
			(vias allowed)
			(pads allowed)
			(copperpour not_allowed)
			(footprints allowed)
		)
		(placement
			(enabled no)
			(sheetname "")
		)
		(fill yes
			(thermal_gap 0.5)
			(thermal_bridge_width 0.5)
			(island_removal_mode 0)
		)
		(polygon
			(pts
				(arc
					(start 410.103066 -225.571304)
					(mid 410.117945 -225.607225)
					(end 410.153866 -225.622104)
				)
				(arc
					(start 411.553406 -225.622104)
					(mid 411.589327 -225.607225)
					(end 411.604206 -225.571304)
				)
				(arc
					(start 411.604206 -225.162364)
					(mid 411.589327 -225.126443)
					(end 411.553406 -225.111564)
				)
				(arc
					(start 410.153866 -225.111564)
					(mid 410.117945 -225.126443)
					(end 410.103066 -225.162364)
				)
			)
		)
	)
	(zone
		(layers "In1.Cu" "In2.Cu")
		(hatch none 0.5)
		(connect_pads
			(clearance 0)
		)
		(min_thickness 0.25)
		(keepout
			(tracks not_allowed)
			(vias allowed)
			(pads allowed)
			(copperpour not_allowed)
			(footprints allowed)
		)
		(placement
			(enabled no)
			(sheetname "")
		)
		(fill yes
			(thermal_gap 0.5)
			(thermal_bridge_width 0.5)
			(island_removal_mode 0)
		)
		(polygon
			(pts
				(arc
					(start 11.490198 -236.62132)
					(mid 11.505077 -236.657241)
					(end 11.540998 -236.67212)
				)
				(arc
					(start 12.940538 -236.67212)
					(mid 12.976459 -236.657241)
					(end 12.991338 -236.62132)
				)
				(arc
					(start 12.991338 -236.21238)
					(mid 12.976459 -236.176459)
					(end 12.940538 -236.16158)
				)
				(arc
					(start 11.540998 -236.16158)
					(mid 11.505077 -236.176459)
					(end 11.490198 -236.21238)
				)
			)
		)
	)
	(zone
		(layers "In1.Cu" "In2.Cu")
		(hatch none 0.5)
		(connect_pads
			(clearance 0)
		)
		(min_thickness 0.25)
		(keepout
			(tracks not_allowed)
			(vias allowed)
			(pads allowed)
			(copperpour not_allowed)
			(footprints allowed)
		)
		(placement
			(enabled no)
			(sheetname "")
		)
		(fill yes
			(thermal_gap 0.5)
			(thermal_bridge_width 0.5)
			(island_removal_mode 0)
		)
		(polygon
			(pts
				(arc
					(start 64.296798 -315.671454)
					(mid 64.311677 -315.707375)
					(end 64.347598 -315.722254)
				)
				(arc
					(start 65.747138 -315.722254)
					(mid 65.783059 -315.707375)
					(end 65.797938 -315.671454)
				)
				(arc
					(start 65.797938 -315.262514)
					(mid 65.783059 -315.226593)
					(end 65.747138 -315.211714)
				)
				(arc
					(start 64.347598 -315.211714)
					(mid 64.311677 -315.226593)
					(end 64.296798 -315.262514)
				)
			)
		)
	)
	(zone
		(layers "In1.Cu" "In2.Cu")
		(hatch none 0.5)
		(connect_pads
			(clearance 0)
		)
		(min_thickness 0.25)
		(keepout
			(tracks not_allowed)
			(vias allowed)
			(pads allowed)
			(copperpour not_allowed)
			(footprints allowed)
		)
		(placement
			(enabled no)
			(sheetname "")
		)
		(fill yes
			(thermal_gap 0.5)
			(thermal_bridge_width 0.5)
			(island_removal_mode 0)
		)
		(polygon
			(pts
				(arc
					(start 304.693066 -260.421374)
					(mid 304.707945 -260.457295)
					(end 304.743866 -260.472174)
				)
				(arc
					(start 306.143406 -260.472174)
					(mid 306.179327 -260.457295)
					(end 306.194206 -260.421374)
				)
				(arc
					(start 306.194206 -260.012434)
					(mid 306.179327 -259.976513)
					(end 306.143406 -259.961634)
				)
				(arc
					(start 304.743866 -259.961634)
					(mid 304.707945 -259.976513)
					(end 304.693066 -260.012434)
				)
			)
		)
	)
	(zone
		(layers "In1.Cu" "In2.Cu")
		(hatch none 0.5)
		(connect_pads
			(clearance 0)
		)
		(min_thickness 0.25)
		(keepout
			(tracks not_allowed)
			(vias allowed)
			(pads allowed)
			(copperpour not_allowed)
			(footprints allowed)
		)
		(placement
			(enabled no)
			(sheetname "")
		)
		(fill yes
			(thermal_gap 0.5)
			(thermal_bridge_width 0.5)
			(island_removal_mode 0)
		)
		(polygon
			(pts
				(arc
					(start 413.546798 -251.07138)
					(mid 413.561677 -251.107301)
					(end 413.597598 -251.12218)
				)
				(arc
					(start 414.997138 -251.12218)
					(mid 415.033059 -251.107301)
					(end 415.047938 -251.07138)
				)
				(arc
					(start 415.047938 -250.66244)
					(mid 415.033059 -250.626519)
					(end 414.997138 -250.61164)
				)
				(arc
					(start 413.597598 -250.61164)
					(mid 413.561677 -250.626519)
					(end 413.546798 -250.66244)
				)
			)
		)
	)
	(zone
		(layers "In1.Cu" "In2.Cu")
		(hatch none 0.5)
		(connect_pads
			(clearance 0)
		)
		(min_thickness 0.25)
		(keepout
			(tracks not_allowed)
			(vias allowed)
			(pads allowed)
			(copperpour not_allowed)
			(footprints allowed)
		)
		(placement
			(enabled no)
			(sheetname "")
		)
		(fill yes
			(thermal_gap 0.5)
			(thermal_bridge_width 0.5)
			(island_removal_mode 0)
		)
		(polygon
			(pts
				(arc
					(start 432.734466 -246.821452)
					(mid 432.749345 -246.857373)
					(end 432.785266 -246.872252)
				)
				(arc
					(start 434.184806 -246.872252)
					(mid 434.220727 -246.857373)
					(end 434.235606 -246.821452)
				)
				(arc
					(start 434.235606 -246.412512)
					(mid 434.220727 -246.376591)
					(end 434.184806 -246.361712)
				)
				(arc
					(start 432.785266 -246.361712)
					(mid 432.749345 -246.376591)
					(end 432.734466 -246.412512)
				)
			)
		)
	)
	(zone
		(layers "In1.Cu" "In2.Cu")
		(hatch none 0.5)
		(connect_pads
			(clearance 0)
		)
		(min_thickness 0.25)
		(keepout
			(tracks not_allowed)
			(vias allowed)
			(pads allowed)
			(copperpour not_allowed)
			(footprints allowed)
		)
		(placement
			(enabled no)
			(sheetname "")
		)
		(fill yes
			(thermal_gap 0.5)
			(thermal_bridge_width 0.5)
			(island_removal_mode 0)
		)
		(polygon
			(pts
				(arc
					(start 262.873998 -305.471322)
					(mid 262.888877 -305.507243)
					(end 262.924798 -305.522122)
				)
				(arc
					(start 264.324338 -305.522122)
					(mid 264.360259 -305.507243)
					(end 264.375138 -305.471322)
				)
				(arc
					(start 264.375138 -305.062382)
					(mid 264.360259 -305.026461)
					(end 264.324338 -305.011582)
				)
				(arc
					(start 262.924798 -305.011582)
					(mid 262.888877 -305.026461)
					(end 262.873998 -305.062382)
				)
			)
		)
	)
	(zone
		(layers "In1.Cu" "In2.Cu")
		(hatch none 0.5)
		(connect_pads
			(clearance 0)
		)
		(min_thickness 0.25)
		(keepout
			(tracks not_allowed)
			(vias allowed)
			(pads allowed)
			(copperpour not_allowed)
			(footprints allowed)
		)
		(placement
			(enabled no)
			(sheetname "")
		)
		(fill yes
			(thermal_gap 0.5)
			(thermal_bridge_width 0.5)
			(island_removal_mode 0)
		)
		(polygon
			(pts
				(arc
					(start 210.86953 -302.921416)
					(mid 210.884409 -302.957337)
					(end 210.92033 -302.972216)
				)
				(arc
					(start 212.31987 -302.972216)
					(mid 212.355791 -302.957337)
					(end 212.37067 -302.921416)
				)
				(arc
					(start 212.37067 -302.512476)
					(mid 212.355791 -302.476555)
					(end 212.31987 -302.461676)
				)
				(arc
					(start 210.92033 -302.461676)
					(mid 210.884409 -302.476555)
					(end 210.86953 -302.512476)
				)
			)
		)
	)
	(zone
		(layers "In1.Cu" "In2.Cu")
		(hatch none 0.5)
		(connect_pads
			(clearance 0)
		)
		(min_thickness 0.25)
		(keepout
			(tracks not_allowed)
			(vias allowed)
			(pads allowed)
			(copperpour not_allowed)
			(footprints allowed)
		)
		(placement
			(enabled no)
			(sheetname "")
		)
		(fill yes
			(thermal_gap 0.5)
			(thermal_bridge_width 0.5)
			(island_removal_mode 0)
		)
		(polygon
			(pts
				(arc
					(start 7.39013 -268.071346)
					(mid 7.405009 -268.107267)
					(end 7.44093 -268.122146)
				)
				(arc
					(start 8.84047 -268.122146)
					(mid 8.876391 -268.107267)
					(end 8.89127 -268.071346)
				)
				(arc
					(start 8.89127 -267.662406)
					(mid 8.876391 -267.626485)
					(end 8.84047 -267.611606)
				)
				(arc
					(start 7.44093 -267.611606)
					(mid 7.405009 -267.626485)
					(end 7.39013 -267.662406)
				)
			)
		)
	)
	(zone
		(layers "In1.Cu" "In2.Cu")
		(hatch none 0.5)
		(connect_pads
			(clearance 0)
		)
		(min_thickness 0.25)
		(keepout
			(tracks not_allowed)
			(vias allowed)
			(pads allowed)
			(copperpour not_allowed)
			(footprints allowed)
		)
		(placement
			(enabled no)
			(sheetname "")
		)
		(fill yes
			(thermal_gap 0.5)
			(thermal_bridge_width 0.5)
			(island_removal_mode 0)
		)
		(polygon
			(pts
				(arc
					(start 436.178198 -303.7713)
					(mid 436.193077 -303.807221)
					(end 436.228998 -303.8221)
				)
				(arc
					(start 437.628538 -303.8221)
					(mid 437.664459 -303.807221)
					(end 437.679338 -303.7713)
				)
				(arc
					(start 437.679338 -303.36236)
					(mid 437.664459 -303.326439)
					(end 437.628538 -303.31156)
				)
				(arc
					(start 436.228998 -303.31156)
					(mid 436.193077 -303.326439)
					(end 436.178198 -303.36236)
				)
			)
		)
	)
	(zone
		(layers "In1.Cu" "In2.Cu")
		(hatch none 0.5)
		(connect_pads
			(clearance 0)
		)
		(min_thickness 0.25)
		(keepout
			(tracks not_allowed)
			(vias allowed)
			(pads allowed)
			(copperpour not_allowed)
			(footprints allowed)
		)
		(placement
			(enabled no)
			(sheetname "")
		)
		(fill yes
			(thermal_gap 0.5)
			(thermal_bridge_width 0.5)
			(island_removal_mode 0)
		)
		(polygon
			(pts
				(arc
					(start 14.93393 -215.371426)
					(mid 14.948809 -215.407347)
					(end 14.98473 -215.422226)
				)
				(arc
					(start 16.38427 -215.422226)
					(mid 16.420191 -215.407347)
					(end 16.43507 -215.371426)
				)
				(arc
					(start 16.43507 -214.962486)
					(mid 16.420191 -214.926565)
					(end 16.38427 -214.911686)
				)
				(arc
					(start 14.98473 -214.911686)
					(mid 14.948809 -214.926565)
					(end 14.93393 -214.962486)
				)
			)
		)
	)
	(zone
		(layers "In1.Cu" "In2.Cu")
		(hatch none 0.5)
		(connect_pads
			(clearance 0)
		)
		(min_thickness 0.25)
		(keepout
			(tracks not_allowed)
			(vias allowed)
			(pads allowed)
			(copperpour not_allowed)
			(footprints allowed)
		)
		(placement
			(enabled no)
			(sheetname "")
		)
		(fill yes
			(thermal_gap 0.5)
			(thermal_bridge_width 0.5)
			(island_removal_mode 0)
		)
		(polygon
			(pts
				(arc
					(start 440.278266 -265.52144)
					(mid 440.293145 -265.557361)
					(end 440.329066 -265.57224)
				)
				(arc
					(start 441.728606 -265.57224)
					(mid 441.764527 -265.557361)
					(end 441.779406 -265.52144)
				)
				(arc
					(start 441.779406 -265.1125)
					(mid 441.764527 -265.076579)
					(end 441.728606 -265.0617)
				)
				(arc
					(start 440.329066 -265.0617)
					(mid 440.293145 -265.076579)
					(end 440.278266 -265.1125)
				)
			)
		)
	)
	(zone
		(layers "In1.Cu" "In2.Cu")
		(hatch none 0.5)
		(connect_pads
			(clearance 0)
		)
		(min_thickness 0.25)
		(keepout
			(tracks not_allowed)
			(vias allowed)
			(pads allowed)
			(copperpour not_allowed)
			(footprints allowed)
		)
		(placement
			(enabled no)
			(sheetname "")
		)
		(fill yes
			(thermal_gap 0.5)
			(thermal_bridge_width 0.5)
			(island_removal_mode 0)
		)
		(polygon
			(pts
				(arc
					(start 56.752998 -200.071482)
					(mid 56.767877 -200.107403)
					(end 56.803798 -200.122282)
				)
				(arc
					(start 58.203338 -200.122282)
					(mid 58.239259 -200.107403)
					(end 58.254138 -200.071482)
				)
				(arc
					(start 58.254138 -199.662542)
					(mid 58.239259 -199.626621)
					(end 58.203338 -199.611742)
				)
				(arc
					(start 56.803798 -199.611742)
					(mid 56.767877 -199.626621)
					(end 56.752998 -199.662542)
				)
			)
		)
	)
	(zone
		(layers "In1.Cu" "In2.Cu")
		(hatch none 0.5)
		(connect_pads
			(clearance 0)
		)
		(min_thickness 0.25)
		(keepout
			(tracks not_allowed)
			(vias allowed)
			(pads allowed)
			(copperpour not_allowed)
			(footprints allowed)
		)
		(placement
			(enabled no)
			(sheetname "")
		)
		(fill yes
			(thermal_gap 0.5)
			(thermal_bridge_width 0.5)
			(island_removal_mode 0)
		)
		(polygon
			(pts
				(arc
					(start 11.490198 -285.92145)
					(mid 11.505077 -285.957371)
					(end 11.540998 -285.97225)
				)
				(arc
					(start 12.940538 -285.97225)
					(mid 12.976459 -285.957371)
					(end 12.991338 -285.92145)
				)
				(arc
					(start 12.991338 -285.51251)
					(mid 12.976459 -285.476589)
					(end 12.940538 -285.46171)
				)
				(arc
					(start 11.540998 -285.46171)
					(mid 11.505077 -285.476589)
					(end 11.490198 -285.51251)
				)
			)
		)
	)
	(zone
		(layers "In1.Cu" "In2.Cu")
		(hatch none 0.5)
		(connect_pads
			(clearance 0)
		)
		(min_thickness 0.25)
		(keepout
			(tracks not_allowed)
			(vias allowed)
			(pads allowed)
			(copperpour not_allowed)
			(footprints allowed)
		)
		(placement
			(enabled no)
			(sheetname "")
		)
		(fill yes
			(thermal_gap 0.5)
			(thermal_bridge_width 0.5)
			(island_removal_mode 0)
		)
		(polygon
			(pts
				(arc
					(start 14.93393 -316.521338)
					(mid 14.948809 -316.557259)
					(end 14.98473 -316.572138)
				)
				(arc
					(start 16.38427 -316.572138)
					(mid 16.420191 -316.557259)
					(end 16.43507 -316.521338)
				)
				(arc
					(start 16.43507 -316.112398)
					(mid 16.420191 -316.076477)
					(end 16.38427 -316.061598)
				)
				(arc
					(start 14.98473 -316.061598)
					(mid 14.948809 -316.076477)
					(end 14.93393 -316.112398)
				)
			)
		)
	)
	(zone
		(layers "In1.Cu" "In2.Cu")
		(hatch none 0.5)
		(connect_pads
			(clearance 0)
		)
		(min_thickness 0.25)
		(keepout
			(tracks not_allowed)
			(vias allowed)
			(pads allowed)
			(copperpour not_allowed)
			(footprints allowed)
		)
		(placement
			(enabled no)
			(sheetname "")
		)
		(fill yes
			(thermal_gap 0.5)
			(thermal_bridge_width 0.5)
			(island_removal_mode 0)
		)
		(polygon
			(pts
				(arc
					(start 421.090598 -266.371324)
					(mid 421.105477 -266.407245)
					(end 421.141398 -266.422124)
				)
				(arc
					(start 422.540938 -266.422124)
					(mid 422.576859 -266.407245)
					(end 422.591738 -266.371324)
				)
				(arc
					(start 422.591738 -265.962384)
					(mid 422.576859 -265.926463)
					(end 422.540938 -265.911584)
				)
				(arc
					(start 421.141398 -265.911584)
					(mid 421.105477 -265.926463)
					(end 421.090598 -265.962384)
				)
			)
		)
	)
	(zone
		(layers "In1.Cu" "In2.Cu")
		(hatch none 0.5)
		(connect_pads
			(clearance 0)
		)
		(min_thickness 0.25)
		(keepout
			(tracks not_allowed)
			(vias allowed)
			(pads allowed)
			(copperpour not_allowed)
			(footprints allowed)
		)
		(placement
			(enabled no)
			(sheetname "")
		)
		(fill yes
			(thermal_gap 0.5)
			(thermal_bridge_width 0.5)
			(island_removal_mode 0)
		)
		(polygon
			(pts
				(arc
					(start 30.02153 -228.121464)
					(mid 30.036409 -228.157385)
					(end 30.07233 -228.172264)
				)
				(arc
					(start 31.47187 -228.172264)
					(mid 31.507791 -228.157385)
					(end 31.52267 -228.121464)
				)
				(arc
					(start 31.52267 -227.712524)
					(mid 31.507791 -227.676603)
					(end 31.47187 -227.661724)
				)
				(arc
					(start 30.07233 -227.661724)
					(mid 30.036409 -227.676603)
					(end 30.02153 -227.712524)
				)
			)
		)
	)
	(zone
		(layers "In1.Cu" "In2.Cu")
		(hatch none 0.5)
		(connect_pads
			(clearance 0)
		)
		(min_thickness 0.25)
		(keepout
			(tracks not_allowed)
			(vias allowed)
			(pads allowed)
			(copperpour not_allowed)
			(footprints allowed)
		)
		(placement
			(enabled no)
			(sheetname "")
		)
		(fill yes
			(thermal_gap 0.5)
			(thermal_bridge_width 0.5)
			(island_removal_mode 0)
		)
		(polygon
			(pts
				(arc
					(start 300.592998 -299.521372)
					(mid 300.607877 -299.557293)
					(end 300.643798 -299.572172)
				)
				(arc
					(start 302.043338 -299.572172)
					(mid 302.079259 -299.557293)
					(end 302.094138 -299.521372)
				)
				(arc
					(start 302.094138 -299.112432)
					(mid 302.079259 -299.076511)
					(end 302.043338 -299.061632)
				)
				(arc
					(start 300.643798 -299.061632)
					(mid 300.607877 -299.076511)
					(end 300.592998 -299.112432)
				)
			)
		)
	)
	(zone
		(layers "In1.Cu" "In2.Cu")
		(hatch none 0.5)
		(connect_pads
			(clearance 0)
		)
		(min_thickness 0.25)
		(keepout
			(tracks not_allowed)
			(vias allowed)
			(pads allowed)
			(copperpour not_allowed)
			(footprints allowed)
		)
		(placement
			(enabled no)
			(sheetname "")
		)
		(fill yes
			(thermal_gap 0.5)
			(thermal_bridge_width 0.5)
			(island_removal_mode 0)
		)
		(polygon
			(pts
				(arc
					(start 169.706798 -234.921298)
					(mid 169.721677 -234.957219)
					(end 169.757598 -234.972098)
				)
				(arc
					(start 171.157138 -234.972098)
					(mid 171.193059 -234.957219)
					(end 171.207938 -234.921298)
				)
				(arc
					(start 171.207938 -234.512358)
					(mid 171.193059 -234.476437)
					(end 171.157138 -234.461558)
				)
				(arc
					(start 169.757598 -234.461558)
					(mid 169.721677 -234.476437)
					(end 169.706798 -234.512358)
				)
			)
		)
	)
	(zone
		(layers "In1.Cu" "In2.Cu")
		(hatch none 0.5)
		(connect_pads
			(clearance 0)
		)
		(min_thickness 0.25)
		(keepout
			(tracks not_allowed)
			(vias allowed)
			(pads allowed)
			(copperpour not_allowed)
			(footprints allowed)
		)
		(placement
			(enabled no)
			(sheetname "")
		)
		(fill yes
			(thermal_gap 0.5)
			(thermal_bridge_width 0.5)
			(island_removal_mode 0)
		)
		(polygon
			(pts
				(arc
					(start 447.822066 -251.921518)
					(mid 447.836945 -251.957439)
					(end 447.872866 -251.972318)
				)
				(arc
					(start 449.272406 -251.972318)
					(mid 449.308327 -251.957439)
					(end 449.323206 -251.921518)
				)
				(arc
					(start 449.323206 -251.512578)
					(mid 449.308327 -251.476657)
					(end 449.272406 -251.461778)
				)
				(arc
					(start 447.872866 -251.461778)
					(mid 447.836945 -251.476657)
					(end 447.822066 -251.512578)
				)
			)
		)
	)
	(zone
		(layers "In1.Cu" "In2.Cu")
		(hatch none 0.5)
		(connect_pads
			(clearance 0)
		)
		(min_thickness 0.25)
		(keepout
			(tracks not_allowed)
			(vias allowed)
			(pads allowed)
			(copperpour not_allowed)
			(footprints allowed)
		)
		(placement
			(enabled no)
			(sheetname "")
		)
		(fill yes
			(thermal_gap 0.5)
			(thermal_bridge_width 0.5)
			(island_removal_mode 0)
		)
		(polygon
			(pts
				(arc
					(start 7.39013 -296.121328)
					(mid 7.405009 -296.157249)
					(end 7.44093 -296.172128)
				)
				(arc
					(start 8.84047 -296.172128)
					(mid 8.876391 -296.157249)
					(end 8.89127 -296.121328)
				)
				(arc
					(start 8.89127 -295.712388)
					(mid 8.876391 -295.676467)
					(end 8.84047 -295.661588)
				)
				(arc
					(start 7.44093 -295.661588)
					(mid 7.405009 -295.676467)
					(end 7.39013 -295.712388)
				)
			)
		)
	)
	(zone
		(layers "In1.Cu" "In2.Cu")
		(hatch none 0.5)
		(connect_pads
			(clearance 0)
		)
		(min_thickness 0.25)
		(keepout
			(tracks not_allowed)
			(vias allowed)
			(pads allowed)
			(copperpour not_allowed)
			(footprints allowed)
		)
		(placement
			(enabled no)
			(sheetname "")
		)
		(fill yes
			(thermal_gap 0.5)
			(thermal_bridge_width 0.5)
			(island_removal_mode 0)
		)
		(polygon
			(pts
				(arc
					(start 210.86953 -271.47139)
					(mid 210.884409 -271.507311)
					(end 210.92033 -271.52219)
				)
				(arc
					(start 212.31987 -271.52219)
					(mid 212.355791 -271.507311)
					(end 212.37067 -271.47139)
				)
				(arc
					(start 212.37067 -271.06245)
					(mid 212.355791 -271.026529)
					(end 212.31987 -271.01165)
				)
				(arc
					(start 210.92033 -271.01165)
					(mid 210.884409 -271.026529)
					(end 210.86953 -271.06245)
				)
			)
		)
	)
	(zone
		(layers "In1.Cu" "In2.Cu")
		(hatch none 0.5)
		(connect_pads
			(clearance 0)
		)
		(min_thickness 0.25)
		(keepout
			(tracks not_allowed)
			(vias allowed)
			(pads allowed)
			(copperpour not_allowed)
			(footprints allowed)
		)
		(placement
			(enabled no)
			(sheetname "")
		)
		(fill yes
			(thermal_gap 0.5)
			(thermal_bridge_width 0.5)
			(island_removal_mode 0)
		)
		(polygon
			(pts
				(arc
					(start 270.417798 -252.771402)
					(mid 270.432677 -252.807323)
					(end 270.468598 -252.822202)
				)
				(arc
					(start 271.868138 -252.822202)
					(mid 271.904059 -252.807323)
					(end 271.918938 -252.771402)
				)
				(arc
					(start 271.918938 -252.362462)
					(mid 271.904059 -252.326541)
					(end 271.868138 -252.311662)
				)
				(arc
					(start 270.468598 -252.311662)
					(mid 270.432677 -252.326541)
					(end 270.417798 -252.362462)
				)
			)
		)
	)
	(zone
		(layers "In1.Cu" "In2.Cu")
		(hatch none 0.5)
		(connect_pads
			(clearance 0)
		)
		(min_thickness 0.25)
		(keepout
			(tracks not_allowed)
			(vias allowed)
			(pads allowed)
			(copperpour not_allowed)
			(footprints allowed)
		)
		(placement
			(enabled no)
			(sheetname "")
		)
		(fill yes
			(thermal_gap 0.5)
			(thermal_bridge_width 0.5)
			(island_removal_mode 0)
		)
		(polygon
			(pts
				(arc
					(start 421.090598 -200.921366)
					(mid 421.105477 -200.957287)
					(end 421.141398 -200.972166)
				)
				(arc
					(start 422.540938 -200.972166)
					(mid 422.576859 -200.957287)
					(end 422.591738 -200.921366)
				)
				(arc
					(start 422.591738 -200.512426)
					(mid 422.576859 -200.476505)
					(end 422.540938 -200.461626)
				)
				(arc
					(start 421.141398 -200.461626)
					(mid 421.105477 -200.476505)
					(end 421.090598 -200.512426)
				)
			)
		)
	)
	(zone
		(layers "In1.Cu" "In2.Cu")
		(hatch none 0.5)
		(connect_pads
			(clearance 0)
		)
		(min_thickness 0.25)
		(keepout
			(tracks not_allowed)
			(vias allowed)
			(pads allowed)
			(copperpour not_allowed)
			(footprints allowed)
		)
		(placement
			(enabled no)
			(sheetname "")
		)
		(fill yes
			(thermal_gap 0.5)
			(thermal_bridge_width 0.5)
			(island_removal_mode 0)
		)
		(polygon
			(pts
				(arc
					(start 7.39013 -293.571422)
					(mid 7.405009 -293.607343)
					(end 7.44093 -293.622222)
				)
				(arc
					(start 8.84047 -293.622222)
					(mid 8.876391 -293.607343)
					(end 8.89127 -293.571422)
				)
				(arc
					(start 8.89127 -293.162482)
					(mid 8.876391 -293.126561)
					(end 8.84047 -293.111682)
				)
				(arc
					(start 7.44093 -293.111682)
					(mid 7.405009 -293.126561)
					(end 7.39013 -293.162482)
				)
			)
		)
	)
	(zone
		(layers "In1.Cu" "In2.Cu")
		(hatch none 0.5)
		(connect_pads
			(clearance 0)
		)
		(min_thickness 0.25)
		(keepout
			(tracks not_allowed)
			(vias allowed)
			(pads allowed)
			(copperpour not_allowed)
			(footprints allowed)
		)
		(placement
			(enabled no)
			(sheetname "")
		)
		(fill yes
			(thermal_gap 0.5)
			(thermal_bridge_width 0.5)
			(island_removal_mode 0)
		)
		(polygon
			(pts
				(arc
					(start 26.577798 -233.22153)
					(mid 26.592677 -233.257451)
					(end 26.628598 -233.27233)
				)
				(arc
					(start 28.028138 -233.27233)
					(mid 28.064059 -233.257451)
					(end 28.078938 -233.22153)
				)
				(arc
					(start 28.078938 -232.81259)
					(mid 28.064059 -232.776669)
					(end 28.028138 -232.76179)
				)
				(arc
					(start 26.628598 -232.76179)
					(mid 26.592677 -232.776669)
					(end 26.577798 -232.81259)
				)
			)
		)
	)
	(zone
		(layers "In1.Cu" "In2.Cu")
		(hatch none 0.5)
		(connect_pads
			(clearance 0)
		)
		(min_thickness 0.25)
		(keepout
			(tracks not_allowed)
			(vias allowed)
			(pads allowed)
			(copperpour not_allowed)
			(footprints allowed)
		)
		(placement
			(enabled no)
			(sheetname "")
		)
		(fill yes
			(thermal_gap 0.5)
			(thermal_bridge_width 0.5)
			(island_removal_mode 0)
		)
		(polygon
			(pts
				(arc
					(start 188.23813 -261.271512)
					(mid 188.253009 -261.307433)
					(end 188.28893 -261.322312)
				)
				(arc
					(start 189.68847 -261.322312)
					(mid 189.724391 -261.307433)
					(end 189.73927 -261.271512)
				)
				(arc
					(start 189.73927 -260.862572)
					(mid 189.724391 -260.826651)
					(end 189.68847 -260.811772)
				)
				(arc
					(start 188.28893 -260.811772)
					(mid 188.253009 -260.826651)
					(end 188.23813 -260.862572)
				)
			)
		)
	)
	(zone
		(layers "In1.Cu" "In2.Cu")
		(hatch none 0.5)
		(connect_pads
			(clearance 0)
		)
		(min_thickness 0.25)
		(keepout
			(tracks not_allowed)
			(vias allowed)
			(pads allowed)
			(copperpour not_allowed)
			(footprints allowed)
		)
		(placement
			(enabled no)
			(sheetname "")
		)
		(fill yes
			(thermal_gap 0.5)
			(thermal_bridge_width 0.5)
			(island_removal_mode 0)
		)
		(polygon
			(pts
				(arc
					(start 425.190666 -298.671488)
					(mid 425.205545 -298.707409)
					(end 425.241466 -298.722288)
				)
				(arc
					(start 426.641006 -298.722288)
					(mid 426.676927 -298.707409)
					(end 426.691806 -298.671488)
				)
				(arc
					(start 426.691806 -298.262548)
					(mid 426.676927 -298.226627)
					(end 426.641006 -298.211748)
				)
				(arc
					(start 425.241466 -298.211748)
					(mid 425.205545 -298.226627)
					(end 425.190666 -298.262548)
				)
			)
		)
	)
	(zone
		(layers "In1.Cu" "In2.Cu")
		(hatch none 0.5)
		(connect_pads
			(clearance 0)
		)
		(min_thickness 0.25)
		(keepout
			(tracks not_allowed)
			(vias allowed)
			(pads allowed)
			(copperpour not_allowed)
			(footprints allowed)
		)
		(placement
			(enabled no)
			(sheetname "")
		)
		(fill yes
			(thermal_gap 0.5)
			(thermal_bridge_width 0.5)
			(island_removal_mode 0)
		)
		(polygon
			(pts
				(arc
					(start 30.02153 -299.521372)
					(mid 30.036409 -299.557293)
					(end 30.07233 -299.572172)
				)
				(arc
					(start 31.47187 -299.572172)
					(mid 31.507791 -299.557293)
					(end 31.52267 -299.521372)
				)
				(arc
					(start 31.52267 -299.112432)
					(mid 31.507791 -299.076511)
					(end 31.47187 -299.061632)
				)
				(arc
					(start 30.07233 -299.061632)
					(mid 30.036409 -299.076511)
					(end 30.02153 -299.112432)
				)
			)
		)
	)
	(zone
		(layers "In1.Cu" "In2.Cu")
		(hatch none 0.5)
		(connect_pads
			(clearance 0)
		)
		(min_thickness 0.25)
		(keepout
			(tracks not_allowed)
			(vias allowed)
			(pads allowed)
			(copperpour not_allowed)
			(footprints allowed)
		)
		(placement
			(enabled no)
			(sheetname "")
		)
		(fill yes
			(thermal_gap 0.5)
			(thermal_bridge_width 0.5)
			(island_removal_mode 0)
		)
		(polygon
			(pts
				(arc
					(start 277.961598 -303.7713)
					(mid 277.976477 -303.807221)
					(end 278.012398 -303.8221)
				)
				(arc
					(start 279.411938 -303.8221)
					(mid 279.447859 -303.807221)
					(end 279.462738 -303.7713)
				)
				(arc
					(start 279.462738 -303.36236)
					(mid 279.447859 -303.326439)
					(end 279.411938 -303.31156)
				)
				(arc
					(start 278.012398 -303.31156)
					(mid 277.976477 -303.326439)
					(end 277.961598 -303.36236)
				)
			)
		)
	)
	(zone
		(layers "In1.Cu" "In2.Cu")
		(hatch none 0.5)
		(connect_pads
			(clearance 0)
		)
		(min_thickness 0.25)
		(keepout
			(tracks not_allowed)
			(vias allowed)
			(pads allowed)
			(copperpour not_allowed)
			(footprints allowed)
		)
		(placement
			(enabled no)
			(sheetname "")
		)
		(fill yes
			(thermal_gap 0.5)
			(thermal_bridge_width 0.5)
			(island_removal_mode 0)
		)
		(polygon
			(pts
				(arc
					(start 285.505398 -249.371358)
					(mid 285.520277 -249.407279)
					(end 285.556198 -249.422158)
				)
				(arc
					(start 286.955738 -249.422158)
					(mid 286.991659 -249.407279)
					(end 287.006538 -249.371358)
				)
				(arc
					(start 287.006538 -248.962418)
					(mid 286.991659 -248.926497)
					(end 286.955738 -248.911618)
				)
				(arc
					(start 285.556198 -248.911618)
					(mid 285.520277 -248.926497)
					(end 285.505398 -248.962418)
				)
			)
		)
	)
	(zone
		(layers "In1.Cu" "In2.Cu")
		(hatch none 0.5)
		(connect_pads
			(clearance 0)
		)
		(min_thickness 0.25)
		(keepout
			(tracks not_allowed)
			(vias allowed)
			(pads allowed)
			(copperpour not_allowed)
			(footprints allowed)
		)
		(placement
			(enabled no)
			(sheetname "")
		)
		(fill yes
			(thermal_gap 0.5)
			(thermal_bridge_width 0.5)
			(island_removal_mode 0)
		)
		(polygon
			(pts
				(arc
					(start 255.330198 -297.82135)
					(mid 255.345077 -297.857271)
					(end 255.380998 -297.87215)
				)
				(arc
					(start 256.780538 -297.87215)
					(mid 256.816459 -297.857271)
					(end 256.831338 -297.82135)
				)
				(arc
					(start 256.831338 -297.41241)
					(mid 256.816459 -297.376489)
					(end 256.780538 -297.36161)
				)
				(arc
					(start 255.380998 -297.36161)
					(mid 255.345077 -297.376489)
					(end 255.330198 -297.41241)
				)
			)
		)
	)
	(zone
		(layers "In1.Cu" "In2.Cu")
		(hatch none 0.5)
		(connect_pads
			(clearance 0)
		)
		(min_thickness 0.25)
		(keepout
			(tracks not_allowed)
			(vias allowed)
			(pads allowed)
			(copperpour not_allowed)
			(footprints allowed)
		)
		(placement
			(enabled no)
			(sheetname "")
		)
		(fill yes
			(thermal_gap 0.5)
			(thermal_bridge_width 0.5)
			(island_removal_mode 0)
		)
		(polygon
			(pts
				(arc
					(start 158.06293 -286.771334)
					(mid 158.077809 -286.807255)
					(end 158.11373 -286.822134)
				)
				(arc
					(start 159.51327 -286.822134)
					(mid 159.549191 -286.807255)
					(end 159.56407 -286.771334)
				)
				(arc
					(start 159.56407 -286.362394)
					(mid 159.549191 -286.326473)
					(end 159.51327 -286.311594)
				)
				(arc
					(start 158.11373 -286.311594)
					(mid 158.077809 -286.326473)
					(end 158.06293 -286.362394)
				)
			)
		)
	)
	(zone
		(layers "In1.Cu" "In2.Cu")
		(hatch none 0.5)
		(connect_pads
			(clearance 0)
		)
		(min_thickness 0.25)
		(keepout
			(tracks not_allowed)
			(vias allowed)
			(pads allowed)
			(copperpour not_allowed)
			(footprints allowed)
		)
		(placement
			(enabled no)
			(sheetname "")
		)
		(fill yes
			(thermal_gap 0.5)
			(thermal_bridge_width 0.5)
			(island_removal_mode 0)
		)
		(polygon
			(pts
				(arc
					(start 300.592998 -277.42134)
					(mid 300.607877 -277.457261)
					(end 300.643798 -277.47214)
				)
				(arc
					(start 302.043338 -277.47214)
					(mid 302.079259 -277.457261)
					(end 302.094138 -277.42134)
				)
				(arc
					(start 302.094138 -277.0124)
					(mid 302.079259 -276.976479)
					(end 302.043338 -276.9616)
				)
				(arc
					(start 300.643798 -276.9616)
					(mid 300.607877 -276.976479)
					(end 300.592998 -277.0124)
				)
			)
		)
	)
	(zone
		(layers "In1.Cu" "In2.Cu")
		(hatch none 0.5)
		(connect_pads
			(clearance 0)
		)
		(min_thickness 0.25)
		(keepout
			(tracks not_allowed)
			(vias allowed)
			(pads allowed)
			(copperpour not_allowed)
			(footprints allowed)
		)
		(placement
			(enabled no)
			(sheetname "")
		)
		(fill yes
			(thermal_gap 0.5)
			(thermal_bridge_width 0.5)
			(island_removal_mode 0)
		)
		(polygon
			(pts
				(arc
					(start 447.822066 -229.821486)
					(mid 447.836945 -229.857407)
					(end 447.872866 -229.872286)
				)
				(arc
					(start 449.272406 -229.872286)
					(mid 449.308327 -229.857407)
					(end 449.323206 -229.821486)
				)
				(arc
					(start 449.323206 -229.412546)
					(mid 449.308327 -229.376625)
					(end 449.272406 -229.361746)
				)
				(arc
					(start 447.872866 -229.361746)
					(mid 447.836945 -229.376625)
					(end 447.822066 -229.412546)
				)
			)
		)
	)
	(zone
		(layers "In1.Cu" "In2.Cu")
		(hatch none 0.5)
		(connect_pads
			(clearance 0)
		)
		(min_thickness 0.25)
		(keepout
			(tracks not_allowed)
			(vias allowed)
			(pads allowed)
			(copperpour not_allowed)
			(footprints allowed)
		)
		(placement
			(enabled no)
			(sheetname "")
		)
		(fill yes
			(thermal_gap 0.5)
			(thermal_bridge_width 0.5)
			(island_removal_mode 0)
		)
		(polygon
			(pts
				(arc
					(start 312.236866 -225.571304)
					(mid 312.251745 -225.607225)
					(end 312.287666 -225.622104)
				)
				(arc
					(start 313.687206 -225.622104)
					(mid 313.723127 -225.607225)
					(end 313.738006 -225.571304)
				)
				(arc
					(start 313.738006 -225.162364)
					(mid 313.723127 -225.126443)
					(end 313.687206 -225.111564)
				)
				(arc
					(start 312.287666 -225.111564)
					(mid 312.251745 -225.126443)
					(end 312.236866 -225.162364)
				)
			)
		)
	)
	(zone
		(layers "In1.Cu" "In2.Cu")
		(hatch none 0.5)
		(connect_pads
			(clearance 0)
		)
		(min_thickness 0.25)
		(keepout
			(tracks not_allowed)
			(vias allowed)
			(pads allowed)
			(copperpour not_allowed)
			(footprints allowed)
		)
		(placement
			(enabled no)
			(sheetname "")
		)
		(fill yes
			(thermal_gap 0.5)
			(thermal_bridge_width 0.5)
			(island_removal_mode 0)
		)
		(polygon
			(pts
				(arc
					(start 274.517866 -201.771504)
					(mid 274.532745 -201.807425)
					(end 274.568666 -201.822304)
				)
				(arc
					(start 275.968206 -201.822304)
					(mid 276.004127 -201.807425)
					(end 276.019006 -201.771504)
				)
				(arc
					(start 276.019006 -201.362564)
					(mid 276.004127 -201.326643)
					(end 275.968206 -201.311764)
				)
				(arc
					(start 274.568666 -201.311764)
					(mid 274.532745 -201.326643)
					(end 274.517866 -201.362564)
				)
			)
		)
	)
	(zone
		(layers "In1.Cu" "In2.Cu")
		(hatch none 0.5)
		(connect_pads
			(clearance 0)
		)
		(min_thickness 0.25)
		(keepout
			(tracks not_allowed)
			(vias allowed)
			(pads allowed)
			(copperpour not_allowed)
			(footprints allowed)
		)
		(placement
			(enabled no)
			(sheetname "")
		)
		(fill yes
			(thermal_gap 0.5)
			(thermal_bridge_width 0.5)
			(island_removal_mode 0)
		)
		(polygon
			(pts
				(arc
					(start 188.23813 -211.971382)
					(mid 188.253009 -212.007303)
					(end 188.28893 -212.022182)
				)
				(arc
					(start 189.68847 -212.022182)
					(mid 189.724391 -212.007303)
					(end 189.73927 -211.971382)
				)
				(arc
					(start 189.73927 -211.562442)
					(mid 189.724391 -211.526521)
					(end 189.68847 -211.511642)
				)
				(arc
					(start 188.28893 -211.511642)
					(mid 188.253009 -211.526521)
					(end 188.23813 -211.562442)
				)
			)
		)
	)
	(zone
		(layers "In1.Cu" "In2.Cu")
		(hatch none 0.5)
		(connect_pads
			(clearance 0)
		)
		(min_thickness 0.25)
		(keepout
			(tracks not_allowed)
			(vias allowed)
			(pads allowed)
			(copperpour not_allowed)
			(footprints allowed)
		)
		(placement
			(enabled no)
			(sheetname "")
		)
		(fill yes
			(thermal_gap 0.5)
			(thermal_bridge_width 0.5)
			(island_removal_mode 0)
		)
		(polygon
			(pts
				(arc
					(start 165.60673 -228.121464)
					(mid 165.621609 -228.157385)
					(end 165.65753 -228.172264)
				)
				(arc
					(start 167.05707 -228.172264)
					(mid 167.092991 -228.157385)
					(end 167.10787 -228.121464)
				)
				(arc
					(start 167.10787 -227.712524)
					(mid 167.092991 -227.676603)
					(end 167.05707 -227.661724)
				)
				(arc
					(start 165.65753 -227.661724)
					(mid 165.621609 -227.676603)
					(end 165.60673 -227.712524)
				)
			)
		)
	)
	(zone
		(layers "In1.Cu" "In2.Cu")
		(hatch none 0.5)
		(connect_pads
			(clearance 0)
		)
		(min_thickness 0.25)
		(keepout
			(tracks not_allowed)
			(vias allowed)
			(pads allowed)
			(copperpour not_allowed)
			(footprints allowed)
		)
		(placement
			(enabled no)
			(sheetname "")
		)
		(fill yes
			(thermal_gap 0.5)
			(thermal_bridge_width 0.5)
			(island_removal_mode 0)
		)
		(polygon
			(pts
				(arc
					(start 266.974066 -312.27141)
					(mid 266.988945 -312.307331)
					(end 267.024866 -312.32221)
				)
				(arc
					(start 268.424406 -312.32221)
					(mid 268.460327 -312.307331)
					(end 268.475206 -312.27141)
				)
				(arc
					(start 268.475206 -311.86247)
					(mid 268.460327 -311.826549)
					(end 268.424406 -311.81167)
				)
				(arc
					(start 267.024866 -311.81167)
					(mid 266.988945 -311.826549)
					(end 266.974066 -311.86247)
				)
			)
		)
	)
	(zone
		(layers "In1.Cu" "In2.Cu")
		(hatch none 0.5)
		(connect_pads
			(clearance 0)
		)
		(min_thickness 0.25)
		(keepout
			(tracks not_allowed)
			(vias allowed)
			(pads allowed)
			(copperpour not_allowed)
			(footprints allowed)
		)
		(placement
			(enabled no)
			(sheetname "")
		)
		(fill yes
			(thermal_gap 0.5)
			(thermal_bridge_width 0.5)
			(island_removal_mode 0)
		)
		(polygon
			(pts
				(arc
					(start 436.178198 -217.071448)
					(mid 436.193077 -217.107369)
					(end 436.228998 -217.122248)
				)
				(arc
					(start 437.628538 -217.122248)
					(mid 437.664459 -217.107369)
					(end 437.679338 -217.071448)
				)
				(arc
					(start 437.679338 -216.662508)
					(mid 437.664459 -216.626587)
					(end 437.628538 -216.611708)
				)
				(arc
					(start 436.228998 -216.611708)
					(mid 436.193077 -216.626587)
					(end 436.178198 -216.662508)
				)
			)
		)
	)
	(zone
		(layers "In1.Cu" "In2.Cu")
		(hatch none 0.5)
		(connect_pads
			(clearance 0)
		)
		(min_thickness 0.25)
		(keepout
			(tracks not_allowed)
			(vias allowed)
			(pads allowed)
			(copperpour not_allowed)
			(footprints allowed)
		)
		(placement
			(enabled no)
			(sheetname "")
		)
		(fill yes
			(thermal_gap 0.5)
			(thermal_bridge_width 0.5)
			(island_removal_mode 0)
		)
		(polygon
			(pts
				(arc
					(start 177.250598 -222.171514)
					(mid 177.265477 -222.207435)
					(end 177.301398 -222.222314)
				)
				(arc
					(start 178.700938 -222.222314)
					(mid 178.736859 -222.207435)
					(end 178.751738 -222.171514)
				)
				(arc
					(start 178.751738 -221.762574)
					(mid 178.736859 -221.726653)
					(end 178.700938 -221.711774)
				)
				(arc
					(start 177.301398 -221.711774)
					(mid 177.265477 -221.726653)
					(end 177.250598 -221.762574)
				)
			)
		)
	)
	(zone
		(layers "In1.Cu" "In2.Cu")
		(hatch none 0.5)
		(connect_pads
			(clearance 0)
		)
		(min_thickness 0.25)
		(keepout
			(tracks not_allowed)
			(vias allowed)
			(pads allowed)
			(copperpour not_allowed)
			(footprints allowed)
		)
		(placement
			(enabled no)
			(sheetname "")
		)
		(fill yes
			(thermal_gap 0.5)
			(thermal_bridge_width 0.5)
			(island_removal_mode 0)
		)
		(polygon
			(pts
				(arc
					(start 462.909666 -246.821452)
					(mid 462.924545 -246.857373)
					(end 462.960466 -246.872252)
				)
				(arc
					(start 464.360006 -246.872252)
					(mid 464.395927 -246.857373)
					(end 464.410806 -246.821452)
				)
				(arc
					(start 464.410806 -246.412512)
					(mid 464.395927 -246.376591)
					(end 464.360006 -246.361712)
				)
				(arc
					(start 462.960466 -246.361712)
					(mid 462.924545 -246.376591)
					(end 462.909666 -246.412512)
				)
			)
		)
	)
	(zone
		(layers "In1.Cu" "In2.Cu")
		(hatch none 0.5)
		(connect_pads
			(clearance 0)
		)
		(min_thickness 0.25)
		(keepout
			(tracks not_allowed)
			(vias allowed)
			(pads allowed)
			(copperpour not_allowed)
			(footprints allowed)
		)
		(placement
			(enabled no)
			(sheetname "")
		)
		(fill yes
			(thermal_gap 0.5)
			(thermal_bridge_width 0.5)
			(island_removal_mode 0)
		)
		(polygon
			(pts
				(arc
					(start 436.178198 -209.421476)
					(mid 436.193077 -209.457397)
					(end 436.228998 -209.472276)
				)
				(arc
					(start 437.628538 -209.472276)
					(mid 437.664459 -209.457397)
					(end 437.679338 -209.421476)
				)
				(arc
					(start 437.679338 -209.012536)
					(mid 437.664459 -208.976615)
					(end 437.628538 -208.961736)
				)
				(arc
					(start 436.228998 -208.961736)
					(mid 436.193077 -208.976615)
					(end 436.178198 -209.012536)
				)
			)
		)
	)
	(zone
		(layers "In1.Cu" "In2.Cu")
		(hatch none 0.5)
		(connect_pads
			(clearance 0)
		)
		(min_thickness 0.25)
		(keepout
			(tracks not_allowed)
			(vias allowed)
			(pads allowed)
			(copperpour not_allowed)
			(footprints allowed)
		)
		(placement
			(enabled no)
			(sheetname "")
		)
		(fill yes
			(thermal_gap 0.5)
			(thermal_bridge_width 0.5)
			(island_removal_mode 0)
		)
		(polygon
			(pts
				(arc
					(start 312.236866 -200.071482)
					(mid 312.251745 -200.107403)
					(end 312.287666 -200.122282)
				)
				(arc
					(start 313.687206 -200.122282)
					(mid 313.723127 -200.107403)
					(end 313.738006 -200.071482)
				)
				(arc
					(start 313.738006 -199.662542)
					(mid 313.723127 -199.626621)
					(end 313.687206 -199.611742)
				)
				(arc
					(start 312.287666 -199.611742)
					(mid 312.251745 -199.626621)
					(end 312.236866 -199.662542)
				)
			)
		)
	)
	(zone
		(layers "In1.Cu" "In2.Cu")
		(hatch none 0.5)
		(connect_pads
			(clearance 0)
		)
		(min_thickness 0.25)
		(keepout
			(tracks not_allowed)
			(vias allowed)
			(pads allowed)
			(copperpour not_allowed)
			(footprints allowed)
		)
		(placement
			(enabled no)
			(sheetname "")
		)
		(fill yes
			(thermal_gap 0.5)
			(thermal_bridge_width 0.5)
			(island_removal_mode 0)
		)
		(polygon
			(pts
				(arc
					(start 169.706798 -298.671488)
					(mid 169.721677 -298.707409)
					(end 169.757598 -298.722288)
				)
				(arc
					(start 171.157138 -298.722288)
					(mid 171.193059 -298.707409)
					(end 171.207938 -298.671488)
				)
				(arc
					(start 171.207938 -298.262548)
					(mid 171.193059 -298.226627)
					(end 171.157138 -298.211748)
				)
				(arc
					(start 169.757598 -298.211748)
					(mid 169.721677 -298.226627)
					(end 169.706798 -298.262548)
				)
			)
		)
	)
	(zone
		(layers "In1.Cu" "In2.Cu")
		(hatch none 0.5)
		(connect_pads
			(clearance 0)
		)
		(min_thickness 0.25)
		(keepout
			(tracks not_allowed)
			(vias allowed)
			(pads allowed)
			(copperpour not_allowed)
			(footprints allowed)
		)
		(placement
			(enabled no)
			(sheetname "")
		)
		(fill yes
			(thermal_gap 0.5)
			(thermal_bridge_width 0.5)
			(island_removal_mode 0)
		)
		(polygon
			(pts
				(arc
					(start 270.417798 -303.7713)
					(mid 270.432677 -303.807221)
					(end 270.468598 -303.8221)
				)
				(arc
					(start 271.868138 -303.8221)
					(mid 271.904059 -303.807221)
					(end 271.918938 -303.7713)
				)
				(arc
					(start 271.918938 -303.36236)
					(mid 271.904059 -303.326439)
					(end 271.868138 -303.31156)
				)
				(arc
					(start 270.468598 -303.31156)
					(mid 270.432677 -303.326439)
					(end 270.417798 -303.36236)
				)
			)
		)
	)
	(zone
		(layers "In1.Cu" "In2.Cu")
		(hatch none 0.5)
		(connect_pads
			(clearance 0)
		)
		(min_thickness 0.25)
		(keepout
			(tracks not_allowed)
			(vias allowed)
			(pads allowed)
			(copperpour not_allowed)
			(footprints allowed)
		)
		(placement
			(enabled no)
			(sheetname "")
		)
		(fill yes
			(thermal_gap 0.5)
			(thermal_bridge_width 0.5)
			(island_removal_mode 0)
		)
		(polygon
			(pts
				(arc
					(start 41.665398 -312.27141)
					(mid 41.680277 -312.307331)
					(end 41.716198 -312.32221)
				)
				(arc
					(start 43.115738 -312.32221)
					(mid 43.151659 -312.307331)
					(end 43.166538 -312.27141)
				)
				(arc
					(start 43.166538 -311.86247)
					(mid 43.151659 -311.826549)
					(end 43.115738 -311.81167)
				)
				(arc
					(start 41.716198 -311.81167)
					(mid 41.680277 -311.826549)
					(end 41.665398 -311.86247)
				)
			)
		)
	)
	(zone
		(layers "In1.Cu" "In2.Cu")
		(hatch none 0.5)
		(connect_pads
			(clearance 0)
		)
		(min_thickness 0.25)
		(keepout
			(tracks not_allowed)
			(vias allowed)
			(pads allowed)
			(copperpour not_allowed)
			(footprints allowed)
		)
		(placement
			(enabled no)
			(sheetname "")
		)
		(fill yes
			(thermal_gap 0.5)
			(thermal_bridge_width 0.5)
			(island_removal_mode 0)
		)
		(polygon
			(pts
				(arc
					(start 308.136798 -209.421476)
					(mid 308.151677 -209.457397)
					(end 308.187598 -209.472276)
				)
				(arc
					(start 309.587138 -209.472276)
					(mid 309.623059 -209.457397)
					(end 309.637938 -209.421476)
				)
				(arc
					(start 309.637938 -209.012536)
					(mid 309.623059 -208.976615)
					(end 309.587138 -208.961736)
				)
				(arc
					(start 308.187598 -208.961736)
					(mid 308.151677 -208.976615)
					(end 308.136798 -209.012536)
				)
			)
		)
	)
	(zone
		(layers "In1.Cu" "In2.Cu")
		(hatch none 0.5)
		(connect_pads
			(clearance 0)
		)
		(min_thickness 0.25)
		(keepout
			(tracks not_allowed)
			(vias allowed)
			(pads allowed)
			(copperpour not_allowed)
			(footprints allowed)
		)
		(placement
			(enabled no)
			(sheetname "")
		)
		(fill yes
			(thermal_gap 0.5)
			(thermal_bridge_width 0.5)
			(island_removal_mode 0)
		)
		(polygon
			(pts
				(arc
					(start 300.592998 -290.171378)
					(mid 300.607877 -290.207299)
					(end 300.643798 -290.222178)
				)
				(arc
					(start 302.043338 -290.222178)
					(mid 302.079259 -290.207299)
					(end 302.094138 -290.171378)
				)
				(arc
					(start 302.094138 -289.762438)
					(mid 302.079259 -289.726517)
					(end 302.043338 -289.711638)
				)
				(arc
					(start 300.643798 -289.711638)
					(mid 300.607877 -289.726517)
					(end 300.592998 -289.762438)
				)
			)
		)
	)
	(zone
		(layers "In1.Cu" "In2.Cu")
		(hatch none 0.5)
		(connect_pads
			(clearance 0)
		)
		(min_thickness 0.25)
		(keepout
			(tracks not_allowed)
			(vias allowed)
			(pads allowed)
			(copperpour not_allowed)
			(footprints allowed)
		)
		(placement
			(enabled no)
			(sheetname "")
		)
		(fill yes
			(thermal_gap 0.5)
			(thermal_bridge_width 0.5)
			(island_removal_mode 0)
		)
		(polygon
			(pts
				(arc
					(start 436.178198 -245.971314)
					(mid 436.193077 -246.007235)
					(end 436.228998 -246.022114)
				)
				(arc
					(start 437.628538 -246.022114)
					(mid 437.664459 -246.007235)
					(end 437.679338 -245.971314)
				)
				(arc
					(start 437.679338 -245.562374)
					(mid 437.664459 -245.526453)
					(end 437.628538 -245.511574)
				)
				(arc
					(start 436.228998 -245.511574)
					(mid 436.193077 -245.526453)
					(end 436.178198 -245.562374)
				)
			)
		)
	)
	(zone
		(layers "In1.Cu" "In2.Cu")
		(hatch none 0.5)
		(connect_pads
			(clearance 0)
		)
		(min_thickness 0.25)
		(keepout
			(tracks not_allowed)
			(vias allowed)
			(pads allowed)
			(copperpour not_allowed)
			(footprints allowed)
		)
		(placement
			(enabled no)
			(sheetname "")
		)
		(fill yes
			(thermal_gap 0.5)
			(thermal_bridge_width 0.5)
			(island_removal_mode 0)
		)
		(polygon
			(pts
				(arc
					(start 312.236866 -209.421476)
					(mid 312.251745 -209.457397)
					(end 312.287666 -209.472276)
				)
				(arc
					(start 313.687206 -209.472276)
					(mid 313.723127 -209.457397)
					(end 313.738006 -209.421476)
				)
				(arc
					(start 313.738006 -209.012536)
					(mid 313.723127 -208.976615)
					(end 313.687206 -208.961736)
				)
				(arc
					(start 312.287666 -208.961736)
					(mid 312.251745 -208.976615)
					(end 312.236866 -209.012536)
				)
			)
		)
	)
	(zone
		(layers "In1.Cu" "In2.Cu")
		(hatch none 0.5)
		(connect_pads
			(clearance 0)
		)
		(min_thickness 0.25)
		(keepout
			(tracks not_allowed)
			(vias allowed)
			(pads allowed)
			(copperpour not_allowed)
			(footprints allowed)
		)
		(placement
			(enabled no)
			(sheetname "")
		)
		(fill yes
			(thermal_gap 0.5)
			(thermal_bridge_width 0.5)
			(island_removal_mode 0)
		)
		(polygon
			(pts
				(arc
					(start 304.693066 -205.171548)
					(mid 304.707945 -205.207469)
					(end 304.743866 -205.222348)
				)
				(arc
					(start 306.143406 -205.222348)
					(mid 306.179327 -205.207469)
					(end 306.194206 -205.171548)
				)
				(arc
					(start 306.194206 -204.762608)
					(mid 306.179327 -204.726687)
					(end 306.143406 -204.711808)
				)
				(arc
					(start 304.743866 -204.711808)
					(mid 304.707945 -204.726687)
					(end 304.693066 -204.762608)
				)
			)
		)
	)
	(zone
		(layers "In1.Cu" "In2.Cu")
		(hatch none 0.5)
		(connect_pads
			(clearance 0)
		)
		(min_thickness 0.25)
		(keepout
			(tracks not_allowed)
			(vias allowed)
			(pads allowed)
			(copperpour not_allowed)
			(footprints allowed)
		)
		(placement
			(enabled no)
			(sheetname "")
		)
		(fill yes
			(thermal_gap 0.5)
			(thermal_bridge_width 0.5)
			(island_removal_mode 0)
		)
		(polygon
			(pts
				(arc
					(start 270.417798 -266.371324)
					(mid 270.432677 -266.407245)
					(end 270.468598 -266.422124)
				)
				(arc
					(start 271.868138 -266.422124)
					(mid 271.904059 -266.407245)
					(end 271.918938 -266.371324)
				)
				(arc
					(start 271.918938 -265.962384)
					(mid 271.904059 -265.926463)
					(end 271.868138 -265.911584)
				)
				(arc
					(start 270.468598 -265.911584)
					(mid 270.432677 -265.926463)
					(end 270.417798 -265.962384)
				)
			)
		)
	)
	(zone
		(layers "In1.Cu" "In2.Cu")
		(hatch none 0.5)
		(connect_pads
			(clearance 0)
		)
		(min_thickness 0.25)
		(keepout
			(tracks not_allowed)
			(vias allowed)
			(pads allowed)
			(copperpour not_allowed)
			(footprints allowed)
		)
		(placement
			(enabled no)
			(sheetname "")
		)
		(fill yes
			(thermal_gap 0.5)
			(thermal_bridge_width 0.5)
			(island_removal_mode 0)
		)
		(polygon
			(pts
				(arc
					(start 207.425798 -246.821452)
					(mid 207.440677 -246.857373)
					(end 207.476598 -246.872252)
				)
				(arc
					(start 208.876138 -246.872252)
					(mid 208.912059 -246.857373)
					(end 208.926938 -246.821452)
				)
				(arc
					(start 208.926938 -246.412512)
					(mid 208.912059 -246.376591)
					(end 208.876138 -246.361712)
				)
				(arc
					(start 207.476598 -246.361712)
					(mid 207.440677 -246.376591)
					(end 207.425798 -246.412512)
				)
			)
		)
	)
	(zone
		(layers "In1.Cu" "In2.Cu")
		(hatch none 0.5)
		(connect_pads
			(clearance 0)
		)
		(min_thickness 0.25)
		(keepout
			(tracks not_allowed)
			(vias allowed)
			(pads allowed)
			(copperpour not_allowed)
			(footprints allowed)
		)
		(placement
			(enabled no)
			(sheetname "")
		)
		(fill yes
			(thermal_gap 0.5)
			(thermal_bridge_width 0.5)
			(island_removal_mode 0)
		)
		(polygon
			(pts
				(arc
					(start 413.546798 -230.67137)
					(mid 413.561677 -230.707291)
					(end 413.597598 -230.72217)
				)
				(arc
					(start 414.997138 -230.72217)
					(mid 415.033059 -230.707291)
					(end 415.047938 -230.67137)
				)
				(arc
					(start 415.047938 -230.26243)
					(mid 415.033059 -230.226509)
					(end 414.997138 -230.21163)
				)
				(arc
					(start 413.597598 -230.21163)
					(mid 413.561677 -230.226509)
					(end 413.546798 -230.26243)
				)
			)
		)
	)
	(zone
		(layers "In1.Cu" "In2.Cu")
		(hatch none 0.5)
		(connect_pads
			(clearance 0)
		)
		(min_thickness 0.25)
		(keepout
			(tracks not_allowed)
			(vias allowed)
			(pads allowed)
			(copperpour not_allowed)
			(footprints allowed)
		)
		(placement
			(enabled no)
			(sheetname "")
		)
		(fill yes
			(thermal_gap 0.5)
			(thermal_bridge_width 0.5)
			(island_removal_mode 0)
		)
		(polygon
			(pts
				(arc
					(start 177.250598 -308.021482)
					(mid 177.265477 -308.057403)
					(end 177.301398 -308.072282)
				)
				(arc
					(start 178.700938 -308.072282)
					(mid 178.736859 -308.057403)
					(end 178.751738 -308.021482)
				)
				(arc
					(start 178.751738 -307.612542)
					(mid 178.736859 -307.576621)
					(end 178.700938 -307.561742)
				)
				(arc
					(start 177.301398 -307.561742)
					(mid 177.265477 -307.576621)
					(end 177.250598 -307.612542)
				)
			)
		)
	)
	(zone
		(layers "In1.Cu" "In2.Cu")
		(hatch none 0.5)
		(connect_pads
			(clearance 0)
		)
		(min_thickness 0.25)
		(keepout
			(tracks not_allowed)
			(vias allowed)
			(pads allowed)
			(copperpour not_allowed)
			(footprints allowed)
		)
		(placement
			(enabled no)
			(sheetname "")
		)
		(fill yes
			(thermal_gap 0.5)
			(thermal_bridge_width 0.5)
			(island_removal_mode 0)
		)
		(polygon
			(pts
				(arc
					(start 11.490198 -195.821554)
					(mid 11.505077 -195.857475)
					(end 11.540998 -195.872354)
				)
				(arc
					(start 12.940538 -195.872354)
					(mid 12.976459 -195.857475)
					(end 12.991338 -195.821554)
				)
				(arc
					(start 12.991338 -195.412614)
					(mid 12.976459 -195.376693)
					(end 12.940538 -195.361814)
				)
				(arc
					(start 11.540998 -195.361814)
					(mid 11.505077 -195.376693)
					(end 11.490198 -195.412614)
				)
			)
		)
	)
	(zone
		(layers "In1.Cu" "In2.Cu")
		(hatch none 0.5)
		(connect_pads
			(clearance 0)
		)
		(min_thickness 0.25)
		(keepout
			(tracks not_allowed)
			(vias allowed)
			(pads allowed)
			(copperpour not_allowed)
			(footprints allowed)
		)
		(placement
			(enabled no)
			(sheetname "")
		)
		(fill yes
			(thermal_gap 0.5)
			(thermal_bridge_width 0.5)
			(island_removal_mode 0)
		)
		(polygon
			(pts
				(arc
					(start 440.278266 -302.921416)
					(mid 440.293145 -302.957337)
					(end 440.329066 -302.972216)
				)
				(arc
					(start 441.728606 -302.972216)
					(mid 441.764527 -302.957337)
					(end 441.779406 -302.921416)
				)
				(arc
					(start 441.779406 -302.512476)
					(mid 441.764527 -302.476555)
					(end 441.728606 -302.461676)
				)
				(arc
					(start 440.329066 -302.461676)
					(mid 440.293145 -302.476555)
					(end 440.278266 -302.512476)
				)
			)
		)
	)
	(zone
		(layers "In1.Cu" "In2.Cu")
		(hatch none 0.5)
		(connect_pads
			(clearance 0)
		)
		(min_thickness 0.25)
		(keepout
			(tracks not_allowed)
			(vias allowed)
			(pads allowed)
			(copperpour not_allowed)
			(footprints allowed)
		)
		(placement
			(enabled no)
			(sheetname "")
		)
		(fill yes
			(thermal_gap 0.5)
			(thermal_bridge_width 0.5)
			(island_removal_mode 0)
		)
		(polygon
			(pts
				(arc
					(start 11.490198 -260.421374)
					(mid 11.505077 -260.457295)
					(end 11.540998 -260.472174)
				)
				(arc
					(start 12.940538 -260.472174)
					(mid 12.976459 -260.457295)
					(end 12.991338 -260.421374)
				)
				(arc
					(start 12.991338 -260.012434)
					(mid 12.976459 -259.976513)
					(end 12.940538 -259.961634)
				)
				(arc
					(start 11.540998 -259.961634)
					(mid 11.505077 -259.976513)
					(end 11.490198 -260.012434)
				)
			)
		)
	)
	(zone
		(layers "In1.Cu" "In2.Cu")
		(hatch none 0.5)
		(connect_pads
			(clearance 0)
		)
		(min_thickness 0.25)
		(keepout
			(tracks not_allowed)
			(vias allowed)
			(pads allowed)
			(copperpour not_allowed)
			(footprints allowed)
		)
		(placement
			(enabled no)
			(sheetname "")
		)
		(fill yes
			(thermal_gap 0.5)
			(thermal_bridge_width 0.5)
			(island_removal_mode 0)
		)
		(polygon
			(pts
				(arc
					(start 41.665398 -313.971432)
					(mid 41.680277 -314.007353)
					(end 41.716198 -314.022232)
				)
				(arc
					(start 43.115738 -314.022232)
					(mid 43.151659 -314.007353)
					(end 43.166538 -313.971432)
				)
				(arc
					(start 43.166538 -313.562492)
					(mid 43.151659 -313.526571)
					(end 43.115738 -313.511692)
				)
				(arc
					(start 41.716198 -313.511692)
					(mid 41.680277 -313.526571)
					(end 41.665398 -313.562492)
				)
			)
		)
	)
	(zone
		(layers "In1.Cu" "In2.Cu")
		(hatch none 0.5)
		(connect_pads
			(clearance 0)
		)
		(min_thickness 0.25)
		(keepout
			(tracks not_allowed)
			(vias allowed)
			(pads allowed)
			(copperpour not_allowed)
			(footprints allowed)
		)
		(placement
			(enabled no)
			(sheetname "")
		)
		(fill yes
			(thermal_gap 0.5)
			(thermal_bridge_width 0.5)
			(island_removal_mode 0)
		)
		(polygon
			(pts
				(arc
					(start 259.430266 -251.921518)
					(mid 259.445145 -251.957439)
					(end 259.481066 -251.972318)
				)
				(arc
					(start 260.880606 -251.972318)
					(mid 260.916527 -251.957439)
					(end 260.931406 -251.921518)
				)
				(arc
					(start 260.931406 -251.512578)
					(mid 260.916527 -251.476657)
					(end 260.880606 -251.461778)
				)
				(arc
					(start 259.481066 -251.461778)
					(mid 259.445145 -251.476657)
					(end 259.430266 -251.512578)
				)
			)
		)
	)
	(zone
		(layers "In1.Cu" "In2.Cu")
		(hatch none 0.5)
		(connect_pads
			(clearance 0)
		)
		(min_thickness 0.25)
		(keepout
			(tracks not_allowed)
			(vias allowed)
			(pads allowed)
			(copperpour not_allowed)
			(footprints allowed)
		)
		(placement
			(enabled no)
			(sheetname "")
		)
		(fill yes
			(thermal_gap 0.5)
			(thermal_bridge_width 0.5)
			(island_removal_mode 0)
		)
		(polygon
			(pts
				(arc
					(start 293.049198 -269.771368)
					(mid 293.064077 -269.807289)
					(end 293.099998 -269.822168)
				)
				(arc
					(start 294.499538 -269.822168)
					(mid 294.535459 -269.807289)
					(end 294.550338 -269.771368)
				)
				(arc
					(start 294.550338 -269.362428)
					(mid 294.535459 -269.326507)
					(end 294.499538 -269.311628)
				)
				(arc
					(start 293.099998 -269.311628)
					(mid 293.064077 -269.326507)
					(end 293.049198 -269.362428)
				)
			)
		)
	)
	(zone
		(layers "In1.Cu" "In2.Cu")
		(hatch none 0.5)
		(connect_pads
			(clearance 0)
		)
		(min_thickness 0.25)
		(keepout
			(tracks not_allowed)
			(vias allowed)
			(pads allowed)
			(copperpour not_allowed)
			(footprints allowed)
		)
		(placement
			(enabled no)
			(sheetname "")
		)
		(fill yes
			(thermal_gap 0.5)
			(thermal_bridge_width 0.5)
			(island_removal_mode 0)
		)
		(polygon
			(pts
				(arc
					(start 282.061666 -206.871316)
					(mid 282.076545 -206.907237)
					(end 282.112466 -206.922116)
				)
				(arc
					(start 283.512006 -206.922116)
					(mid 283.547927 -206.907237)
					(end 283.562806 -206.871316)
				)
				(arc
					(start 283.562806 -206.462376)
					(mid 283.547927 -206.426455)
					(end 283.512006 -206.411576)
				)
				(arc
					(start 282.112466 -206.411576)
					(mid 282.076545 -206.426455)
					(end 282.061666 -206.462376)
				)
			)
		)
	)
	(zone
		(layers "In1.Cu" "In2.Cu")
		(hatch none 0.5)
		(connect_pads
			(clearance 0)
		)
		(min_thickness 0.25)
		(keepout
			(tracks not_allowed)
			(vias allowed)
			(pads allowed)
			(copperpour not_allowed)
			(footprints allowed)
		)
		(placement
			(enabled no)
			(sheetname "")
		)
		(fill yes
			(thermal_gap 0.5)
			(thermal_bridge_width 0.5)
			(island_removal_mode 0)
		)
		(polygon
			(pts
				(arc
					(start 177.250598 -216.22131)
					(mid 177.265477 -216.257231)
					(end 177.301398 -216.27211)
				)
				(arc
					(start 178.700938 -216.27211)
					(mid 178.736859 -216.257231)
					(end 178.751738 -216.22131)
				)
				(arc
					(start 178.751738 -215.81237)
					(mid 178.736859 -215.776449)
					(end 178.700938 -215.76157)
				)
				(arc
					(start 177.301398 -215.76157)
					(mid 177.265477 -215.776449)
					(end 177.250598 -215.81237)
				)
			)
		)
	)
	(zone
		(layers "In1.Cu" "In2.Cu")
		(hatch none 0.5)
		(connect_pads
			(clearance 0)
		)
		(min_thickness 0.25)
		(keepout
			(tracks not_allowed)
			(vias allowed)
			(pads allowed)
			(copperpour not_allowed)
			(footprints allowed)
		)
		(placement
			(enabled no)
			(sheetname "")
		)
		(fill yes
			(thermal_gap 0.5)
			(thermal_bridge_width 0.5)
			(island_removal_mode 0)
		)
		(polygon
			(pts
				(arc
					(start 173.15053 -245.971314)
					(mid 173.165409 -246.007235)
					(end 173.20133 -246.022114)
				)
				(arc
					(start 174.60087 -246.022114)
					(mid 174.636791 -246.007235)
					(end 174.65167 -245.971314)
				)
				(arc
					(start 174.65167 -245.562374)
					(mid 174.636791 -245.526453)
					(end 174.60087 -245.511574)
				)
				(arc
					(start 173.20133 -245.511574)
					(mid 173.165409 -245.526453)
					(end 173.15053 -245.562374)
				)
			)
		)
	)
	(zone
		(layers "In1.Cu" "In2.Cu")
		(hatch none 0.5)
		(connect_pads
			(clearance 0)
		)
		(min_thickness 0.25)
		(keepout
			(tracks not_allowed)
			(vias allowed)
			(pads allowed)
			(copperpour not_allowed)
			(footprints allowed)
		)
		(placement
			(enabled no)
			(sheetname "")
		)
		(fill yes
			(thermal_gap 0.5)
			(thermal_bridge_width 0.5)
			(island_removal_mode 0)
		)
		(polygon
			(pts
				(arc
					(start 214.969598 -287.621472)
					(mid 214.984477 -287.657393)
					(end 215.020398 -287.672272)
				)
				(arc
					(start 216.419938 -287.672272)
					(mid 216.455859 -287.657393)
					(end 216.470738 -287.621472)
				)
				(arc
					(start 216.470738 -287.212532)
					(mid 216.455859 -287.176611)
					(end 216.419938 -287.161732)
				)
				(arc
					(start 215.020398 -287.161732)
					(mid 214.984477 -287.176611)
					(end 214.969598 -287.212532)
				)
			)
		)
	)
	(zone
		(layers "In1.Cu" "In2.Cu")
		(hatch none 0.5)
		(connect_pads
			(clearance 0)
		)
		(min_thickness 0.25)
		(keepout
			(tracks not_allowed)
			(vias allowed)
			(pads allowed)
			(copperpour not_allowed)
			(footprints allowed)
		)
		(placement
			(enabled no)
			(sheetname "")
		)
		(fill yes
			(thermal_gap 0.5)
			(thermal_bridge_width 0.5)
			(island_removal_mode 0)
		)
		(polygon
			(pts
				(arc
					(start 451.265798 -316.521338)
					(mid 451.280677 -316.557259)
					(end 451.316598 -316.572138)
				)
				(arc
					(start 452.716138 -316.572138)
					(mid 452.752059 -316.557259)
					(end 452.766938 -316.521338)
				)
				(arc
					(start 452.766938 -316.112398)
					(mid 452.752059 -316.076477)
					(end 452.716138 -316.061598)
				)
				(arc
					(start 451.316598 -316.061598)
					(mid 451.280677 -316.076477)
					(end 451.265798 -316.112398)
				)
			)
		)
	)
	(zone
		(layers "In1.Cu" "In2.Cu")
		(hatch none 0.5)
		(connect_pads
			(clearance 0)
		)
		(min_thickness 0.25)
		(keepout
			(tracks not_allowed)
			(vias allowed)
			(pads allowed)
			(copperpour not_allowed)
			(footprints allowed)
		)
		(placement
			(enabled no)
			(sheetname "")
		)
		(fill yes
			(thermal_gap 0.5)
			(thermal_bridge_width 0.5)
			(island_removal_mode 0)
		)
		(polygon
			(pts
				(arc
					(start 158.06293 -259.57149)
					(mid 158.077809 -259.607411)
					(end 158.11373 -259.62229)
				)
				(arc
					(start 159.51327 -259.62229)
					(mid 159.549191 -259.607411)
					(end 159.56407 -259.57149)
				)
				(arc
					(start 159.56407 -259.16255)
					(mid 159.549191 -259.126629)
					(end 159.51327 -259.11175)
				)
				(arc
					(start 158.11373 -259.11175)
					(mid 158.077809 -259.126629)
					(end 158.06293 -259.16255)
				)
			)
		)
	)
	(zone
		(layers "In1.Cu" "In2.Cu")
		(hatch none 0.5)
		(connect_pads
			(clearance 0)
		)
		(min_thickness 0.25)
		(keepout
			(tracks not_allowed)
			(vias allowed)
			(pads allowed)
			(copperpour not_allowed)
			(footprints allowed)
		)
		(placement
			(enabled no)
			(sheetname "")
		)
		(fill yes
			(thermal_gap 0.5)
			(thermal_bridge_width 0.5)
			(island_removal_mode 0)
		)
		(polygon
			(pts
				(arc
					(start 180.69433 -202.621388)
					(mid 180.709209 -202.657309)
					(end 180.74513 -202.672188)
				)
				(arc
					(start 182.14467 -202.672188)
					(mid 182.180591 -202.657309)
					(end 182.19547 -202.621388)
				)
				(arc
					(start 182.19547 -202.212448)
					(mid 182.180591 -202.176527)
					(end 182.14467 -202.161648)
				)
				(arc
					(start 180.74513 -202.161648)
					(mid 180.709209 -202.176527)
					(end 180.69433 -202.212448)
				)
			)
		)
	)
	(zone
		(layers "In1.Cu" "In2.Cu")
		(hatch none 0.5)
		(connect_pads
			(clearance 0)
		)
		(min_thickness 0.25)
		(keepout
			(tracks not_allowed)
			(vias allowed)
			(pads allowed)
			(copperpour not_allowed)
			(footprints allowed)
		)
		(placement
			(enabled no)
			(sheetname "")
		)
		(fill yes
			(thermal_gap 0.5)
			(thermal_bridge_width 0.5)
			(island_removal_mode 0)
		)
		(polygon
			(pts
				(arc
					(start 180.69433 -213.671404)
					(mid 180.709209 -213.707325)
					(end 180.74513 -213.722204)
				)
				(arc
					(start 182.14467 -213.722204)
					(mid 182.180591 -213.707325)
					(end 182.19547 -213.671404)
				)
				(arc
					(start 182.19547 -213.262464)
					(mid 182.180591 -213.226543)
					(end 182.14467 -213.211664)
				)
				(arc
					(start 180.74513 -213.211664)
					(mid 180.709209 -213.226543)
					(end 180.69433 -213.262464)
				)
			)
		)
	)
	(zone
		(layers "In1.Cu" "In2.Cu")
		(hatch none 0.5)
		(connect_pads
			(clearance 0)
		)
		(min_thickness 0.25)
		(keepout
			(tracks not_allowed)
			(vias allowed)
			(pads allowed)
			(copperpour not_allowed)
			(footprints allowed)
		)
		(placement
			(enabled no)
			(sheetname "")
		)
		(fill yes
			(thermal_gap 0.5)
			(thermal_bridge_width 0.5)
			(island_removal_mode 0)
		)
		(polygon
			(pts
				(arc
					(start 56.752998 -313.971432)
					(mid 56.767877 -314.007353)
					(end 56.803798 -314.022232)
				)
				(arc
					(start 58.203338 -314.022232)
					(mid 58.239259 -314.007353)
					(end 58.254138 -313.971432)
				)
				(arc
					(start 58.254138 -313.562492)
					(mid 58.239259 -313.526571)
					(end 58.203338 -313.511692)
				)
				(arc
					(start 56.803798 -313.511692)
					(mid 56.767877 -313.526571)
					(end 56.752998 -313.562492)
				)
			)
		)
	)
	(zone
		(layers "In1.Cu" "In2.Cu")
		(hatch none 0.5)
		(connect_pads
			(clearance 0)
		)
		(min_thickness 0.25)
		(keepout
			(tracks not_allowed)
			(vias allowed)
			(pads allowed)
			(copperpour not_allowed)
			(footprints allowed)
		)
		(placement
			(enabled no)
			(sheetname "")
		)
		(fill yes
			(thermal_gap 0.5)
			(thermal_bridge_width 0.5)
			(island_removal_mode 0)
		)
		(polygon
			(pts
				(arc
					(start 203.32573 -308.871366)
					(mid 203.340609 -308.907287)
					(end 203.37653 -308.922166)
				)
				(arc
					(start 204.77607 -308.922166)
					(mid 204.811991 -308.907287)
					(end 204.82687 -308.871366)
				)
				(arc
					(start 204.82687 -308.462426)
					(mid 204.811991 -308.426505)
					(end 204.77607 -308.411626)
				)
				(arc
					(start 203.37653 -308.411626)
					(mid 203.340609 -308.426505)
					(end 203.32573 -308.462426)
				)
			)
		)
	)
	(zone
		(layers "In1.Cu" "In2.Cu")
		(hatch none 0.5)
		(connect_pads
			(clearance 0)
		)
		(min_thickness 0.25)
		(keepout
			(tracks not_allowed)
			(vias allowed)
			(pads allowed)
			(copperpour not_allowed)
			(footprints allowed)
		)
		(placement
			(enabled no)
			(sheetname "")
		)
		(fill yes
			(thermal_gap 0.5)
			(thermal_bridge_width 0.5)
			(island_removal_mode 0)
		)
		(polygon
			(pts
				(arc
					(start 188.23813 -264.671302)
					(mid 188.253009 -264.707223)
					(end 188.28893 -264.722102)
				)
				(arc
					(start 189.68847 -264.722102)
					(mid 189.724391 -264.707223)
					(end 189.73927 -264.671302)
				)
				(arc
					(start 189.73927 -264.262362)
					(mid 189.724391 -264.226441)
					(end 189.68847 -264.211562)
				)
				(arc
					(start 188.28893 -264.211562)
					(mid 188.253009 -264.226441)
					(end 188.23813 -264.262362)
				)
			)
		)
	)
	(zone
		(layers "In1.Cu" "In2.Cu")
		(hatch none 0.5)
		(connect_pads
			(clearance 0)
		)
		(min_thickness 0.25)
		(keepout
			(tracks not_allowed)
			(vias allowed)
			(pads allowed)
			(copperpour not_allowed)
			(footprints allowed)
		)
		(placement
			(enabled no)
			(sheetname "")
		)
		(fill yes
			(thermal_gap 0.5)
			(thermal_bridge_width 0.5)
			(island_removal_mode 0)
		)
		(polygon
			(pts
				(arc
					(start 304.693066 -208.571338)
					(mid 304.707945 -208.607259)
					(end 304.743866 -208.622138)
				)
				(arc
					(start 306.143406 -208.622138)
					(mid 306.179327 -208.607259)
					(end 306.194206 -208.571338)
				)
				(arc
					(start 306.194206 -208.162398)
					(mid 306.179327 -208.126477)
					(end 306.143406 -208.111598)
				)
				(arc
					(start 304.743866 -208.111598)
					(mid 304.707945 -208.126477)
					(end 304.693066 -208.162398)
				)
			)
		)
	)
	(zone
		(layers "In1.Cu" "In2.Cu")
		(hatch none 0.5)
		(connect_pads
			(clearance 0)
		)
		(min_thickness 0.25)
		(keepout
			(tracks not_allowed)
			(vias allowed)
			(pads allowed)
			(copperpour not_allowed)
			(footprints allowed)
		)
		(placement
			(enabled no)
			(sheetname "")
		)
		(fill yes
			(thermal_gap 0.5)
			(thermal_bridge_width 0.5)
			(island_removal_mode 0)
		)
		(polygon
			(pts
				(arc
					(start 7.39013 -241.721386)
					(mid 7.405009 -241.757307)
					(end 7.44093 -241.772186)
				)
				(arc
					(start 8.84047 -241.772186)
					(mid 8.876391 -241.757307)
					(end 8.89127 -241.721386)
				)
				(arc
					(start 8.89127 -241.312446)
					(mid 8.876391 -241.276525)
					(end 8.84047 -241.261646)
				)
				(arc
					(start 7.44093 -241.261646)
					(mid 7.405009 -241.276525)
					(end 7.39013 -241.312446)
				)
			)
		)
	)
	(zone
		(layers "In1.Cu" "In2.Cu")
		(hatch none 0.5)
		(connect_pads
			(clearance 0)
		)
		(min_thickness 0.25)
		(keepout
			(tracks not_allowed)
			(vias allowed)
			(pads allowed)
			(copperpour not_allowed)
			(footprints allowed)
		)
		(placement
			(enabled no)
			(sheetname "")
		)
		(fill yes
			(thermal_gap 0.5)
			(thermal_bridge_width 0.5)
			(island_removal_mode 0)
		)
		(polygon
			(pts
				(arc
					(start 259.430266 -306.32146)
					(mid 259.445145 -306.357381)
					(end 259.481066 -306.37226)
				)
				(arc
					(start 260.880606 -306.37226)
					(mid 260.916527 -306.357381)
					(end 260.931406 -306.32146)
				)
				(arc
					(start 260.931406 -305.91252)
					(mid 260.916527 -305.876599)
					(end 260.880606 -305.86172)
				)
				(arc
					(start 259.481066 -305.86172)
					(mid 259.445145 -305.876599)
					(end 259.430266 -305.91252)
				)
			)
		)
	)
	(zone
		(layers "In1.Cu" "In2.Cu")
		(hatch none 0.5)
		(connect_pads
			(clearance 0)
		)
		(min_thickness 0.25)
		(keepout
			(tracks not_allowed)
			(vias allowed)
			(pads allowed)
			(copperpour not_allowed)
			(footprints allowed)
		)
		(placement
			(enabled no)
			(sheetname "")
		)
		(fill yes
			(thermal_gap 0.5)
			(thermal_bridge_width 0.5)
			(island_removal_mode 0)
		)
		(polygon
			(pts
				(arc
					(start 436.178198 -238.321342)
					(mid 436.193077 -238.357263)
					(end 436.228998 -238.372142)
				)
				(arc
					(start 437.628538 -238.372142)
					(mid 437.664459 -238.357263)
					(end 437.679338 -238.321342)
				)
				(arc
					(start 437.679338 -237.912402)
					(mid 437.664459 -237.876481)
					(end 437.628538 -237.861602)
				)
				(arc
					(start 436.228998 -237.861602)
					(mid 436.193077 -237.876481)
					(end 436.178198 -237.912402)
				)
			)
		)
	)
	(zone
		(layers "In1.Cu" "In2.Cu")
		(hatch none 0.5)
		(connect_pads
			(clearance 0)
		)
		(min_thickness 0.25)
		(keepout
			(tracks not_allowed)
			(vias allowed)
			(pads allowed)
			(copperpour not_allowed)
			(footprints allowed)
		)
		(placement
			(enabled no)
			(sheetname "")
		)
		(fill yes
			(thermal_gap 0.5)
			(thermal_bridge_width 0.5)
			(island_removal_mode 0)
		)
		(polygon
			(pts
				(arc
					(start 7.39013 -243.421408)
					(mid 7.405009 -243.457329)
					(end 7.44093 -243.472208)
				)
				(arc
					(start 8.84047 -243.472208)
					(mid 8.876391 -243.457329)
					(end 8.89127 -243.421408)
				)
				(arc
					(start 8.89127 -243.012468)
					(mid 8.876391 -242.976547)
					(end 8.84047 -242.961668)
				)
				(arc
					(start 7.44093 -242.961668)
					(mid 7.405009 -242.976547)
					(end 7.39013 -243.012468)
				)
			)
		)
	)
	(zone
		(layers "In1.Cu" "In2.Cu")
		(hatch none 0.5)
		(connect_pads
			(clearance 0)
		)
		(min_thickness 0.25)
		(keepout
			(tracks not_allowed)
			(vias allowed)
			(pads allowed)
			(copperpour not_allowed)
			(footprints allowed)
		)
		(placement
			(enabled no)
			(sheetname "")
		)
		(fill yes
			(thermal_gap 0.5)
			(thermal_bridge_width 0.5)
			(island_removal_mode 0)
		)
		(polygon
			(pts
				(arc
					(start 413.546798 -223.021398)
					(mid 413.561677 -223.057319)
					(end 413.597598 -223.072198)
				)
				(arc
					(start 414.997138 -223.072198)
					(mid 415.033059 -223.057319)
					(end 415.047938 -223.021398)
				)
				(arc
					(start 415.047938 -222.612458)
					(mid 415.033059 -222.576537)
					(end 414.997138 -222.561658)
				)
				(arc
					(start 413.597598 -222.561658)
					(mid 413.561677 -222.576537)
					(end 413.546798 -222.612458)
				)
			)
		)
	)
	(zone
		(layers "In1.Cu" "In2.Cu")
		(hatch none 0.5)
		(connect_pads
			(clearance 0)
		)
		(min_thickness 0.25)
		(keepout
			(tracks not_allowed)
			(vias allowed)
			(pads allowed)
			(copperpour not_allowed)
			(footprints allowed)
		)
		(placement
			(enabled no)
			(sheetname "")
		)
		(fill yes
			(thermal_gap 0.5)
			(thermal_bridge_width 0.5)
			(island_removal_mode 0)
		)
		(polygon
			(pts
				(arc
					(start 410.103066 -251.921518)
					(mid 410.117945 -251.957439)
					(end 410.153866 -251.972318)
				)
				(arc
					(start 411.553406 -251.972318)
					(mid 411.589327 -251.957439)
					(end 411.604206 -251.921518)
				)
				(arc
					(start 411.604206 -251.512578)
					(mid 411.589327 -251.476657)
					(end 411.553406 -251.461778)
				)
				(arc
					(start 410.153866 -251.461778)
					(mid 410.117945 -251.476657)
					(end 410.103066 -251.512578)
				)
			)
		)
	)
	(zone
		(layers "In1.Cu" "In2.Cu")
		(hatch none 0.5)
		(connect_pads
			(clearance 0)
		)
		(min_thickness 0.25)
		(keepout
			(tracks not_allowed)
			(vias allowed)
			(pads allowed)
			(copperpour not_allowed)
			(footprints allowed)
		)
		(placement
			(enabled no)
			(sheetname "")
		)
		(fill yes
			(thermal_gap 0.5)
			(thermal_bridge_width 0.5)
			(island_removal_mode 0)
		)
		(polygon
			(pts
				(arc
					(start 195.78193 -198.37146)
					(mid 195.796809 -198.407381)
					(end 195.83273 -198.42226)
				)
				(arc
					(start 197.23227 -198.42226)
					(mid 197.268191 -198.407381)
					(end 197.28307 -198.37146)
				)
				(arc
					(start 197.28307 -197.96252)
					(mid 197.268191 -197.926599)
					(end 197.23227 -197.91172)
				)
				(arc
					(start 195.83273 -197.91172)
					(mid 195.796809 -197.926599)
					(end 195.78193 -197.96252)
				)
			)
		)
	)
	(zone
		(layers "In1.Cu" "In2.Cu")
		(hatch none 0.5)
		(connect_pads
			(clearance 0)
		)
		(min_thickness 0.25)
		(keepout
			(tracks not_allowed)
			(vias allowed)
			(pads allowed)
			(copperpour not_allowed)
			(footprints allowed)
		)
		(placement
			(enabled no)
			(sheetname "")
		)
		(fill yes
			(thermal_gap 0.5)
			(thermal_bridge_width 0.5)
			(island_removal_mode 0)
		)
		(polygon
			(pts
				(arc
					(start 304.693066 -309.721504)
					(mid 304.707945 -309.757425)
					(end 304.743866 -309.772304)
				)
				(arc
					(start 306.143406 -309.772304)
					(mid 306.179327 -309.757425)
					(end 306.194206 -309.721504)
				)
				(arc
					(start 306.194206 -309.312564)
					(mid 306.179327 -309.276643)
					(end 306.143406 -309.261764)
				)
				(arc
					(start 304.743866 -309.261764)
					(mid 304.707945 -309.276643)
					(end 304.693066 -309.312564)
				)
			)
		)
	)
	(zone
		(layers "In1.Cu" "In2.Cu")
		(hatch none 0.5)
		(connect_pads
			(clearance 0)
		)
		(min_thickness 0.25)
		(keepout
			(tracks not_allowed)
			(vias allowed)
			(pads allowed)
			(copperpour not_allowed)
			(footprints allowed)
		)
		(placement
			(enabled no)
			(sheetname "")
		)
		(fill yes
			(thermal_gap 0.5)
			(thermal_bridge_width 0.5)
			(island_removal_mode 0)
		)
		(polygon
			(pts
				(arc
					(start 262.873998 -210.27136)
					(mid 262.888877 -210.307281)
					(end 262.924798 -210.32216)
				)
				(arc
					(start 264.324338 -210.32216)
					(mid 264.360259 -210.307281)
					(end 264.375138 -210.27136)
				)
				(arc
					(start 264.375138 -209.86242)
					(mid 264.360259 -209.826499)
					(end 264.324338 -209.81162)
				)
				(arc
					(start 262.924798 -209.81162)
					(mid 262.888877 -209.826499)
					(end 262.873998 -209.86242)
				)
			)
		)
	)
	(zone
		(layers "In1.Cu" "In2.Cu")
		(hatch none 0.5)
		(connect_pads
			(clearance 0)
		)
		(min_thickness 0.25)
		(keepout
			(tracks not_allowed)
			(vias allowed)
			(pads allowed)
			(copperpour not_allowed)
			(footprints allowed)
		)
		(placement
			(enabled no)
			(sheetname "")
		)
		(fill yes
			(thermal_gap 0.5)
			(thermal_bridge_width 0.5)
			(island_removal_mode 0)
		)
		(polygon
			(pts
				(arc
					(start 192.338198 -309.721504)
					(mid 192.353077 -309.757425)
					(end 192.388998 -309.772304)
				)
				(arc
					(start 193.788538 -309.772304)
					(mid 193.824459 -309.757425)
					(end 193.839338 -309.721504)
				)
				(arc
					(start 193.839338 -309.312564)
					(mid 193.824459 -309.276643)
					(end 193.788538 -309.261764)
				)
				(arc
					(start 192.388998 -309.261764)
					(mid 192.353077 -309.276643)
					(end 192.338198 -309.312564)
				)
			)
		)
	)
	(zone
		(layers "In1.Cu" "In2.Cu")
		(hatch none 0.5)
		(connect_pads
			(clearance 0)
		)
		(min_thickness 0.25)
		(keepout
			(tracks not_allowed)
			(vias allowed)
			(pads allowed)
			(copperpour not_allowed)
			(footprints allowed)
		)
		(placement
			(enabled no)
			(sheetname "")
		)
		(fill yes
			(thermal_gap 0.5)
			(thermal_bridge_width 0.5)
			(island_removal_mode 0)
		)
		(polygon
			(pts
				(arc
					(start 440.278266 -228.121464)
					(mid 440.293145 -228.157385)
					(end 440.329066 -228.172264)
				)
				(arc
					(start 441.728606 -228.172264)
					(mid 441.764527 -228.157385)
					(end 441.779406 -228.121464)
				)
				(arc
					(start 441.779406 -227.712524)
					(mid 441.764527 -227.676603)
					(end 441.728606 -227.661724)
				)
				(arc
					(start 440.329066 -227.661724)
					(mid 440.293145 -227.676603)
					(end 440.278266 -227.712524)
				)
			)
		)
	)
	(zone
		(layers "In1.Cu" "In2.Cu")
		(hatch none 0.5)
		(connect_pads
			(clearance 0)
		)
		(min_thickness 0.25)
		(keepout
			(tracks not_allowed)
			(vias allowed)
			(pads allowed)
			(copperpour not_allowed)
			(footprints allowed)
		)
		(placement
			(enabled no)
			(sheetname "")
		)
		(fill yes
			(thermal_gap 0.5)
			(thermal_bridge_width 0.5)
			(island_removal_mode 0)
		)
		(polygon
			(pts
				(arc
					(start 410.103066 -268.921484)
					(mid 410.117945 -268.957405)
					(end 410.153866 -268.972284)
				)
				(arc
					(start 411.553406 -268.972284)
					(mid 411.589327 -268.957405)
					(end 411.604206 -268.921484)
				)
				(arc
					(start 411.604206 -268.512544)
					(mid 411.589327 -268.476623)
					(end 411.553406 -268.461744)
				)
				(arc
					(start 410.153866 -268.461744)
					(mid 410.117945 -268.476623)
					(end 410.103066 -268.512544)
				)
			)
		)
	)
	(zone
		(layers "In1.Cu" "In2.Cu")
		(hatch none 0.5)
		(connect_pads
			(clearance 0)
		)
		(min_thickness 0.25)
		(keepout
			(tracks not_allowed)
			(vias allowed)
			(pads allowed)
			(copperpour not_allowed)
			(footprints allowed)
		)
		(placement
			(enabled no)
			(sheetname "")
		)
		(fill yes
			(thermal_gap 0.5)
			(thermal_bridge_width 0.5)
			(island_removal_mode 0)
		)
		(polygon
			(pts
				(arc
					(start 270.417798 -196.671438)
					(mid 270.432677 -196.707359)
					(end 270.468598 -196.722238)
				)
				(arc
					(start 271.868138 -196.722238)
					(mid 271.904059 -196.707359)
					(end 271.918938 -196.671438)
				)
				(arc
					(start 271.918938 -196.262498)
					(mid 271.904059 -196.226577)
					(end 271.868138 -196.211698)
				)
				(arc
					(start 270.468598 -196.211698)
					(mid 270.432677 -196.226577)
					(end 270.417798 -196.262498)
				)
			)
		)
	)
	(zone
		(layers "In1.Cu" "In2.Cu")
		(hatch none 0.5)
		(connect_pads
			(clearance 0)
		)
		(min_thickness 0.25)
		(keepout
			(tracks not_allowed)
			(vias allowed)
			(pads allowed)
			(copperpour not_allowed)
			(footprints allowed)
		)
		(placement
			(enabled no)
			(sheetname "")
		)
		(fill yes
			(thermal_gap 0.5)
			(thermal_bridge_width 0.5)
			(island_removal_mode 0)
		)
		(polygon
			(pts
				(arc
					(start 440.278266 -311.421526)
					(mid 440.293145 -311.457447)
					(end 440.329066 -311.472326)
				)
				(arc
					(start 441.728606 -311.472326)
					(mid 441.764527 -311.457447)
					(end 441.779406 -311.421526)
				)
				(arc
					(start 441.779406 -311.012586)
					(mid 441.764527 -310.976665)
					(end 441.728606 -310.961786)
				)
				(arc
					(start 440.329066 -310.961786)
					(mid 440.293145 -310.976665)
					(end 440.278266 -311.012586)
				)
			)
		)
	)
	(zone
		(layers "In1.Cu" "In2.Cu")
		(hatch none 0.5)
		(connect_pads
			(clearance 0)
		)
		(min_thickness 0.25)
		(keepout
			(tracks not_allowed)
			(vias allowed)
			(pads allowed)
			(copperpour not_allowed)
			(footprints allowed)
		)
		(placement
			(enabled no)
			(sheetname "")
		)
		(fill yes
			(thermal_gap 0.5)
			(thermal_bridge_width 0.5)
			(island_removal_mode 0)
		)
		(polygon
			(pts
				(arc
					(start 165.60673 -230.67137)
					(mid 165.621609 -230.707291)
					(end 165.65753 -230.72217)
				)
				(arc
					(start 167.05707 -230.72217)
					(mid 167.092991 -230.707291)
					(end 167.10787 -230.67137)
				)
				(arc
					(start 167.10787 -230.26243)
					(mid 167.092991 -230.226509)
					(end 167.05707 -230.21163)
				)
				(arc
					(start 165.65753 -230.21163)
					(mid 165.621609 -230.226509)
					(end 165.60673 -230.26243)
				)
			)
		)
	)
	(zone
		(layers "In1.Cu" "In2.Cu")
		(hatch none 0.5)
		(connect_pads
			(clearance 0)
		)
		(min_thickness 0.25)
		(keepout
			(tracks not_allowed)
			(vias allowed)
			(pads allowed)
			(copperpour not_allowed)
			(footprints allowed)
		)
		(placement
			(enabled no)
			(sheetname "")
		)
		(fill yes
			(thermal_gap 0.5)
			(thermal_bridge_width 0.5)
			(island_removal_mode 0)
		)
		(polygon
			(pts
				(arc
					(start 300.592998 -284.221428)
					(mid 300.607877 -284.257349)
					(end 300.643798 -284.272228)
				)
				(arc
					(start 302.043338 -284.272228)
					(mid 302.079259 -284.257349)
					(end 302.094138 -284.221428)
				)
				(arc
					(start 302.094138 -283.812488)
					(mid 302.079259 -283.776567)
					(end 302.043338 -283.761688)
				)
				(arc
					(start 300.643798 -283.761688)
					(mid 300.607877 -283.776567)
					(end 300.592998 -283.812488)
				)
			)
		)
	)
	(zone
		(layers "In1.Cu" "In2.Cu")
		(hatch none 0.5)
		(connect_pads
			(clearance 0)
		)
		(min_thickness 0.25)
		(keepout
			(tracks not_allowed)
			(vias allowed)
			(pads allowed)
			(copperpour not_allowed)
			(footprints allowed)
		)
		(placement
			(enabled no)
			(sheetname "")
		)
		(fill yes
			(thermal_gap 0.5)
			(thermal_bridge_width 0.5)
			(island_removal_mode 0)
		)
		(polygon
			(pts
				(arc
					(start 45.10913 -228.971348)
					(mid 45.124009 -229.007269)
					(end 45.15993 -229.022148)
				)
				(arc
					(start 46.55947 -229.022148)
					(mid 46.595391 -229.007269)
					(end 46.61027 -228.971348)
				)
				(arc
					(start 46.61027 -228.562408)
					(mid 46.595391 -228.526487)
					(end 46.55947 -228.511608)
				)
				(arc
					(start 45.15993 -228.511608)
					(mid 45.124009 -228.526487)
					(end 45.10913 -228.562408)
				)
			)
		)
	)
	(zone
		(layers "In1.Cu" "In2.Cu")
		(hatch none 0.5)
		(connect_pads
			(clearance 0)
		)
		(min_thickness 0.25)
		(keepout
			(tracks not_allowed)
			(vias allowed)
			(pads allowed)
			(copperpour not_allowed)
			(footprints allowed)
		)
		(placement
			(enabled no)
			(sheetname "")
		)
		(fill yes
			(thermal_gap 0.5)
			(thermal_bridge_width 0.5)
			(island_removal_mode 0)
		)
		(polygon
			(pts
				(arc
					(start 180.69433 -280.821384)
					(mid 180.709209 -280.857305)
					(end 180.74513 -280.872184)
				)
				(arc
					(start 182.14467 -280.872184)
					(mid 182.180591 -280.857305)
					(end 182.19547 -280.821384)
				)
				(arc
					(start 182.19547 -280.412444)
					(mid 182.180591 -280.376523)
					(end 182.14467 -280.361644)
				)
				(arc
					(start 180.74513 -280.361644)
					(mid 180.709209 -280.376523)
					(end 180.69433 -280.412444)
				)
			)
		)
	)
	(zone
		(layers "In1.Cu" "In2.Cu")
		(hatch none 0.5)
		(connect_pads
			(clearance 0)
		)
		(min_thickness 0.25)
		(keepout
			(tracks not_allowed)
			(vias allowed)
			(pads allowed)
			(copperpour not_allowed)
			(footprints allowed)
		)
		(placement
			(enabled no)
			(sheetname "")
		)
		(fill yes
			(thermal_gap 0.5)
			(thermal_bridge_width 0.5)
			(island_removal_mode 0)
		)
		(polygon
			(pts
				(arc
					(start 60.19673 -296.121328)
					(mid 60.211609 -296.157249)
					(end 60.24753 -296.172128)
				)
				(arc
					(start 61.64707 -296.172128)
					(mid 61.682991 -296.157249)
					(end 61.69787 -296.121328)
				)
				(arc
					(start 61.69787 -295.712388)
					(mid 61.682991 -295.676467)
					(end 61.64707 -295.661588)
				)
				(arc
					(start 60.24753 -295.661588)
					(mid 60.211609 -295.676467)
					(end 60.19673 -295.712388)
				)
			)
		)
	)
	(zone
		(layers "In1.Cu" "In2.Cu")
		(hatch none 0.5)
		(connect_pads
			(clearance 0)
		)
		(min_thickness 0.25)
		(keepout
			(tracks not_allowed)
			(vias allowed)
			(pads allowed)
			(copperpour not_allowed)
			(footprints allowed)
		)
		(placement
			(enabled no)
			(sheetname "")
		)
		(fill yes
			(thermal_gap 0.5)
			(thermal_bridge_width 0.5)
			(island_removal_mode 0)
		)
		(polygon
			(pts
				(arc
					(start 60.19673 -202.621388)
					(mid 60.211609 -202.657309)
					(end 60.24753 -202.672188)
				)
				(arc
					(start 61.64707 -202.672188)
					(mid 61.682991 -202.657309)
					(end 61.69787 -202.621388)
				)
				(arc
					(start 61.69787 -202.212448)
					(mid 61.682991 -202.176527)
					(end 61.64707 -202.161648)
				)
				(arc
					(start 60.24753 -202.161648)
					(mid 60.211609 -202.176527)
					(end 60.19673 -202.212448)
				)
			)
		)
	)
	(zone
		(layers "In1.Cu" "In2.Cu")
		(hatch none 0.5)
		(connect_pads
			(clearance 0)
		)
		(min_thickness 0.25)
		(keepout
			(tracks not_allowed)
			(vias allowed)
			(pads allowed)
			(copperpour not_allowed)
			(footprints allowed)
		)
		(placement
			(enabled no)
			(sheetname "")
		)
		(fill yes
			(thermal_gap 0.5)
			(thermal_bridge_width 0.5)
			(island_removal_mode 0)
		)
		(polygon
			(pts
				(arc
					(start 210.86953 -252.771402)
					(mid 210.884409 -252.807323)
					(end 210.92033 -252.822202)
				)
				(arc
					(start 212.31987 -252.822202)
					(mid 212.355791 -252.807323)
					(end 212.37067 -252.771402)
				)
				(arc
					(start 212.37067 -252.362462)
					(mid 212.355791 -252.326541)
					(end 212.31987 -252.311662)
				)
				(arc
					(start 210.92033 -252.311662)
					(mid 210.884409 -252.326541)
					(end 210.86953 -252.362462)
				)
			)
		)
	)
	(zone
		(layers "In1.Cu" "In2.Cu")
		(hatch none 0.5)
		(connect_pads
			(clearance 0)
		)
		(min_thickness 0.25)
		(keepout
			(tracks not_allowed)
			(vias allowed)
			(pads allowed)
			(copperpour not_allowed)
			(footprints allowed)
		)
		(placement
			(enabled no)
			(sheetname "")
		)
		(fill yes
			(thermal_gap 0.5)
			(thermal_bridge_width 0.5)
			(island_removal_mode 0)
		)
		(polygon
			(pts
				(arc
					(start 297.149266 -236.62132)
					(mid 297.164145 -236.657241)
					(end 297.200066 -236.67212)
				)
				(arc
					(start 298.599606 -236.67212)
					(mid 298.635527 -236.657241)
					(end 298.650406 -236.62132)
				)
				(arc
					(start 298.650406 -236.21238)
					(mid 298.635527 -236.176459)
					(end 298.599606 -236.16158)
				)
				(arc
					(start 297.200066 -236.16158)
					(mid 297.164145 -236.176459)
					(end 297.149266 -236.21238)
				)
			)
		)
	)
	(zone
		(layers "In1.Cu" "In2.Cu")
		(hatch none 0.5)
		(connect_pads
			(clearance 0)
		)
		(min_thickness 0.25)
		(keepout
			(tracks not_allowed)
			(vias allowed)
			(pads allowed)
			(copperpour not_allowed)
			(footprints allowed)
		)
		(placement
			(enabled no)
			(sheetname "")
		)
		(fill yes
			(thermal_gap 0.5)
			(thermal_bridge_width 0.5)
			(island_removal_mode 0)
		)
		(polygon
			(pts
				(arc
					(start 270.417798 -297.82135)
					(mid 270.432677 -297.857271)
					(end 270.468598 -297.87215)
				)
				(arc
					(start 271.868138 -297.87215)
					(mid 271.904059 -297.857271)
					(end 271.918938 -297.82135)
				)
				(arc
					(start 271.918938 -297.41241)
					(mid 271.904059 -297.376489)
					(end 271.868138 -297.36161)
				)
				(arc
					(start 270.468598 -297.36161)
					(mid 270.432677 -297.376489)
					(end 270.417798 -297.41241)
				)
			)
		)
	)
	(zone
		(layers "In1.Cu" "In2.Cu")
		(hatch none 0.5)
		(connect_pads
			(clearance 0)
		)
		(min_thickness 0.25)
		(keepout
			(tracks not_allowed)
			(vias allowed)
			(pads allowed)
			(copperpour not_allowed)
			(footprints allowed)
		)
		(placement
			(enabled no)
			(sheetname "")
		)
		(fill yes
			(thermal_gap 0.5)
			(thermal_bridge_width 0.5)
			(island_removal_mode 0)
		)
		(polygon
			(pts
				(arc
					(start 458.809598 -290.171378)
					(mid 458.824477 -290.207299)
					(end 458.860398 -290.222178)
				)
				(arc
					(start 460.259938 -290.222178)
					(mid 460.295859 -290.207299)
					(end 460.310738 -290.171378)
				)
				(arc
					(start 460.310738 -289.762438)
					(mid 460.295859 -289.726517)
					(end 460.259938 -289.711638)
				)
				(arc
					(start 458.860398 -289.711638)
					(mid 458.824477 -289.726517)
					(end 458.809598 -289.762438)
				)
			)
		)
	)
	(zone
		(layers "In1.Cu" "In2.Cu")
		(hatch none 0.5)
		(connect_pads
			(clearance 0)
		)
		(min_thickness 0.25)
		(keepout
			(tracks not_allowed)
			(vias allowed)
			(pads allowed)
			(copperpour not_allowed)
			(footprints allowed)
		)
		(placement
			(enabled no)
			(sheetname "")
		)
		(fill yes
			(thermal_gap 0.5)
			(thermal_bridge_width 0.5)
			(island_removal_mode 0)
		)
		(polygon
			(pts
				(arc
					(start 297.149266 -216.22131)
					(mid 297.164145 -216.257231)
					(end 297.200066 -216.27211)
				)
				(arc
					(start 298.599606 -216.27211)
					(mid 298.635527 -216.257231)
					(end 298.650406 -216.22131)
				)
				(arc
					(start 298.650406 -215.81237)
					(mid 298.635527 -215.776449)
					(end 298.599606 -215.76157)
				)
				(arc
					(start 297.200066 -215.76157)
					(mid 297.164145 -215.776449)
					(end 297.149266 -215.81237)
				)
			)
		)
	)
	(zone
		(layers "In1.Cu" "In2.Cu")
		(hatch none 0.5)
		(connect_pads
			(clearance 0)
		)
		(min_thickness 0.25)
		(keepout
			(tracks not_allowed)
			(vias allowed)
			(pads allowed)
			(copperpour not_allowed)
			(footprints allowed)
		)
		(placement
			(enabled no)
			(sheetname "")
		)
		(fill yes
			(thermal_gap 0.5)
			(thermal_bridge_width 0.5)
			(island_removal_mode 0)
		)
		(polygon
			(pts
				(arc
					(start 192.338198 -284.221428)
					(mid 192.353077 -284.257349)
					(end 192.388998 -284.272228)
				)
				(arc
					(start 193.788538 -284.272228)
					(mid 193.824459 -284.257349)
					(end 193.839338 -284.221428)
				)
				(arc
					(start 193.839338 -283.812488)
					(mid 193.824459 -283.776567)
					(end 193.788538 -283.761688)
				)
				(arc
					(start 192.388998 -283.761688)
					(mid 192.353077 -283.776567)
					(end 192.338198 -283.812488)
				)
			)
		)
	)
	(zone
		(layers "In1.Cu" "In2.Cu")
		(hatch none 0.5)
		(connect_pads
			(clearance 0)
		)
		(min_thickness 0.25)
		(keepout
			(tracks not_allowed)
			(vias allowed)
			(pads allowed)
			(copperpour not_allowed)
			(footprints allowed)
		)
		(placement
			(enabled no)
			(sheetname "")
		)
		(fill yes
			(thermal_gap 0.5)
			(thermal_bridge_width 0.5)
			(island_removal_mode 0)
		)
		(polygon
			(pts
				(arc
					(start 436.178198 -196.671438)
					(mid 436.193077 -196.707359)
					(end 436.228998 -196.722238)
				)
				(arc
					(start 437.628538 -196.722238)
					(mid 437.664459 -196.707359)
					(end 437.679338 -196.671438)
				)
				(arc
					(start 437.679338 -196.262498)
					(mid 437.664459 -196.226577)
					(end 437.628538 -196.211698)
				)
				(arc
					(start 436.228998 -196.211698)
					(mid 436.193077 -196.226577)
					(end 436.178198 -196.262498)
				)
			)
		)
	)
	(zone
		(layers "In1.Cu" "In2.Cu")
		(hatch none 0.5)
		(connect_pads
			(clearance 0)
		)
		(min_thickness 0.25)
		(keepout
			(tracks not_allowed)
			(vias allowed)
			(pads allowed)
			(copperpour not_allowed)
			(footprints allowed)
		)
		(placement
			(enabled no)
			(sheetname "")
		)
		(fill yes
			(thermal_gap 0.5)
			(thermal_bridge_width 0.5)
			(island_removal_mode 0)
		)
		(polygon
			(pts
				(arc
					(start 169.706798 -276.571456)
					(mid 169.721677 -276.607377)
					(end 169.757598 -276.622256)
				)
				(arc
					(start 171.157138 -276.622256)
					(mid 171.193059 -276.607377)
					(end 171.207938 -276.571456)
				)
				(arc
					(start 171.207938 -276.162516)
					(mid 171.193059 -276.126595)
					(end 171.157138 -276.111716)
				)
				(arc
					(start 169.757598 -276.111716)
					(mid 169.721677 -276.126595)
					(end 169.706798 -276.162516)
				)
			)
		)
	)
	(zone
		(layers "In1.Cu" "In2.Cu")
		(hatch none 0.5)
		(connect_pads
			(clearance 0)
		)
		(min_thickness 0.25)
		(keepout
			(tracks not_allowed)
			(vias allowed)
			(pads allowed)
			(copperpour not_allowed)
			(footprints allowed)
		)
		(placement
			(enabled no)
			(sheetname "")
		)
		(fill yes
			(thermal_gap 0.5)
			(thermal_bridge_width 0.5)
			(island_removal_mode 0)
		)
		(polygon
			(pts
				(arc
					(start 165.60673 -294.421306)
					(mid 165.621609 -294.457227)
					(end 165.65753 -294.472106)
				)
				(arc
					(start 167.05707 -294.472106)
					(mid 167.092991 -294.457227)
					(end 167.10787 -294.421306)
				)
				(arc
					(start 167.10787 -294.012366)
					(mid 167.092991 -293.976445)
					(end 167.05707 -293.961566)
				)
				(arc
					(start 165.65753 -293.961566)
					(mid 165.621609 -293.976445)
					(end 165.60673 -294.012366)
				)
			)
		)
	)
	(zone
		(layers "In1.Cu" "In2.Cu")
		(hatch none 0.5)
		(connect_pads
			(clearance 0)
		)
		(min_thickness 0.25)
		(keepout
			(tracks not_allowed)
			(vias allowed)
			(pads allowed)
			(copperpour not_allowed)
			(footprints allowed)
		)
		(placement
			(enabled no)
			(sheetname "")
		)
		(fill yes
			(thermal_gap 0.5)
			(thermal_bridge_width 0.5)
			(island_removal_mode 0)
		)
		(polygon
			(pts
				(arc
					(start 64.296798 -203.471526)
					(mid 64.311677 -203.507447)
					(end 64.347598 -203.522326)
				)
				(arc
					(start 65.747138 -203.522326)
					(mid 65.783059 -203.507447)
					(end 65.797938 -203.471526)
				)
				(arc
					(start 65.797938 -203.062586)
					(mid 65.783059 -203.026665)
					(end 65.747138 -203.011786)
				)
				(arc
					(start 64.347598 -203.011786)
					(mid 64.311677 -203.026665)
					(end 64.296798 -203.062586)
				)
			)
		)
	)
	(zone
		(layers "In1.Cu" "In2.Cu")
		(hatch none 0.5)
		(connect_pads
			(clearance 0)
		)
		(min_thickness 0.25)
		(keepout
			(tracks not_allowed)
			(vias allowed)
			(pads allowed)
			(copperpour not_allowed)
			(footprints allowed)
		)
		(placement
			(enabled no)
			(sheetname "")
		)
		(fill yes
			(thermal_gap 0.5)
			(thermal_bridge_width 0.5)
			(island_removal_mode 0)
		)
		(polygon
			(pts
				(arc
					(start 11.490198 -268.921484)
					(mid 11.505077 -268.957405)
					(end 11.540998 -268.972284)
				)
				(arc
					(start 12.940538 -268.972284)
					(mid 12.976459 -268.957405)
					(end 12.991338 -268.921484)
				)
				(arc
					(start 12.991338 -268.512544)
					(mid 12.976459 -268.476623)
					(end 12.940538 -268.461744)
				)
				(arc
					(start 11.540998 -268.461744)
					(mid 11.505077 -268.476623)
					(end 11.490198 -268.512544)
				)
			)
		)
	)
	(zone
		(layers "In1.Cu" "In2.Cu")
		(hatch none 0.5)
		(connect_pads
			(clearance 0)
		)
		(min_thickness 0.25)
		(keepout
			(tracks not_allowed)
			(vias allowed)
			(pads allowed)
			(copperpour not_allowed)
			(footprints allowed)
		)
		(placement
			(enabled no)
			(sheetname "")
		)
		(fill yes
			(thermal_gap 0.5)
			(thermal_bridge_width 0.5)
			(island_removal_mode 0)
		)
		(polygon
			(pts
				(arc
					(start 7.39013 -279.121362)
					(mid 7.405009 -279.157283)
					(end 7.44093 -279.172162)
				)
				(arc
					(start 8.84047 -279.172162)
					(mid 8.876391 -279.157283)
					(end 8.89127 -279.121362)
				)
				(arc
					(start 8.89127 -278.712422)
					(mid 8.876391 -278.676501)
					(end 8.84047 -278.661622)
				)
				(arc
					(start 7.44093 -278.661622)
					(mid 7.405009 -278.676501)
					(end 7.39013 -278.712422)
				)
			)
		)
	)
	(zone
		(layers "In1.Cu" "In2.Cu")
		(hatch none 0.5)
		(connect_pads
			(clearance 0)
		)
		(min_thickness 0.25)
		(keepout
			(tracks not_allowed)
			(vias allowed)
			(pads allowed)
			(copperpour not_allowed)
			(footprints allowed)
		)
		(placement
			(enabled no)
			(sheetname "")
		)
		(fill yes
			(thermal_gap 0.5)
			(thermal_bridge_width 0.5)
			(island_removal_mode 0)
		)
		(polygon
			(pts
				(arc
					(start 22.47773 -234.071414)
					(mid 22.492609 -234.107335)
					(end 22.52853 -234.122214)
				)
				(arc
					(start 23.92807 -234.122214)
					(mid 23.963991 -234.107335)
					(end 23.97887 -234.071414)
				)
				(arc
					(start 23.97887 -233.662474)
					(mid 23.963991 -233.626553)
					(end 23.92807 -233.611674)
				)
				(arc
					(start 22.52853 -233.611674)
					(mid 22.492609 -233.626553)
					(end 22.47773 -233.662474)
				)
			)
		)
	)
	(zone
		(layers "In1.Cu" "In2.Cu")
		(hatch none 0.5)
		(connect_pads
			(clearance 0)
		)
		(min_thickness 0.25)
		(keepout
			(tracks not_allowed)
			(vias allowed)
			(pads allowed)
			(copperpour not_allowed)
			(footprints allowed)
		)
		(placement
			(enabled no)
			(sheetname "")
		)
		(fill yes
			(thermal_gap 0.5)
			(thermal_bridge_width 0.5)
			(island_removal_mode 0)
		)
		(polygon
			(pts
				(arc
					(start 180.69433 -218.77147)
					(mid 180.709209 -218.807391)
					(end 180.74513 -218.82227)
				)
				(arc
					(start 182.14467 -218.82227)
					(mid 182.180591 -218.807391)
					(end 182.19547 -218.77147)
				)
				(arc
					(start 182.19547 -218.36253)
					(mid 182.180591 -218.326609)
					(end 182.14467 -218.31173)
				)
				(arc
					(start 180.74513 -218.31173)
					(mid 180.709209 -218.326609)
					(end 180.69433 -218.36253)
				)
			)
		)
	)
	(zone
		(layers "In1.Cu" "In2.Cu")
		(hatch none 0.5)
		(connect_pads
			(clearance 0)
		)
		(min_thickness 0.25)
		(keepout
			(tracks not_allowed)
			(vias allowed)
			(pads allowed)
			(copperpour not_allowed)
			(footprints allowed)
		)
		(placement
			(enabled no)
			(sheetname "")
		)
		(fill yes
			(thermal_gap 0.5)
			(thermal_bridge_width 0.5)
			(island_removal_mode 0)
		)
		(polygon
			(pts
				(arc
					(start 428.634398 -210.27136)
					(mid 428.649277 -210.307281)
					(end 428.685198 -210.32216)
				)
				(arc
					(start 430.084738 -210.32216)
					(mid 430.120659 -210.307281)
					(end 430.135538 -210.27136)
				)
				(arc
					(start 430.135538 -209.86242)
					(mid 430.120659 -209.826499)
					(end 430.084738 -209.81162)
				)
				(arc
					(start 428.685198 -209.81162)
					(mid 428.649277 -209.826499)
					(end 428.634398 -209.86242)
				)
			)
		)
	)
	(zone
		(layers "In1.Cu" "In2.Cu")
		(hatch none 0.5)
		(connect_pads
			(clearance 0)
		)
		(min_thickness 0.25)
		(keepout
			(tracks not_allowed)
			(vias allowed)
			(pads allowed)
			(copperpour not_allowed)
			(footprints allowed)
		)
		(placement
			(enabled no)
			(sheetname "")
		)
		(fill yes
			(thermal_gap 0.5)
			(thermal_bridge_width 0.5)
			(island_removal_mode 0)
		)
		(polygon
			(pts
				(arc
					(start 173.15053 -232.371392)
					(mid 173.165409 -232.407313)
					(end 173.20133 -232.422192)
				)
				(arc
					(start 174.60087 -232.422192)
					(mid 174.636791 -232.407313)
					(end 174.65167 -232.371392)
				)
				(arc
					(start 174.65167 -231.962452)
					(mid 174.636791 -231.926531)
					(end 174.60087 -231.911652)
				)
				(arc
					(start 173.20133 -231.911652)
					(mid 173.165409 -231.926531)
					(end 173.15053 -231.962452)
				)
			)
		)
	)
	(zone
		(layers "In1.Cu" "In2.Cu")
		(hatch none 0.5)
		(connect_pads
			(clearance 0)
		)
		(min_thickness 0.25)
		(keepout
			(tracks not_allowed)
			(vias allowed)
			(pads allowed)
			(copperpour not_allowed)
			(footprints allowed)
		)
		(placement
			(enabled no)
			(sheetname "")
		)
		(fill yes
			(thermal_gap 0.5)
			(thermal_bridge_width 0.5)
			(island_removal_mode 0)
		)
		(polygon
			(pts
				(arc
					(start 255.330198 -211.971382)
					(mid 255.345077 -212.007303)
					(end 255.380998 -212.022182)
				)
				(arc
					(start 256.780538 -212.022182)
					(mid 256.816459 -212.007303)
					(end 256.831338 -211.971382)
				)
				(arc
					(start 256.831338 -211.562442)
					(mid 256.816459 -211.526521)
					(end 256.780538 -211.511642)
				)
				(arc
					(start 255.380998 -211.511642)
					(mid 255.345077 -211.526521)
					(end 255.330198 -211.562442)
				)
			)
		)
	)
	(zone
		(layers "In1.Cu" "In2.Cu")
		(hatch none 0.5)
		(connect_pads
			(clearance 0)
		)
		(min_thickness 0.25)
		(keepout
			(tracks not_allowed)
			(vias allowed)
			(pads allowed)
			(copperpour not_allowed)
			(footprints allowed)
		)
		(placement
			(enabled no)
			(sheetname "")
		)
		(fill yes
			(thermal_gap 0.5)
			(thermal_bridge_width 0.5)
			(island_removal_mode 0)
		)
		(polygon
			(pts
				(arc
					(start 158.06293 -316.521338)
					(mid 158.077809 -316.557259)
					(end 158.11373 -316.572138)
				)
				(arc
					(start 159.51327 -316.572138)
					(mid 159.549191 -316.557259)
					(end 159.56407 -316.521338)
				)
				(arc
					(start 159.56407 -316.112398)
					(mid 159.549191 -316.076477)
					(end 159.51327 -316.061598)
				)
				(arc
					(start 158.11373 -316.061598)
					(mid 158.077809 -316.076477)
					(end 158.06293 -316.112398)
				)
			)
		)
	)
	(zone
		(layers "In1.Cu" "In2.Cu")
		(hatch none 0.5)
		(connect_pads
			(clearance 0)
		)
		(min_thickness 0.25)
		(keepout
			(tracks not_allowed)
			(vias allowed)
			(pads allowed)
			(copperpour not_allowed)
			(footprints allowed)
		)
		(placement
			(enabled no)
			(sheetname "")
		)
		(fill yes
			(thermal_gap 0.5)
			(thermal_bridge_width 0.5)
			(island_removal_mode 0)
		)
		(polygon
			(pts
				(arc
					(start 52.65293 -223.021398)
					(mid 52.667809 -223.057319)
					(end 52.70373 -223.072198)
				)
				(arc
					(start 54.10327 -223.072198)
					(mid 54.139191 -223.057319)
					(end 54.15407 -223.021398)
				)
				(arc
					(start 54.15407 -222.612458)
					(mid 54.139191 -222.576537)
					(end 54.10327 -222.561658)
				)
				(arc
					(start 52.70373 -222.561658)
					(mid 52.667809 -222.576537)
					(end 52.65293 -222.612458)
				)
			)
		)
	)
	(zone
		(layers "In1.Cu" "In2.Cu")
		(hatch none 0.5)
		(connect_pads
			(clearance 0)
		)
		(min_thickness 0.25)
		(keepout
			(tracks not_allowed)
			(vias allowed)
			(pads allowed)
			(copperpour not_allowed)
			(footprints allowed)
		)
		(placement
			(enabled no)
			(sheetname "")
		)
		(fill yes
			(thermal_gap 0.5)
			(thermal_bridge_width 0.5)
			(island_removal_mode 0)
		)
		(polygon
			(pts
				(arc
					(start 274.517866 -278.271478)
					(mid 274.532745 -278.307399)
					(end 274.568666 -278.322278)
				)
				(arc
					(start 275.968206 -278.322278)
					(mid 276.004127 -278.307399)
					(end 276.019006 -278.271478)
				)
				(arc
					(start 276.019006 -277.862538)
					(mid 276.004127 -277.826617)
					(end 275.968206 -277.811738)
				)
				(arc
					(start 274.568666 -277.811738)
					(mid 274.532745 -277.826617)
					(end 274.517866 -277.862538)
				)
			)
		)
	)
	(zone
		(layers "In1.Cu" "In2.Cu")
		(hatch none 0.5)
		(connect_pads
			(clearance 0)
		)
		(min_thickness 0.25)
		(keepout
			(tracks not_allowed)
			(vias allowed)
			(pads allowed)
			(copperpour not_allowed)
			(footprints allowed)
		)
		(placement
			(enabled no)
			(sheetname "")
		)
		(fill yes
			(thermal_gap 0.5)
			(thermal_bridge_width 0.5)
			(island_removal_mode 0)
		)
		(polygon
			(pts
				(arc
					(start 255.330198 -291.8714)
					(mid 255.345077 -291.907321)
					(end 255.380998 -291.9222)
				)
				(arc
					(start 256.780538 -291.9222)
					(mid 256.816459 -291.907321)
					(end 256.831338 -291.8714)
				)
				(arc
					(start 256.831338 -291.46246)
					(mid 256.816459 -291.426539)
					(end 256.780538 -291.41166)
				)
				(arc
					(start 255.380998 -291.41166)
					(mid 255.345077 -291.426539)
					(end 255.330198 -291.46246)
				)
			)
		)
	)
	(zone
		(layers "In1.Cu" "In2.Cu")
		(hatch none 0.5)
		(connect_pads
			(clearance 0)
		)
		(min_thickness 0.25)
		(keepout
			(tracks not_allowed)
			(vias allowed)
			(pads allowed)
			(copperpour not_allowed)
			(footprints allowed)
		)
		(placement
			(enabled no)
			(sheetname "")
		)
		(fill yes
			(thermal_gap 0.5)
			(thermal_bridge_width 0.5)
			(island_removal_mode 0)
		)
		(polygon
			(pts
				(arc
					(start 436.178198 -290.171378)
					(mid 436.193077 -290.207299)
					(end 436.228998 -290.222178)
				)
				(arc
					(start 437.628538 -290.222178)
					(mid 437.664459 -290.207299)
					(end 437.679338 -290.171378)
				)
				(arc
					(start 437.679338 -289.762438)
					(mid 437.664459 -289.726517)
					(end 437.628538 -289.711638)
				)
				(arc
					(start 436.228998 -289.711638)
					(mid 436.193077 -289.726517)
					(end 436.178198 -289.762438)
				)
			)
		)
	)
	(zone
		(layers "In1.Cu" "In2.Cu")
		(hatch none 0.5)
		(connect_pads
			(clearance 0)
		)
		(min_thickness 0.25)
		(keepout
			(tracks not_allowed)
			(vias allowed)
			(pads allowed)
			(copperpour not_allowed)
			(footprints allowed)
		)
		(placement
			(enabled no)
			(sheetname "")
		)
		(fill yes
			(thermal_gap 0.5)
			(thermal_bridge_width 0.5)
			(island_removal_mode 0)
		)
		(polygon
			(pts
				(arc
					(start 26.577798 -222.171514)
					(mid 26.592677 -222.207435)
					(end 26.628598 -222.222314)
				)
				(arc
					(start 28.028138 -222.222314)
					(mid 28.064059 -222.207435)
					(end 28.078938 -222.171514)
				)
				(arc
					(start 28.078938 -221.762574)
					(mid 28.064059 -221.726653)
					(end 28.028138 -221.711774)
				)
				(arc
					(start 26.628598 -221.711774)
					(mid 26.592677 -221.726653)
					(end 26.577798 -221.762574)
				)
			)
		)
	)
	(zone
		(layers "In1.Cu" "In2.Cu")
		(hatch none 0.5)
		(connect_pads
			(clearance 0)
		)
		(min_thickness 0.25)
		(keepout
			(tracks not_allowed)
			(vias allowed)
			(pads allowed)
			(copperpour not_allowed)
			(footprints allowed)
		)
		(placement
			(enabled no)
			(sheetname "")
		)
		(fill yes
			(thermal_gap 0.5)
			(thermal_bridge_width 0.5)
			(island_removal_mode 0)
		)
		(polygon
			(pts
				(arc
					(start 455.365866 -199.221344)
					(mid 455.380745 -199.257265)
					(end 455.416666 -199.272144)
				)
				(arc
					(start 456.816206 -199.272144)
					(mid 456.852127 -199.257265)
					(end 456.867006 -199.221344)
				)
				(arc
					(start 456.867006 -198.812404)
					(mid 456.852127 -198.776483)
					(end 456.816206 -198.761604)
				)
				(arc
					(start 455.416666 -198.761604)
					(mid 455.380745 -198.776483)
					(end 455.365866 -198.812404)
				)
			)
		)
	)
	(zone
		(layers "In1.Cu" "In2.Cu")
		(hatch none 0.5)
		(connect_pads
			(clearance 0)
		)
		(min_thickness 0.25)
		(keepout
			(tracks not_allowed)
			(vias allowed)
			(pads allowed)
			(copperpour not_allowed)
			(footprints allowed)
		)
		(placement
			(enabled no)
			(sheetname "")
		)
		(fill yes
			(thermal_gap 0.5)
			(thermal_bridge_width 0.5)
			(island_removal_mode 0)
		)
		(polygon
			(pts
				(arc
					(start 19.033998 -304.621438)
					(mid 19.048877 -304.657359)
					(end 19.084798 -304.672238)
				)
				(arc
					(start 20.484338 -304.672238)
					(mid 20.520259 -304.657359)
					(end 20.535138 -304.621438)
				)
				(arc
					(start 20.535138 -304.212498)
					(mid 20.520259 -304.176577)
					(end 20.484338 -304.161698)
				)
				(arc
					(start 19.084798 -304.161698)
					(mid 19.048877 -304.176577)
					(end 19.033998 -304.212498)
				)
			)
		)
	)
	(zone
		(layers "In1.Cu" "In2.Cu")
		(hatch none 0.5)
		(connect_pads
			(clearance 0)
		)
		(min_thickness 0.25)
		(keepout
			(tracks not_allowed)
			(vias allowed)
			(pads allowed)
			(copperpour not_allowed)
			(footprints allowed)
		)
		(placement
			(enabled no)
			(sheetname "")
		)
		(fill yes
			(thermal_gap 0.5)
			(thermal_bridge_width 0.5)
			(island_removal_mode 0)
		)
		(polygon
			(pts
				(arc
					(start 285.505398 -251.07138)
					(mid 285.520277 -251.107301)
					(end 285.556198 -251.12218)
				)
				(arc
					(start 286.955738 -251.12218)
					(mid 286.991659 -251.107301)
					(end 287.006538 -251.07138)
				)
				(arc
					(start 287.006538 -250.66244)
					(mid 286.991659 -250.626519)
					(end 286.955738 -250.61164)
				)
				(arc
					(start 285.556198 -250.61164)
					(mid 285.520277 -250.626519)
					(end 285.505398 -250.66244)
				)
			)
		)
	)
	(zone
		(layers "In1.Cu" "In2.Cu")
		(hatch none 0.5)
		(connect_pads
			(clearance 0)
		)
		(min_thickness 0.25)
		(keepout
			(tracks not_allowed)
			(vias allowed)
			(pads allowed)
			(copperpour not_allowed)
			(footprints allowed)
		)
		(placement
			(enabled no)
			(sheetname "")
		)
		(fill yes
			(thermal_gap 0.5)
			(thermal_bridge_width 0.5)
			(island_removal_mode 0)
		)
		(polygon
			(pts
				(arc
					(start 195.78193 -314.821316)
					(mid 195.796809 -314.857237)
					(end 195.83273 -314.872116)
				)
				(arc
					(start 197.23227 -314.872116)
					(mid 197.268191 -314.857237)
					(end 197.28307 -314.821316)
				)
				(arc
					(start 197.28307 -314.412376)
					(mid 197.268191 -314.376455)
					(end 197.23227 -314.361576)
				)
				(arc
					(start 195.83273 -314.361576)
					(mid 195.796809 -314.376455)
					(end 195.78193 -314.412376)
				)
			)
		)
	)
	(zone
		(layers "In1.Cu" "In2.Cu")
		(hatch none 0.5)
		(connect_pads
			(clearance 0)
		)
		(min_thickness 0.25)
		(keepout
			(tracks not_allowed)
			(vias allowed)
			(pads allowed)
			(copperpour not_allowed)
			(footprints allowed)
		)
		(placement
			(enabled no)
			(sheetname "")
		)
		(fill yes
			(thermal_gap 0.5)
			(thermal_bridge_width 0.5)
			(island_removal_mode 0)
		)
		(polygon
			(pts
				(arc
					(start 195.78193 -266.371324)
					(mid 195.796809 -266.407245)
					(end 195.83273 -266.422124)
				)
				(arc
					(start 197.23227 -266.422124)
					(mid 197.268191 -266.407245)
					(end 197.28307 -266.371324)
				)
				(arc
					(start 197.28307 -265.962384)
					(mid 197.268191 -265.926463)
					(end 197.23227 -265.911584)
				)
				(arc
					(start 195.83273 -265.911584)
					(mid 195.796809 -265.926463)
					(end 195.78193 -265.962384)
				)
			)
		)
	)
	(zone
		(layers "In1.Cu" "In2.Cu")
		(hatch none 0.5)
		(connect_pads
			(clearance 0)
		)
		(min_thickness 0.25)
		(keepout
			(tracks not_allowed)
			(vias allowed)
			(pads allowed)
			(copperpour not_allowed)
			(footprints allowed)
		)
		(placement
			(enabled no)
			(sheetname "")
		)
		(fill yes
			(thermal_gap 0.5)
			(thermal_bridge_width 0.5)
			(island_removal_mode 0)
		)
		(polygon
			(pts
				(arc
					(start 293.049198 -266.371324)
					(mid 293.064077 -266.407245)
					(end 293.099998 -266.422124)
				)
				(arc
					(start 294.499538 -266.422124)
					(mid 294.535459 -266.407245)
					(end 294.550338 -266.371324)
				)
				(arc
					(start 294.550338 -265.962384)
					(mid 294.535459 -265.926463)
					(end 294.499538 -265.911584)
				)
				(arc
					(start 293.099998 -265.911584)
					(mid 293.064077 -265.926463)
					(end 293.049198 -265.962384)
				)
			)
		)
	)
	(zone
		(layers "In1.Cu" "In2.Cu")
		(hatch none 0.5)
		(connect_pads
			(clearance 0)
		)
		(min_thickness 0.25)
		(keepout
			(tracks not_allowed)
			(vias allowed)
			(pads allowed)
			(copperpour not_allowed)
			(footprints allowed)
		)
		(placement
			(enabled no)
			(sheetname "")
		)
		(fill yes
			(thermal_gap 0.5)
			(thermal_bridge_width 0.5)
			(island_removal_mode 0)
		)
		(polygon
			(pts
				(arc
					(start 11.490198 -212.82152)
					(mid 11.505077 -212.857441)
					(end 11.540998 -212.87232)
				)
				(arc
					(start 12.940538 -212.87232)
					(mid 12.976459 -212.857441)
					(end 12.991338 -212.82152)
				)
				(arc
					(start 12.991338 -212.41258)
					(mid 12.976459 -212.376659)
					(end 12.940538 -212.36178)
				)
				(arc
					(start 11.540998 -212.36178)
					(mid 11.505077 -212.376659)
					(end 11.490198 -212.41258)
				)
			)
		)
	)
	(zone
		(layers "In1.Cu" "In2.Cu")
		(hatch none 0.5)
		(connect_pads
			(clearance 0)
		)
		(min_thickness 0.25)
		(keepout
			(tracks not_allowed)
			(vias allowed)
			(pads allowed)
			(copperpour not_allowed)
			(footprints allowed)
		)
		(placement
			(enabled no)
			(sheetname "")
		)
		(fill yes
			(thermal_gap 0.5)
			(thermal_bridge_width 0.5)
			(island_removal_mode 0)
		)
		(polygon
			(pts
				(arc
					(start 289.605466 -222.171514)
					(mid 289.620345 -222.207435)
					(end 289.656266 -222.222314)
				)
				(arc
					(start 291.055806 -222.222314)
					(mid 291.091727 -222.207435)
					(end 291.106606 -222.171514)
				)
				(arc
					(start 291.106606 -221.762574)
					(mid 291.091727 -221.726653)
					(end 291.055806 -221.711774)
				)
				(arc
					(start 289.656266 -221.711774)
					(mid 289.620345 -221.726653)
					(end 289.605466 -221.762574)
				)
			)
		)
	)
	(zone
		(layers "In1.Cu" "In2.Cu")
		(hatch none 0.5)
		(connect_pads
			(clearance 0)
		)
		(min_thickness 0.25)
		(keepout
			(tracks not_allowed)
			(vias allowed)
			(pads allowed)
			(copperpour not_allowed)
			(footprints allowed)
		)
		(placement
			(enabled no)
			(sheetname "")
		)
		(fill yes
			(thermal_gap 0.5)
			(thermal_bridge_width 0.5)
			(island_removal_mode 0)
		)
		(polygon
			(pts
				(arc
					(start 14.93393 -297.82135)
					(mid 14.948809 -297.857271)
					(end 14.98473 -297.87215)
				)
				(arc
					(start 16.38427 -297.87215)
					(mid 16.420191 -297.857271)
					(end 16.43507 -297.82135)
				)
				(arc
					(start 16.43507 -297.41241)
					(mid 16.420191 -297.376489)
					(end 16.38427 -297.36161)
				)
				(arc
					(start 14.98473 -297.36161)
					(mid 14.948809 -297.376489)
					(end 14.93393 -297.41241)
				)
			)
		)
	)
	(zone
		(layers "In1.Cu" "In2.Cu")
		(hatch none 0.5)
		(connect_pads
			(clearance 0)
		)
		(min_thickness 0.25)
		(keepout
			(tracks not_allowed)
			(vias allowed)
			(pads allowed)
			(copperpour not_allowed)
			(footprints allowed)
		)
		(placement
			(enabled no)
			(sheetname "")
		)
		(fill yes
			(thermal_gap 0.5)
			(thermal_bridge_width 0.5)
			(island_removal_mode 0)
		)
		(polygon
			(pts
				(arc
					(start 270.417798 -210.27136)
					(mid 270.432677 -210.307281)
					(end 270.468598 -210.32216)
				)
				(arc
					(start 271.868138 -210.32216)
					(mid 271.904059 -210.307281)
					(end 271.918938 -210.27136)
				)
				(arc
					(start 271.918938 -209.86242)
					(mid 271.904059 -209.826499)
					(end 271.868138 -209.81162)
				)
				(arc
					(start 270.468598 -209.81162)
					(mid 270.432677 -209.826499)
					(end 270.417798 -209.86242)
				)
			)
		)
	)
	(zone
		(layers "In1.Cu" "In2.Cu")
		(hatch none 0.5)
		(connect_pads
			(clearance 0)
		)
		(min_thickness 0.25)
		(keepout
			(tracks not_allowed)
			(vias allowed)
			(pads allowed)
			(copperpour not_allowed)
			(footprints allowed)
		)
		(placement
			(enabled no)
			(sheetname "")
		)
		(fill yes
			(thermal_gap 0.5)
			(thermal_bridge_width 0.5)
			(island_removal_mode 0)
		)
		(polygon
			(pts
				(arc
					(start 177.250598 -220.471492)
					(mid 177.265477 -220.507413)
					(end 177.301398 -220.522292)
				)
				(arc
					(start 178.700938 -220.522292)
					(mid 178.736859 -220.507413)
					(end 178.751738 -220.471492)
				)
				(arc
					(start 178.751738 -220.062552)
					(mid 178.736859 -220.026631)
					(end 178.700938 -220.011752)
				)
				(arc
					(start 177.301398 -220.011752)
					(mid 177.265477 -220.026631)
					(end 177.250598 -220.062552)
				)
			)
		)
	)
	(zone
		(layers "In1.Cu" "In2.Cu")
		(hatch none 0.5)
		(connect_pads
			(clearance 0)
		)
		(min_thickness 0.25)
		(keepout
			(tracks not_allowed)
			(vias allowed)
			(pads allowed)
			(copperpour not_allowed)
			(footprints allowed)
		)
		(placement
			(enabled no)
			(sheetname "")
		)
		(fill yes
			(thermal_gap 0.5)
			(thermal_bridge_width 0.5)
			(island_removal_mode 0)
		)
		(polygon
			(pts
				(arc
					(start 262.873998 -284.221428)
					(mid 262.888877 -284.257349)
					(end 262.924798 -284.272228)
				)
				(arc
					(start 264.324338 -284.272228)
					(mid 264.360259 -284.257349)
					(end 264.375138 -284.221428)
				)
				(arc
					(start 264.375138 -283.812488)
					(mid 264.360259 -283.776567)
					(end 264.324338 -283.761688)
				)
				(arc
					(start 262.924798 -283.761688)
					(mid 262.888877 -283.776567)
					(end 262.873998 -283.812488)
				)
			)
		)
	)
	(zone
		(layers "In1.Cu" "In2.Cu")
		(hatch none 0.5)
		(connect_pads
			(clearance 0)
		)
		(min_thickness 0.25)
		(keepout
			(tracks not_allowed)
			(vias allowed)
			(pads allowed)
			(copperpour not_allowed)
			(footprints allowed)
		)
		(placement
			(enabled no)
			(sheetname "")
		)
		(fill yes
			(thermal_gap 0.5)
			(thermal_bridge_width 0.5)
			(island_removal_mode 0)
		)
		(polygon
			(pts
				(arc
					(start 214.969598 -278.271478)
					(mid 214.984477 -278.307399)
					(end 215.020398 -278.322278)
				)
				(arc
					(start 216.419938 -278.322278)
					(mid 216.455859 -278.307399)
					(end 216.470738 -278.271478)
				)
				(arc
					(start 216.470738 -277.862538)
					(mid 216.455859 -277.826617)
					(end 216.419938 -277.811738)
				)
				(arc
					(start 215.020398 -277.811738)
					(mid 214.984477 -277.826617)
					(end 214.969598 -277.862538)
				)
			)
		)
	)
	(zone
		(layers "In1.Cu" "In2.Cu")
		(hatch none 0.5)
		(connect_pads
			(clearance 0)
		)
		(min_thickness 0.25)
		(keepout
			(tracks not_allowed)
			(vias allowed)
			(pads allowed)
			(copperpour not_allowed)
			(footprints allowed)
		)
		(placement
			(enabled no)
			(sheetname "")
		)
		(fill yes
			(thermal_gap 0.5)
			(thermal_bridge_width 0.5)
			(island_removal_mode 0)
		)
		(polygon
			(pts
				(arc
					(start 49.209198 -251.921518)
					(mid 49.224077 -251.957439)
					(end 49.259998 -251.972318)
				)
				(arc
					(start 50.659538 -251.972318)
					(mid 50.695459 -251.957439)
					(end 50.710338 -251.921518)
				)
				(arc
					(start 50.710338 -251.512578)
					(mid 50.695459 -251.476657)
					(end 50.659538 -251.461778)
				)
				(arc
					(start 49.259998 -251.461778)
					(mid 49.224077 -251.476657)
					(end 49.209198 -251.512578)
				)
			)
		)
	)
	(zone
		(layers "In1.Cu" "In2.Cu")
		(hatch none 0.5)
		(connect_pads
			(clearance 0)
		)
		(min_thickness 0.25)
		(keepout
			(tracks not_allowed)
			(vias allowed)
			(pads allowed)
			(copperpour not_allowed)
			(footprints allowed)
		)
		(placement
			(enabled no)
			(sheetname "")
		)
		(fill yes
			(thermal_gap 0.5)
			(thermal_bridge_width 0.5)
			(island_removal_mode 0)
		)
		(polygon
			(pts
				(arc
					(start 203.32573 -269.771368)
					(mid 203.340609 -269.807289)
					(end 203.37653 -269.822168)
				)
				(arc
					(start 204.77607 -269.822168)
					(mid 204.811991 -269.807289)
					(end 204.82687 -269.771368)
				)
				(arc
					(start 204.82687 -269.362428)
					(mid 204.811991 -269.326507)
					(end 204.77607 -269.311628)
				)
				(arc
					(start 203.37653 -269.311628)
					(mid 203.340609 -269.326507)
					(end 203.32573 -269.362428)
				)
			)
		)
	)
	(zone
		(layers "In1.Cu" "In2.Cu")
		(hatch none 0.5)
		(connect_pads
			(clearance 0)
		)
		(min_thickness 0.25)
		(keepout
			(tracks not_allowed)
			(vias allowed)
			(pads allowed)
			(copperpour not_allowed)
			(footprints allowed)
		)
		(placement
			(enabled no)
			(sheetname "")
		)
		(fill yes
			(thermal_gap 0.5)
			(thermal_bridge_width 0.5)
			(island_removal_mode 0)
		)
		(polygon
			(pts
				(arc
					(start 210.86953 -238.321342)
					(mid 210.884409 -238.357263)
					(end 210.92033 -238.372142)
				)
				(arc
					(start 212.31987 -238.372142)
					(mid 212.355791 -238.357263)
					(end 212.37067 -238.321342)
				)
				(arc
					(start 212.37067 -237.912402)
					(mid 212.355791 -237.876481)
					(end 212.31987 -237.861602)
				)
				(arc
					(start 210.92033 -237.861602)
					(mid 210.884409 -237.876481)
					(end 210.86953 -237.912402)
				)
			)
		)
	)
	(zone
		(layers "In1.Cu" "In2.Cu")
		(hatch none 0.5)
		(connect_pads
			(clearance 0)
		)
		(min_thickness 0.25)
		(keepout
			(tracks not_allowed)
			(vias allowed)
			(pads allowed)
			(copperpour not_allowed)
			(footprints allowed)
		)
		(placement
			(enabled no)
			(sheetname "")
		)
		(fill yes
			(thermal_gap 0.5)
			(thermal_bridge_width 0.5)
			(island_removal_mode 0)
		)
		(polygon
			(pts
				(arc
					(start 192.338198 -304.621438)
					(mid 192.353077 -304.657359)
					(end 192.388998 -304.672238)
				)
				(arc
					(start 193.788538 -304.672238)
					(mid 193.824459 -304.657359)
					(end 193.839338 -304.621438)
				)
				(arc
					(start 193.839338 -304.212498)
					(mid 193.824459 -304.176577)
					(end 193.788538 -304.161698)
				)
				(arc
					(start 192.388998 -304.161698)
					(mid 192.353077 -304.176577)
					(end 192.338198 -304.212498)
				)
			)
		)
	)
	(zone
		(layers "In1.Cu" "In2.Cu")
		(hatch none 0.5)
		(connect_pads
			(clearance 0)
		)
		(min_thickness 0.25)
		(keepout
			(tracks not_allowed)
			(vias allowed)
			(pads allowed)
			(copperpour not_allowed)
			(footprints allowed)
		)
		(placement
			(enabled no)
			(sheetname "")
		)
		(fill yes
			(thermal_gap 0.5)
			(thermal_bridge_width 0.5)
			(island_removal_mode 0)
		)
		(polygon
			(pts
				(arc
					(start 195.78193 -211.971382)
					(mid 195.796809 -212.007303)
					(end 195.83273 -212.022182)
				)
				(arc
					(start 197.23227 -212.022182)
					(mid 197.268191 -212.007303)
					(end 197.28307 -211.971382)
				)
				(arc
					(start 197.28307 -211.562442)
					(mid 197.268191 -211.526521)
					(end 197.23227 -211.511642)
				)
				(arc
					(start 195.83273 -211.511642)
					(mid 195.796809 -211.526521)
					(end 195.78193 -211.562442)
				)
			)
		)
	)
	(zone
		(layers "In1.Cu" "In2.Cu")
		(hatch none 0.5)
		(connect_pads
			(clearance 0)
		)
		(min_thickness 0.25)
		(keepout
			(tracks not_allowed)
			(vias allowed)
			(pads allowed)
			(copperpour not_allowed)
			(footprints allowed)
		)
		(placement
			(enabled no)
			(sheetname "")
		)
		(fill yes
			(thermal_gap 0.5)
			(thermal_bridge_width 0.5)
			(island_removal_mode 0)
		)
		(polygon
			(pts
				(arc
					(start 440.278266 -313.971432)
					(mid 440.293145 -314.007353)
					(end 440.329066 -314.022232)
				)
				(arc
					(start 441.728606 -314.022232)
					(mid 441.764527 -314.007353)
					(end 441.779406 -313.971432)
				)
				(arc
					(start 441.779406 -313.562492)
					(mid 441.764527 -313.526571)
					(end 441.728606 -313.511692)
				)
				(arc
					(start 440.329066 -313.511692)
					(mid 440.293145 -313.526571)
					(end 440.278266 -313.562492)
				)
			)
		)
	)
	(zone
		(layers "In1.Cu" "In2.Cu")
		(hatch none 0.5)
		(connect_pads
			(clearance 0)
		)
		(min_thickness 0.25)
		(keepout
			(tracks not_allowed)
			(vias allowed)
			(pads allowed)
			(copperpour not_allowed)
			(footprints allowed)
		)
		(placement
			(enabled no)
			(sheetname "")
		)
		(fill yes
			(thermal_gap 0.5)
			(thermal_bridge_width 0.5)
			(island_removal_mode 0)
		)
		(polygon
			(pts
				(arc
					(start 207.425798 -274.02155)
					(mid 207.440677 -274.057471)
					(end 207.476598 -274.07235)
				)
				(arc
					(start 208.876138 -274.07235)
					(mid 208.912059 -274.057471)
					(end 208.926938 -274.02155)
				)
				(arc
					(start 208.926938 -273.61261)
					(mid 208.912059 -273.576689)
					(end 208.876138 -273.56181)
				)
				(arc
					(start 207.476598 -273.56181)
					(mid 207.440677 -273.576689)
					(end 207.425798 -273.61261)
				)
			)
		)
	)
	(zone
		(layers "In1.Cu" "In2.Cu")
		(hatch none 0.5)
		(connect_pads
			(clearance 0)
		)
		(min_thickness 0.25)
		(keepout
			(tracks not_allowed)
			(vias allowed)
			(pads allowed)
			(copperpour not_allowed)
			(footprints allowed)
		)
		(placement
			(enabled no)
			(sheetname "")
		)
		(fill yes
			(thermal_gap 0.5)
			(thermal_bridge_width 0.5)
			(island_removal_mode 0)
		)
		(polygon
			(pts
				(arc
					(start 440.278266 -272.321528)
					(mid 440.293145 -272.357449)
					(end 440.329066 -272.372328)
				)
				(arc
					(start 441.728606 -272.372328)
					(mid 441.764527 -272.357449)
					(end 441.779406 -272.321528)
				)
				(arc
					(start 441.779406 -271.912588)
					(mid 441.764527 -271.876667)
					(end 441.728606 -271.861788)
				)
				(arc
					(start 440.329066 -271.861788)
					(mid 440.293145 -271.876667)
					(end 440.278266 -271.912588)
				)
			)
		)
	)
	(zone
		(layers "In1.Cu" "In2.Cu")
		(hatch none 0.5)
		(connect_pads
			(clearance 0)
		)
		(min_thickness 0.25)
		(keepout
			(tracks not_allowed)
			(vias allowed)
			(pads allowed)
			(copperpour not_allowed)
			(footprints allowed)
		)
		(placement
			(enabled no)
			(sheetname "")
		)
		(fill yes
			(thermal_gap 0.5)
			(thermal_bridge_width 0.5)
			(island_removal_mode 0)
		)
		(polygon
			(pts
				(arc
					(start 19.033998 -203.471526)
					(mid 19.048877 -203.507447)
					(end 19.084798 -203.522326)
				)
				(arc
					(start 20.484338 -203.522326)
					(mid 20.520259 -203.507447)
					(end 20.535138 -203.471526)
				)
				(arc
					(start 20.535138 -203.062586)
					(mid 20.520259 -203.026665)
					(end 20.484338 -203.011786)
				)
				(arc
					(start 19.084798 -203.011786)
					(mid 19.048877 -203.026665)
					(end 19.033998 -203.062586)
				)
			)
		)
	)
	(zone
		(layers "In1.Cu" "In2.Cu")
		(hatch none 0.5)
		(connect_pads
			(clearance 0)
		)
		(min_thickness 0.25)
		(keepout
			(tracks not_allowed)
			(vias allowed)
			(pads allowed)
			(copperpour not_allowed)
			(footprints allowed)
		)
		(placement
			(enabled no)
			(sheetname "")
		)
		(fill yes
			(thermal_gap 0.5)
			(thermal_bridge_width 0.5)
			(island_removal_mode 0)
		)
		(polygon
			(pts
				(arc
					(start 195.78193 -275.721318)
					(mid 195.796809 -275.757239)
					(end 195.83273 -275.772118)
				)
				(arc
					(start 197.23227 -275.772118)
					(mid 197.268191 -275.757239)
					(end 197.28307 -275.721318)
				)
				(arc
					(start 197.28307 -275.312378)
					(mid 197.268191 -275.276457)
					(end 197.23227 -275.261578)
				)
				(arc
					(start 195.83273 -275.261578)
					(mid 195.796809 -275.276457)
					(end 195.78193 -275.312378)
				)
			)
		)
	)
	(zone
		(layers "In1.Cu" "In2.Cu")
		(hatch none 0.5)
		(connect_pads
			(clearance 0)
		)
		(min_thickness 0.25)
		(keepout
			(tracks not_allowed)
			(vias allowed)
			(pads allowed)
			(copperpour not_allowed)
			(footprints allowed)
		)
		(placement
			(enabled no)
			(sheetname "")
		)
		(fill yes
			(thermal_gap 0.5)
			(thermal_bridge_width 0.5)
			(island_removal_mode 0)
		)
		(polygon
			(pts
				(arc
					(start 259.430266 -199.221344)
					(mid 259.445145 -199.257265)
					(end 259.481066 -199.272144)
				)
				(arc
					(start 260.880606 -199.272144)
					(mid 260.916527 -199.257265)
					(end 260.931406 -199.221344)
				)
				(arc
					(start 260.931406 -198.812404)
					(mid 260.916527 -198.776483)
					(end 260.880606 -198.761604)
				)
				(arc
					(start 259.481066 -198.761604)
					(mid 259.445145 -198.776483)
					(end 259.430266 -198.812404)
				)
			)
		)
	)
	(zone
		(layers "In1.Cu" "In2.Cu")
		(hatch none 0.5)
		(connect_pads
			(clearance 0)
		)
		(min_thickness 0.25)
		(keepout
			(tracks not_allowed)
			(vias allowed)
			(pads allowed)
			(copperpour not_allowed)
			(footprints allowed)
		)
		(placement
			(enabled no)
			(sheetname "")
		)
		(fill yes
			(thermal_gap 0.5)
			(thermal_bridge_width 0.5)
			(island_removal_mode 0)
		)
		(polygon
			(pts
				(arc
					(start 308.136798 -224.72142)
					(mid 308.151677 -224.757341)
					(end 308.187598 -224.77222)
				)
				(arc
					(start 309.587138 -224.77222)
					(mid 309.623059 -224.757341)
					(end 309.637938 -224.72142)
				)
				(arc
					(start 309.637938 -224.31248)
					(mid 309.623059 -224.276559)
					(end 309.587138 -224.26168)
				)
				(arc
					(start 308.187598 -224.26168)
					(mid 308.151677 -224.276559)
					(end 308.136798 -224.31248)
				)
			)
		)
	)
	(zone
		(layers "In1.Cu" "In2.Cu")
		(hatch none 0.5)
		(connect_pads
			(clearance 0)
		)
		(min_thickness 0.25)
		(keepout
			(tracks not_allowed)
			(vias allowed)
			(pads allowed)
			(copperpour not_allowed)
			(footprints allowed)
		)
		(placement
			(enabled no)
			(sheetname "")
		)
		(fill yes
			(thermal_gap 0.5)
			(thermal_bridge_width 0.5)
			(island_removal_mode 0)
		)
		(polygon
			(pts
				(arc
					(start 177.250598 -217.921332)
					(mid 177.265477 -217.957253)
					(end 177.301398 -217.972132)
				)
				(arc
					(start 178.700938 -217.972132)
					(mid 178.736859 -217.957253)
					(end 178.751738 -217.921332)
				)
				(arc
					(start 178.751738 -217.512392)
					(mid 178.736859 -217.476471)
					(end 178.700938 -217.461592)
				)
				(arc
					(start 177.301398 -217.461592)
					(mid 177.265477 -217.476471)
					(end 177.250598 -217.512392)
				)
			)
		)
	)
	(zone
		(layers "In1.Cu" "In2.Cu")
		(hatch none 0.5)
		(connect_pads
			(clearance 0)
		)
		(min_thickness 0.25)
		(keepout
			(tracks not_allowed)
			(vias allowed)
			(pads allowed)
			(copperpour not_allowed)
			(footprints allowed)
		)
		(placement
			(enabled no)
			(sheetname "")
		)
		(fill yes
			(thermal_gap 0.5)
			(thermal_bridge_width 0.5)
			(island_removal_mode 0)
		)
		(polygon
			(pts
				(arc
					(start 45.10913 -305.471322)
					(mid 45.124009 -305.507243)
					(end 45.15993 -305.522122)
				)
				(arc
					(start 46.55947 -305.522122)
					(mid 46.595391 -305.507243)
					(end 46.61027 -305.471322)
				)
				(arc
					(start 46.61027 -305.062382)
					(mid 46.595391 -305.026461)
					(end 46.55947 -305.011582)
				)
				(arc
					(start 45.15993 -305.011582)
					(mid 45.124009 -305.026461)
					(end 45.10913 -305.062382)
				)
			)
		)
	)
	(zone
		(layers "In1.Cu" "In2.Cu")
		(hatch none 0.5)
		(connect_pads
			(clearance 0)
		)
		(min_thickness 0.25)
		(keepout
			(tracks not_allowed)
			(vias allowed)
			(pads allowed)
			(copperpour not_allowed)
			(footprints allowed)
		)
		(placement
			(enabled no)
			(sheetname "")
		)
		(fill yes
			(thermal_gap 0.5)
			(thermal_bridge_width 0.5)
			(island_removal_mode 0)
		)
		(polygon
			(pts
				(arc
					(start 289.605466 -276.571456)
					(mid 289.620345 -276.607377)
					(end 289.656266 -276.622256)
				)
				(arc
					(start 291.055806 -276.622256)
					(mid 291.091727 -276.607377)
					(end 291.106606 -276.571456)
				)
				(arc
					(start 291.106606 -276.162516)
					(mid 291.091727 -276.126595)
					(end 291.055806 -276.111716)
				)
				(arc
					(start 289.656266 -276.111716)
					(mid 289.620345 -276.126595)
					(end 289.605466 -276.162516)
				)
			)
		)
	)
	(zone
		(layers "In1.Cu" "In2.Cu")
		(hatch none 0.5)
		(connect_pads
			(clearance 0)
		)
		(min_thickness 0.25)
		(keepout
			(tracks not_allowed)
			(vias allowed)
			(pads allowed)
			(copperpour not_allowed)
			(footprints allowed)
		)
		(placement
			(enabled no)
			(sheetname "")
		)
		(fill yes
			(thermal_gap 0.5)
			(thermal_bridge_width 0.5)
			(island_removal_mode 0)
		)
		(polygon
			(pts
				(arc
					(start 173.15053 -228.121464)
					(mid 173.165409 -228.157385)
					(end 173.20133 -228.172264)
				)
				(arc
					(start 174.60087 -228.172264)
					(mid 174.636791 -228.157385)
					(end 174.65167 -228.121464)
				)
				(arc
					(start 174.65167 -227.712524)
					(mid 174.636791 -227.676603)
					(end 174.60087 -227.661724)
				)
				(arc
					(start 173.20133 -227.661724)
					(mid 173.165409 -227.676603)
					(end 173.15053 -227.712524)
				)
			)
		)
	)
	(zone
		(layers "In1.Cu" "In2.Cu")
		(hatch none 0.5)
		(connect_pads
			(clearance 0)
		)
		(min_thickness 0.25)
		(keepout
			(tracks not_allowed)
			(vias allowed)
			(pads allowed)
			(copperpour not_allowed)
			(footprints allowed)
		)
		(placement
			(enabled no)
			(sheetname "")
		)
		(fill yes
			(thermal_gap 0.5)
			(thermal_bridge_width 0.5)
			(island_removal_mode 0)
		)
		(polygon
			(pts
				(arc
					(start 19.033998 -287.621472)
					(mid 19.048877 -287.657393)
					(end 19.084798 -287.672272)
				)
				(arc
					(start 20.484338 -287.672272)
					(mid 20.520259 -287.657393)
					(end 20.535138 -287.621472)
				)
				(arc
					(start 20.535138 -287.212532)
					(mid 20.520259 -287.176611)
					(end 20.484338 -287.161732)
				)
				(arc
					(start 19.084798 -287.161732)
					(mid 19.048877 -287.176611)
					(end 19.033998 -287.212532)
				)
			)
		)
	)
	(zone
		(layers "In1.Cu" "In2.Cu")
		(hatch none 0.5)
		(connect_pads
			(clearance 0)
		)
		(min_thickness 0.25)
		(keepout
			(tracks not_allowed)
			(vias allowed)
			(pads allowed)
			(copperpour not_allowed)
			(footprints allowed)
		)
		(placement
			(enabled no)
			(sheetname "")
		)
		(fill yes
			(thermal_gap 0.5)
			(thermal_bridge_width 0.5)
			(island_removal_mode 0)
		)
		(polygon
			(pts
				(arc
					(start 277.961598 -296.121328)
					(mid 277.976477 -296.157249)
					(end 278.012398 -296.172128)
				)
				(arc
					(start 279.411938 -296.172128)
					(mid 279.447859 -296.157249)
					(end 279.462738 -296.121328)
				)
				(arc
					(start 279.462738 -295.712388)
					(mid 279.447859 -295.676467)
					(end 279.411938 -295.661588)
				)
				(arc
					(start 278.012398 -295.661588)
					(mid 277.976477 -295.676467)
					(end 277.961598 -295.712388)
				)
			)
		)
	)
	(zone
		(layers "In1.Cu" "In2.Cu")
		(hatch none 0.5)
		(connect_pads
			(clearance 0)
		)
		(min_thickness 0.25)
		(keepout
			(tracks not_allowed)
			(vias allowed)
			(pads allowed)
			(copperpour not_allowed)
			(footprints allowed)
		)
		(placement
			(enabled no)
			(sheetname "")
		)
		(fill yes
			(thermal_gap 0.5)
			(thermal_bridge_width 0.5)
			(island_removal_mode 0)
		)
		(polygon
			(pts
				(arc
					(start 440.278266 -315.671454)
					(mid 440.293145 -315.707375)
					(end 440.329066 -315.722254)
				)
				(arc
					(start 441.728606 -315.722254)
					(mid 441.764527 -315.707375)
					(end 441.779406 -315.671454)
				)
				(arc
					(start 441.779406 -315.262514)
					(mid 441.764527 -315.226593)
					(end 441.728606 -315.211714)
				)
				(arc
					(start 440.329066 -315.211714)
					(mid 440.293145 -315.226593)
					(end 440.278266 -315.262514)
				)
			)
		)
	)
	(zone
		(layers "In1.Cu" "In2.Cu")
		(hatch none 0.5)
		(connect_pads
			(clearance 0)
		)
		(min_thickness 0.25)
		(keepout
			(tracks not_allowed)
			(vias allowed)
			(pads allowed)
			(copperpour not_allowed)
			(footprints allowed)
		)
		(placement
			(enabled no)
			(sheetname "")
		)
		(fill yes
			(thermal_gap 0.5)
			(thermal_bridge_width 0.5)
			(island_removal_mode 0)
		)
		(polygon
			(pts
				(arc
					(start 285.505398 -213.671404)
					(mid 285.520277 -213.707325)
					(end 285.556198 -213.722204)
				)
				(arc
					(start 286.955738 -213.722204)
					(mid 286.991659 -213.707325)
					(end 287.006538 -213.671404)
				)
				(arc
					(start 287.006538 -213.262464)
					(mid 286.991659 -213.226543)
					(end 286.955738 -213.211664)
				)
				(arc
					(start 285.556198 -213.211664)
					(mid 285.520277 -213.226543)
					(end 285.505398 -213.262464)
				)
			)
		)
	)
	(zone
		(layers "In1.Cu" "In2.Cu")
		(hatch none 0.5)
		(connect_pads
			(clearance 0)
		)
		(min_thickness 0.25)
		(keepout
			(tracks not_allowed)
			(vias allowed)
			(pads allowed)
			(copperpour not_allowed)
			(footprints allowed)
		)
		(placement
			(enabled no)
			(sheetname "")
		)
		(fill yes
			(thermal_gap 0.5)
			(thermal_bridge_width 0.5)
			(island_removal_mode 0)
		)
		(polygon
			(pts
				(arc
					(start 56.752998 -234.921298)
					(mid 56.767877 -234.957219)
					(end 56.803798 -234.972098)
				)
				(arc
					(start 58.203338 -234.972098)
					(mid 58.239259 -234.957219)
					(end 58.254138 -234.921298)
				)
				(arc
					(start 58.254138 -234.512358)
					(mid 58.239259 -234.476437)
					(end 58.203338 -234.461558)
				)
				(arc
					(start 56.803798 -234.461558)
					(mid 56.767877 -234.476437)
					(end 56.752998 -234.512358)
				)
			)
		)
	)
	(zone
		(layers "In1.Cu" "In2.Cu")
		(hatch none 0.5)
		(connect_pads
			(clearance 0)
		)
		(min_thickness 0.25)
		(keepout
			(tracks not_allowed)
			(vias allowed)
			(pads allowed)
			(copperpour not_allowed)
			(footprints allowed)
		)
		(placement
			(enabled no)
			(sheetname "")
		)
		(fill yes
			(thermal_gap 0.5)
			(thermal_bridge_width 0.5)
			(island_removal_mode 0)
		)
		(polygon
			(pts
				(arc
					(start 22.47773 -299.521372)
					(mid 22.492609 -299.557293)
					(end 22.52853 -299.572172)
				)
				(arc
					(start 23.92807 -299.572172)
					(mid 23.963991 -299.557293)
					(end 23.97887 -299.521372)
				)
				(arc
					(start 23.97887 -299.112432)
					(mid 23.963991 -299.076511)
					(end 23.92807 -299.061632)
				)
				(arc
					(start 22.52853 -299.061632)
					(mid 22.492609 -299.076511)
					(end 22.47773 -299.112432)
				)
			)
		)
	)
	(zone
		(layers "In1.Cu" "In2.Cu")
		(hatch none 0.5)
		(connect_pads
			(clearance 0)
		)
		(min_thickness 0.25)
		(keepout
			(tracks not_allowed)
			(vias allowed)
			(pads allowed)
			(copperpour not_allowed)
			(footprints allowed)
		)
		(placement
			(enabled no)
			(sheetname "")
		)
		(fill yes
			(thermal_gap 0.5)
			(thermal_bridge_width 0.5)
			(island_removal_mode 0)
		)
		(polygon
			(pts
				(arc
					(start 308.136798 -217.071448)
					(mid 308.151677 -217.107369)
					(end 308.187598 -217.122248)
				)
				(arc
					(start 309.587138 -217.122248)
					(mid 309.623059 -217.107369)
					(end 309.637938 -217.071448)
				)
				(arc
					(start 309.637938 -216.662508)
					(mid 309.623059 -216.626587)
					(end 309.587138 -216.611708)
				)
				(arc
					(start 308.187598 -216.611708)
					(mid 308.151677 -216.626587)
					(end 308.136798 -216.662508)
				)
			)
		)
	)
	(zone
		(layers "In1.Cu" "In2.Cu")
		(hatch none 0.5)
		(connect_pads
			(clearance 0)
		)
		(min_thickness 0.25)
		(keepout
			(tracks not_allowed)
			(vias allowed)
			(pads allowed)
			(copperpour not_allowed)
			(footprints allowed)
		)
		(placement
			(enabled no)
			(sheetname "")
		)
		(fill yes
			(thermal_gap 0.5)
			(thermal_bridge_width 0.5)
			(island_removal_mode 0)
		)
		(polygon
			(pts
				(arc
					(start 425.190666 -203.471526)
					(mid 425.205545 -203.507447)
					(end 425.241466 -203.522326)
				)
				(arc
					(start 426.641006 -203.522326)
					(mid 426.676927 -203.507447)
					(end 426.691806 -203.471526)
				)
				(arc
					(start 426.691806 -203.062586)
					(mid 426.676927 -203.026665)
					(end 426.641006 -203.011786)
				)
				(arc
					(start 425.241466 -203.011786)
					(mid 425.205545 -203.026665)
					(end 425.190666 -203.062586)
				)
			)
		)
	)
	(zone
		(layers "In1.Cu" "In2.Cu")
		(hatch none 0.5)
		(connect_pads
			(clearance 0)
		)
		(min_thickness 0.25)
		(keepout
			(tracks not_allowed)
			(vias allowed)
			(pads allowed)
			(copperpour not_allowed)
			(footprints allowed)
		)
		(placement
			(enabled no)
			(sheetname "")
		)
		(fill yes
			(thermal_gap 0.5)
			(thermal_bridge_width 0.5)
			(island_removal_mode 0)
		)
		(polygon
			(pts
				(arc
					(start 52.65293 -266.371324)
					(mid 52.667809 -266.407245)
					(end 52.70373 -266.422124)
				)
				(arc
					(start 54.10327 -266.422124)
					(mid 54.139191 -266.407245)
					(end 54.15407 -266.371324)
				)
				(arc
					(start 54.15407 -265.962384)
					(mid 54.139191 -265.926463)
					(end 54.10327 -265.911584)
				)
				(arc
					(start 52.70373 -265.911584)
					(mid 52.667809 -265.926463)
					(end 52.65293 -265.962384)
				)
			)
		)
	)
	(zone
		(layers "In1.Cu" "In2.Cu")
		(hatch none 0.5)
		(connect_pads
			(clearance 0)
		)
		(min_thickness 0.25)
		(keepout
			(tracks not_allowed)
			(vias allowed)
			(pads allowed)
			(copperpour not_allowed)
			(footprints allowed)
		)
		(placement
			(enabled no)
			(sheetname "")
		)
		(fill yes
			(thermal_gap 0.5)
			(thermal_bridge_width 0.5)
			(island_removal_mode 0)
		)
		(polygon
			(pts
				(arc
					(start 455.365866 -285.92145)
					(mid 455.380745 -285.957371)
					(end 455.416666 -285.97225)
				)
				(arc
					(start 456.816206 -285.97225)
					(mid 456.852127 -285.957371)
					(end 456.867006 -285.92145)
				)
				(arc
					(start 456.867006 -285.51251)
					(mid 456.852127 -285.476589)
					(end 456.816206 -285.46171)
				)
				(arc
					(start 455.416666 -285.46171)
					(mid 455.380745 -285.476589)
					(end 455.365866 -285.51251)
				)
			)
		)
	)
	(zone
		(layers "In1.Cu" "In2.Cu")
		(hatch none 0.5)
		(connect_pads
			(clearance 0)
		)
		(min_thickness 0.25)
		(keepout
			(tracks not_allowed)
			(vias allowed)
			(pads allowed)
			(copperpour not_allowed)
			(footprints allowed)
		)
		(placement
			(enabled no)
			(sheetname "")
		)
		(fill yes
			(thermal_gap 0.5)
			(thermal_bridge_width 0.5)
			(island_removal_mode 0)
		)
		(polygon
			(pts
				(arc
					(start 266.974066 -281.671522)
					(mid 266.988945 -281.707443)
					(end 267.024866 -281.722322)
				)
				(arc
					(start 268.424406 -281.722322)
					(mid 268.460327 -281.707443)
					(end 268.475206 -281.671522)
				)
				(arc
					(start 268.475206 -281.262582)
					(mid 268.460327 -281.226661)
					(end 268.424406 -281.211782)
				)
				(arc
					(start 267.024866 -281.211782)
					(mid 266.988945 -281.226661)
					(end 266.974066 -281.262582)
				)
			)
		)
	)
	(zone
		(layers "In1.Cu" "In2.Cu")
		(hatch none 0.5)
		(connect_pads
			(clearance 0)
		)
		(min_thickness 0.25)
		(keepout
			(tracks not_allowed)
			(vias allowed)
			(pads allowed)
			(copperpour not_allowed)
			(footprints allowed)
		)
		(placement
			(enabled no)
			(sheetname "")
		)
		(fill yes
			(thermal_gap 0.5)
			(thermal_bridge_width 0.5)
			(island_removal_mode 0)
		)
		(polygon
			(pts
				(arc
					(start 195.78193 -305.471322)
					(mid 195.796809 -305.507243)
					(end 195.83273 -305.522122)
				)
				(arc
					(start 197.23227 -305.522122)
					(mid 197.268191 -305.507243)
					(end 197.28307 -305.471322)
				)
				(arc
					(start 197.28307 -305.062382)
					(mid 197.268191 -305.026461)
					(end 197.23227 -305.011582)
				)
				(arc
					(start 195.83273 -305.011582)
					(mid 195.796809 -305.026461)
					(end 195.78193 -305.062382)
				)
			)
		)
	)
	(zone
		(layers "In1.Cu" "In2.Cu")
		(hatch none 0.5)
		(connect_pads
			(clearance 0)
		)
		(min_thickness 0.25)
		(keepout
			(tracks not_allowed)
			(vias allowed)
			(pads allowed)
			(copperpour not_allowed)
			(footprints allowed)
		)
		(placement
			(enabled no)
			(sheetname "")
		)
		(fill yes
			(thermal_gap 0.5)
			(thermal_bridge_width 0.5)
			(island_removal_mode 0)
		)
		(polygon
			(pts
				(arc
					(start 436.178198 -286.771334)
					(mid 436.193077 -286.807255)
					(end 436.228998 -286.822134)
				)
				(arc
					(start 437.628538 -286.822134)
					(mid 437.664459 -286.807255)
					(end 437.679338 -286.771334)
				)
				(arc
					(start 437.679338 -286.362394)
					(mid 437.664459 -286.326473)
					(end 437.628538 -286.311594)
				)
				(arc
					(start 436.228998 -286.311594)
					(mid 436.193077 -286.326473)
					(end 436.178198 -286.362394)
				)
			)
		)
	)
	(zone
		(layers "In1.Cu" "In2.Cu")
		(hatch none 0.5)
		(connect_pads
			(clearance 0)
		)
		(min_thickness 0.25)
		(keepout
			(tracks not_allowed)
			(vias allowed)
			(pads allowed)
			(copperpour not_allowed)
			(footprints allowed)
		)
		(placement
			(enabled no)
			(sheetname "")
		)
		(fill yes
			(thermal_gap 0.5)
			(thermal_bridge_width 0.5)
			(island_removal_mode 0)
		)
		(polygon
			(pts
				(arc
					(start 274.517866 -250.221496)
					(mid 274.532745 -250.257417)
					(end 274.568666 -250.272296)
				)
				(arc
					(start 275.968206 -250.272296)
					(mid 276.004127 -250.257417)
					(end 276.019006 -250.221496)
				)
				(arc
					(start 276.019006 -249.812556)
					(mid 276.004127 -249.776635)
					(end 275.968206 -249.761756)
				)
				(arc
					(start 274.568666 -249.761756)
					(mid 274.532745 -249.776635)
					(end 274.517866 -249.812556)
				)
			)
		)
	)
	(zone
		(layers "In1.Cu" "In2.Cu")
		(hatch none 0.5)
		(connect_pads
			(clearance 0)
		)
		(min_thickness 0.25)
		(keepout
			(tracks not_allowed)
			(vias allowed)
			(pads allowed)
			(copperpour not_allowed)
			(footprints allowed)
		)
		(placement
			(enabled no)
			(sheetname "")
		)
		(fill yes
			(thermal_gap 0.5)
			(thermal_bridge_width 0.5)
			(island_removal_mode 0)
		)
		(polygon
			(pts
				(arc
					(start 22.47773 -269.771368)
					(mid 22.492609 -269.807289)
					(end 22.52853 -269.822168)
				)
				(arc
					(start 23.92807 -269.822168)
					(mid 23.963991 -269.807289)
					(end 23.97887 -269.771368)
				)
				(arc
					(start 23.97887 -269.362428)
					(mid 23.963991 -269.326507)
					(end 23.92807 -269.311628)
				)
				(arc
					(start 22.52853 -269.311628)
					(mid 22.492609 -269.326507)
					(end 22.47773 -269.362428)
				)
			)
		)
	)
	(zone
		(layers "In1.Cu" "In2.Cu")
		(hatch none 0.5)
		(connect_pads
			(clearance 0)
		)
		(min_thickness 0.25)
		(keepout
			(tracks not_allowed)
			(vias allowed)
			(pads allowed)
			(copperpour not_allowed)
			(footprints allowed)
		)
		(placement
			(enabled no)
			(sheetname "")
		)
		(fill yes
			(thermal_gap 0.5)
			(thermal_bridge_width 0.5)
			(island_removal_mode 0)
		)
		(polygon
			(pts
				(arc
					(start 56.752998 -236.62132)
					(mid 56.767877 -236.657241)
					(end 56.803798 -236.67212)
				)
				(arc
					(start 58.203338 -236.67212)
					(mid 58.239259 -236.657241)
					(end 58.254138 -236.62132)
				)
				(arc
					(start 58.254138 -236.21238)
					(mid 58.239259 -236.176459)
					(end 58.203338 -236.16158)
				)
				(arc
					(start 56.803798 -236.16158)
					(mid 56.767877 -236.176459)
					(end 56.752998 -236.21238)
				)
			)
		)
	)
	(zone
		(layers "In1.Cu" "In2.Cu")
		(hatch none 0.5)
		(connect_pads
			(clearance 0)
		)
		(min_thickness 0.25)
		(keepout
			(tracks not_allowed)
			(vias allowed)
			(pads allowed)
			(copperpour not_allowed)
			(footprints allowed)
		)
		(placement
			(enabled no)
			(sheetname "")
		)
		(fill yes
			(thermal_gap 0.5)
			(thermal_bridge_width 0.5)
			(island_removal_mode 0)
		)
		(polygon
			(pts
				(arc
					(start 64.296798 -276.571456)
					(mid 64.311677 -276.607377)
					(end 64.347598 -276.622256)
				)
				(arc
					(start 65.747138 -276.622256)
					(mid 65.783059 -276.607377)
					(end 65.797938 -276.571456)
				)
				(arc
					(start 65.797938 -276.162516)
					(mid 65.783059 -276.126595)
					(end 65.747138 -276.111716)
				)
				(arc
					(start 64.347598 -276.111716)
					(mid 64.311677 -276.126595)
					(end 64.296798 -276.162516)
				)
			)
		)
	)
	(zone
		(layers "In1.Cu" "In2.Cu")
		(hatch none 0.5)
		(connect_pads
			(clearance 0)
		)
		(min_thickness 0.25)
		(keepout
			(tracks not_allowed)
			(vias allowed)
			(pads allowed)
			(copperpour not_allowed)
			(footprints allowed)
		)
		(placement
			(enabled no)
			(sheetname "")
		)
		(fill yes
			(thermal_gap 0.5)
			(thermal_bridge_width 0.5)
			(island_removal_mode 0)
		)
		(polygon
			(pts
				(arc
					(start 440.278266 -292.721538)
					(mid 440.293145 -292.757459)
					(end 440.329066 -292.772338)
				)
				(arc
					(start 441.728606 -292.772338)
					(mid 441.764527 -292.757459)
					(end 441.779406 -292.721538)
				)
				(arc
					(start 441.779406 -292.312598)
					(mid 441.764527 -292.276677)
					(end 441.728606 -292.261798)
				)
				(arc
					(start 440.329066 -292.261798)
					(mid 440.293145 -292.276677)
					(end 440.278266 -292.312598)
				)
			)
		)
	)
	(zone
		(layers "In1.Cu" "In2.Cu")
		(hatch none 0.5)
		(connect_pads
			(clearance 0)
		)
		(min_thickness 0.25)
		(keepout
			(tracks not_allowed)
			(vias allowed)
			(pads allowed)
			(copperpour not_allowed)
			(footprints allowed)
		)
		(placement
			(enabled no)
			(sheetname "")
		)
		(fill yes
			(thermal_gap 0.5)
			(thermal_bridge_width 0.5)
			(island_removal_mode 0)
		)
		(polygon
			(pts
				(arc
					(start 277.961598 -273.171412)
					(mid 277.976477 -273.207333)
					(end 278.012398 -273.222212)
				)
				(arc
					(start 279.411938 -273.222212)
					(mid 279.447859 -273.207333)
					(end 279.462738 -273.171412)
				)
				(arc
					(start 279.462738 -272.762472)
					(mid 279.447859 -272.726551)
					(end 279.411938 -272.711672)
				)
				(arc
					(start 278.012398 -272.711672)
					(mid 277.976477 -272.726551)
					(end 277.961598 -272.762472)
				)
			)
		)
	)
	(zone
		(layers "In1.Cu" "In2.Cu")
		(hatch none 0.5)
		(connect_pads
			(clearance 0)
		)
		(min_thickness 0.25)
		(keepout
			(tracks not_allowed)
			(vias allowed)
			(pads allowed)
			(copperpour not_allowed)
			(footprints allowed)
		)
		(placement
			(enabled no)
			(sheetname "")
		)
		(fill yes
			(thermal_gap 0.5)
			(thermal_bridge_width 0.5)
			(island_removal_mode 0)
		)
		(polygon
			(pts
				(arc
					(start 417.646866 -302.071532)
					(mid 417.661745 -302.107453)
					(end 417.697666 -302.122332)
				)
				(arc
					(start 419.097206 -302.122332)
					(mid 419.133127 -302.107453)
					(end 419.148006 -302.071532)
				)
				(arc
					(start 419.148006 -301.662592)
					(mid 419.133127 -301.626671)
					(end 419.097206 -301.611792)
				)
				(arc
					(start 417.697666 -301.611792)
					(mid 417.661745 -301.626671)
					(end 417.646866 -301.662592)
				)
			)
		)
	)
	(zone
		(layers "In1.Cu" "In2.Cu")
		(hatch none 0.5)
		(connect_pads
			(clearance 0)
		)
		(min_thickness 0.25)
		(keepout
			(tracks not_allowed)
			(vias allowed)
			(pads allowed)
			(copperpour not_allowed)
			(footprints allowed)
		)
		(placement
			(enabled no)
			(sheetname "")
		)
		(fill yes
			(thermal_gap 0.5)
			(thermal_bridge_width 0.5)
			(island_removal_mode 0)
		)
		(polygon
			(pts
				(arc
					(start 207.425798 -251.921518)
					(mid 207.440677 -251.957439)
					(end 207.476598 -251.972318)
				)
				(arc
					(start 208.876138 -251.972318)
					(mid 208.912059 -251.957439)
					(end 208.926938 -251.921518)
				)
				(arc
					(start 208.926938 -251.512578)
					(mid 208.912059 -251.476657)
					(end 208.876138 -251.461778)
				)
				(arc
					(start 207.476598 -251.461778)
					(mid 207.440677 -251.476657)
					(end 207.425798 -251.512578)
				)
			)
		)
	)
	(zone
		(layers "In1.Cu" "In2.Cu")
		(hatch none 0.5)
		(connect_pads
			(clearance 0)
		)
		(min_thickness 0.25)
		(keepout
			(tracks not_allowed)
			(vias allowed)
			(pads allowed)
			(copperpour not_allowed)
			(footprints allowed)
		)
		(placement
			(enabled no)
			(sheetname "")
		)
		(fill yes
			(thermal_gap 0.5)
			(thermal_bridge_width 0.5)
			(island_removal_mode 0)
		)
		(polygon
			(pts
				(arc
					(start 177.250598 -295.271444)
					(mid 177.265477 -295.307365)
					(end 177.301398 -295.322244)
				)
				(arc
					(start 178.700938 -295.322244)
					(mid 178.736859 -295.307365)
					(end 178.751738 -295.271444)
				)
				(arc
					(start 178.751738 -294.862504)
					(mid 178.736859 -294.826583)
					(end 178.700938 -294.811704)
				)
				(arc
					(start 177.301398 -294.811704)
					(mid 177.265477 -294.826583)
					(end 177.250598 -294.862504)
				)
			)
		)
	)
	(zone
		(layers "In1.Cu" "In2.Cu")
		(hatch none 0.5)
		(connect_pads
			(clearance 0)
		)
		(min_thickness 0.25)
		(keepout
			(tracks not_allowed)
			(vias allowed)
			(pads allowed)
			(copperpour not_allowed)
			(footprints allowed)
		)
		(placement
			(enabled no)
			(sheetname "")
		)
		(fill yes
			(thermal_gap 0.5)
			(thermal_bridge_width 0.5)
			(island_removal_mode 0)
		)
		(polygon
			(pts
				(arc
					(start 432.734466 -225.571304)
					(mid 432.749345 -225.607225)
					(end 432.785266 -225.622104)
				)
				(arc
					(start 434.184806 -225.622104)
					(mid 434.220727 -225.607225)
					(end 434.235606 -225.571304)
				)
				(arc
					(start 434.235606 -225.162364)
					(mid 434.220727 -225.126443)
					(end 434.184806 -225.111564)
				)
				(arc
					(start 432.785266 -225.111564)
					(mid 432.749345 -225.126443)
					(end 432.734466 -225.162364)
				)
			)
		)
	)
	(zone
		(layers "In1.Cu" "In2.Cu")
		(hatch none 0.5)
		(connect_pads
			(clearance 0)
		)
		(min_thickness 0.25)
		(keepout
			(tracks not_allowed)
			(vias allowed)
			(pads allowed)
			(copperpour not_allowed)
			(footprints allowed)
		)
		(placement
			(enabled no)
			(sheetname "")
		)
		(fill yes
			(thermal_gap 0.5)
			(thermal_bridge_width 0.5)
			(island_removal_mode 0)
		)
		(polygon
			(pts
				(arc
					(start 41.665398 -298.671488)
					(mid 41.680277 -298.707409)
					(end 41.716198 -298.722288)
				)
				(arc
					(start 43.115738 -298.722288)
					(mid 43.151659 -298.707409)
					(end 43.166538 -298.671488)
				)
				(arc
					(start 43.166538 -298.262548)
					(mid 43.151659 -298.226627)
					(end 43.115738 -298.211748)
				)
				(arc
					(start 41.716198 -298.211748)
					(mid 41.680277 -298.226627)
					(end 41.665398 -298.262548)
				)
			)
		)
	)
	(zone
		(layers "In1.Cu" "In2.Cu")
		(hatch none 0.5)
		(connect_pads
			(clearance 0)
		)
		(min_thickness 0.25)
		(keepout
			(tracks not_allowed)
			(vias allowed)
			(pads allowed)
			(copperpour not_allowed)
			(footprints allowed)
		)
		(placement
			(enabled no)
			(sheetname "")
		)
		(fill yes
			(thermal_gap 0.5)
			(thermal_bridge_width 0.5)
			(island_removal_mode 0)
		)
		(polygon
			(pts
				(arc
					(start 45.10913 -285.071312)
					(mid 45.124009 -285.107233)
					(end 45.15993 -285.122112)
				)
				(arc
					(start 46.55947 -285.122112)
					(mid 46.595391 -285.107233)
					(end 46.61027 -285.071312)
				)
				(arc
					(start 46.61027 -284.662372)
					(mid 46.595391 -284.626451)
					(end 46.55947 -284.611572)
				)
				(arc
					(start 45.15993 -284.611572)
					(mid 45.124009 -284.626451)
					(end 45.10913 -284.662372)
				)
			)
		)
	)
	(zone
		(layers "In1.Cu" "In2.Cu")
		(hatch none 0.5)
		(connect_pads
			(clearance 0)
		)
		(min_thickness 0.25)
		(keepout
			(tracks not_allowed)
			(vias allowed)
			(pads allowed)
			(copperpour not_allowed)
			(footprints allowed)
		)
		(placement
			(enabled no)
			(sheetname "")
		)
		(fill yes
			(thermal_gap 0.5)
			(thermal_bridge_width 0.5)
			(island_removal_mode 0)
		)
		(polygon
			(pts
				(arc
					(start 443.721998 -219.621354)
					(mid 443.736877 -219.657275)
					(end 443.772798 -219.672154)
				)
				(arc
					(start 445.172338 -219.672154)
					(mid 445.208259 -219.657275)
					(end 445.223138 -219.621354)
				)
				(arc
					(start 445.223138 -219.212414)
					(mid 445.208259 -219.176493)
					(end 445.172338 -219.161614)
				)
				(arc
					(start 443.772798 -219.161614)
					(mid 443.736877 -219.176493)
					(end 443.721998 -219.212414)
				)
			)
		)
	)
	(zone
		(layers "In1.Cu" "In2.Cu")
		(hatch none 0.5)
		(connect_pads
			(clearance 0)
		)
		(min_thickness 0.25)
		(keepout
			(tracks not_allowed)
			(vias allowed)
			(pads allowed)
			(copperpour not_allowed)
			(footprints allowed)
		)
		(placement
			(enabled no)
			(sheetname "")
		)
		(fill yes
			(thermal_gap 0.5)
			(thermal_bridge_width 0.5)
			(island_removal_mode 0)
		)
		(polygon
			(pts
				(arc
					(start 300.592998 -314.821316)
					(mid 300.607877 -314.857237)
					(end 300.643798 -314.872116)
				)
				(arc
					(start 302.043338 -314.872116)
					(mid 302.079259 -314.857237)
					(end 302.094138 -314.821316)
				)
				(arc
					(start 302.094138 -314.412376)
					(mid 302.079259 -314.376455)
					(end 302.043338 -314.361576)
				)
				(arc
					(start 300.643798 -314.361576)
					(mid 300.607877 -314.376455)
					(end 300.592998 -314.412376)
				)
			)
		)
	)
	(zone
		(layers "In1.Cu" "In2.Cu")
		(hatch none 0.5)
		(connect_pads
			(clearance 0)
		)
		(min_thickness 0.25)
		(keepout
			(tracks not_allowed)
			(vias allowed)
			(pads allowed)
			(copperpour not_allowed)
			(footprints allowed)
		)
		(placement
			(enabled no)
			(sheetname "")
		)
		(fill yes
			(thermal_gap 0.5)
			(thermal_bridge_width 0.5)
			(island_removal_mode 0)
		)
		(polygon
			(pts
				(arc
					(start 41.665398 -208.571338)
					(mid 41.680277 -208.607259)
					(end 41.716198 -208.622138)
				)
				(arc
					(start 43.115738 -208.622138)
					(mid 43.151659 -208.607259)
					(end 43.166538 -208.571338)
				)
				(arc
					(start 43.166538 -208.162398)
					(mid 43.151659 -208.126477)
					(end 43.115738 -208.111598)
				)
				(arc
					(start 41.716198 -208.111598)
					(mid 41.680277 -208.126477)
					(end 41.665398 -208.162398)
				)
			)
		)
	)
	(zone
		(layers "In1.Cu" "In2.Cu")
		(hatch none 0.5)
		(connect_pads
			(clearance 0)
		)
		(min_thickness 0.25)
		(keepout
			(tracks not_allowed)
			(vias allowed)
			(pads allowed)
			(copperpour not_allowed)
			(footprints allowed)
		)
		(placement
			(enabled no)
			(sheetname "")
		)
		(fill yes
			(thermal_gap 0.5)
			(thermal_bridge_width 0.5)
			(island_removal_mode 0)
		)
		(polygon
			(pts
				(arc
					(start 165.60673 -296.121328)
					(mid 165.621609 -296.157249)
					(end 165.65753 -296.172128)
				)
				(arc
					(start 167.05707 -296.172128)
					(mid 167.092991 -296.157249)
					(end 167.10787 -296.121328)
				)
				(arc
					(start 167.10787 -295.712388)
					(mid 167.092991 -295.676467)
					(end 167.05707 -295.661588)
				)
				(arc
					(start 165.65753 -295.661588)
					(mid 165.621609 -295.676467)
					(end 165.60673 -295.712388)
				)
			)
		)
	)
	(zone
		(layers "In1.Cu" "In2.Cu")
		(hatch none 0.5)
		(connect_pads
			(clearance 0)
		)
		(min_thickness 0.25)
		(keepout
			(tracks not_allowed)
			(vias allowed)
			(pads allowed)
			(copperpour not_allowed)
			(footprints allowed)
		)
		(placement
			(enabled no)
			(sheetname "")
		)
		(fill yes
			(thermal_gap 0.5)
			(thermal_bridge_width 0.5)
			(island_removal_mode 0)
		)
		(polygon
			(pts
				(arc
					(start 262.873998 -310.571388)
					(mid 262.888877 -310.607309)
					(end 262.924798 -310.622188)
				)
				(arc
					(start 264.324338 -310.622188)
					(mid 264.360259 -310.607309)
					(end 264.375138 -310.571388)
				)
				(arc
					(start 264.375138 -310.162448)
					(mid 264.360259 -310.126527)
					(end 264.324338 -310.111648)
				)
				(arc
					(start 262.924798 -310.111648)
					(mid 262.888877 -310.126527)
					(end 262.873998 -310.162448)
				)
			)
		)
	)
	(zone
		(layers "In1.Cu" "In2.Cu")
		(hatch none 0.5)
		(connect_pads
			(clearance 0)
		)
		(min_thickness 0.25)
		(keepout
			(tracks not_allowed)
			(vias allowed)
			(pads allowed)
			(copperpour not_allowed)
			(footprints allowed)
		)
		(placement
			(enabled no)
			(sheetname "")
		)
		(fill yes
			(thermal_gap 0.5)
			(thermal_bridge_width 0.5)
			(island_removal_mode 0)
		)
		(polygon
			(pts
				(arc
					(start 30.02153 -228.971348)
					(mid 30.036409 -229.007269)
					(end 30.07233 -229.022148)
				)
				(arc
					(start 31.47187 -229.022148)
					(mid 31.507791 -229.007269)
					(end 31.52267 -228.971348)
				)
				(arc
					(start 31.52267 -228.562408)
					(mid 31.507791 -228.526487)
					(end 31.47187 -228.511608)
				)
				(arc
					(start 30.07233 -228.511608)
					(mid 30.036409 -228.526487)
					(end 30.02153 -228.562408)
				)
			)
		)
	)
	(zone
		(layers "In1.Cu" "In2.Cu")
		(hatch none 0.5)
		(connect_pads
			(clearance 0)
		)
		(min_thickness 0.25)
		(keepout
			(tracks not_allowed)
			(vias allowed)
			(pads allowed)
			(copperpour not_allowed)
			(footprints allowed)
		)
		(placement
			(enabled no)
			(sheetname "")
		)
		(fill yes
			(thermal_gap 0.5)
			(thermal_bridge_width 0.5)
			(island_removal_mode 0)
		)
		(polygon
			(pts
				(arc
					(start 436.178198 -259.57149)
					(mid 436.193077 -259.607411)
					(end 436.228998 -259.62229)
				)
				(arc
					(start 437.628538 -259.62229)
					(mid 437.664459 -259.607411)
					(end 437.679338 -259.57149)
				)
				(arc
					(start 437.679338 -259.16255)
					(mid 437.664459 -259.126629)
					(end 437.628538 -259.11175)
				)
				(arc
					(start 436.228998 -259.11175)
					(mid 436.193077 -259.126629)
					(end 436.178198 -259.16255)
				)
			)
		)
	)
	(zone
		(layers "In1.Cu" "In2.Cu")
		(hatch none 0.5)
		(connect_pads
			(clearance 0)
		)
		(min_thickness 0.25)
		(keepout
			(tracks not_allowed)
			(vias allowed)
			(pads allowed)
			(copperpour not_allowed)
			(footprints allowed)
		)
		(placement
			(enabled no)
			(sheetname "")
		)
		(fill yes
			(thermal_gap 0.5)
			(thermal_bridge_width 0.5)
			(island_removal_mode 0)
		)
		(polygon
			(pts
				(arc
					(start 425.190666 -300.37151)
					(mid 425.205545 -300.407431)
					(end 425.241466 -300.42231)
				)
				(arc
					(start 426.641006 -300.42231)
					(mid 426.676927 -300.407431)
					(end 426.691806 -300.37151)
				)
				(arc
					(start 426.691806 -299.96257)
					(mid 426.676927 -299.926649)
					(end 426.641006 -299.91177)
				)
				(arc
					(start 425.241466 -299.91177)
					(mid 425.205545 -299.926649)
					(end 425.190666 -299.96257)
				)
			)
		)
	)
	(zone
		(layers "In1.Cu" "In2.Cu")
		(hatch none 0.5)
		(connect_pads
			(clearance 0)
		)
		(min_thickness 0.25)
		(keepout
			(tracks not_allowed)
			(vias allowed)
			(pads allowed)
			(copperpour not_allowed)
			(footprints allowed)
		)
		(placement
			(enabled no)
			(sheetname "")
		)
		(fill yes
			(thermal_gap 0.5)
			(thermal_bridge_width 0.5)
			(island_removal_mode 0)
		)
		(polygon
			(pts
				(arc
					(start 7.39013 -314.821316)
					(mid 7.405009 -314.857237)
					(end 7.44093 -314.872116)
				)
				(arc
					(start 8.84047 -314.872116)
					(mid 8.876391 -314.857237)
					(end 8.89127 -314.821316)
				)
				(arc
					(start 8.89127 -314.412376)
					(mid 8.876391 -314.376455)
					(end 8.84047 -314.361576)
				)
				(arc
					(start 7.44093 -314.361576)
					(mid 7.405009 -314.376455)
					(end 7.39013 -314.412376)
				)
			)
		)
	)
	(zone
		(layers "In1.Cu" "In2.Cu")
		(hatch none 0.5)
		(connect_pads
			(clearance 0)
		)
		(min_thickness 0.25)
		(keepout
			(tracks not_allowed)
			(vias allowed)
			(pads allowed)
			(copperpour not_allowed)
			(footprints allowed)
		)
		(placement
			(enabled no)
			(sheetname "")
		)
		(fill yes
			(thermal_gap 0.5)
			(thermal_bridge_width 0.5)
			(island_removal_mode 0)
		)
		(polygon
			(pts
				(arc
					(start 274.517866 -259.57149)
					(mid 274.532745 -259.607411)
					(end 274.568666 -259.62229)
				)
				(arc
					(start 275.968206 -259.62229)
					(mid 276.004127 -259.607411)
					(end 276.019006 -259.57149)
				)
				(arc
					(start 276.019006 -259.16255)
					(mid 276.004127 -259.126629)
					(end 275.968206 -259.11175)
				)
				(arc
					(start 274.568666 -259.11175)
					(mid 274.532745 -259.126629)
					(end 274.517866 -259.16255)
				)
			)
		)
	)
	(zone
		(layers "In1.Cu" "In2.Cu")
		(hatch none 0.5)
		(connect_pads
			(clearance 0)
		)
		(min_thickness 0.25)
		(keepout
			(tracks not_allowed)
			(vias allowed)
			(pads allowed)
			(copperpour not_allowed)
			(footprints allowed)
		)
		(placement
			(enabled no)
			(sheetname "")
		)
		(fill yes
			(thermal_gap 0.5)
			(thermal_bridge_width 0.5)
			(island_removal_mode 0)
		)
		(polygon
			(pts
				(arc
					(start 406.002998 -219.621354)
					(mid 406.017877 -219.657275)
					(end 406.053798 -219.672154)
				)
				(arc
					(start 407.453338 -219.672154)
					(mid 407.489259 -219.657275)
					(end 407.504138 -219.621354)
				)
				(arc
					(start 407.504138 -219.212414)
					(mid 407.489259 -219.176493)
					(end 407.453338 -219.161614)
				)
				(arc
					(start 406.053798 -219.161614)
					(mid 406.017877 -219.176493)
					(end 406.002998 -219.212414)
				)
			)
		)
	)
	(zone
		(layers "In1.Cu" "In2.Cu")
		(hatch none 0.5)
		(connect_pads
			(clearance 0)
		)
		(min_thickness 0.25)
		(keepout
			(tracks not_allowed)
			(vias allowed)
			(pads allowed)
			(copperpour not_allowed)
			(footprints allowed)
		)
		(placement
			(enabled no)
			(sheetname "")
		)
		(fill yes
			(thermal_gap 0.5)
			(thermal_bridge_width 0.5)
			(island_removal_mode 0)
		)
		(polygon
			(pts
				(arc
					(start 184.794398 -274.871434)
					(mid 184.809277 -274.907355)
					(end 184.845198 -274.922234)
				)
				(arc
					(start 186.244738 -274.922234)
					(mid 186.280659 -274.907355)
					(end 186.295538 -274.871434)
				)
				(arc
					(start 186.295538 -274.462494)
					(mid 186.280659 -274.426573)
					(end 186.244738 -274.411694)
				)
				(arc
					(start 184.845198 -274.411694)
					(mid 184.809277 -274.426573)
					(end 184.794398 -274.462494)
				)
			)
		)
	)
	(zone
		(layers "In1.Cu" "In2.Cu")
		(hatch none 0.5)
		(connect_pads
			(clearance 0)
		)
		(min_thickness 0.25)
		(keepout
			(tracks not_allowed)
			(vias allowed)
			(pads allowed)
			(copperpour not_allowed)
			(footprints allowed)
		)
		(placement
			(enabled no)
			(sheetname "")
		)
		(fill yes
			(thermal_gap 0.5)
			(thermal_bridge_width 0.5)
			(island_removal_mode 0)
		)
		(polygon
			(pts
				(arc
					(start 421.090598 -198.37146)
					(mid 421.105477 -198.407381)
					(end 421.141398 -198.42226)
				)
				(arc
					(start 422.540938 -198.42226)
					(mid 422.576859 -198.407381)
					(end 422.591738 -198.37146)
				)
				(arc
					(start 422.591738 -197.96252)
					(mid 422.576859 -197.926599)
					(end 422.540938 -197.91172)
				)
				(arc
					(start 421.141398 -197.91172)
					(mid 421.105477 -197.926599)
					(end 421.090598 -197.96252)
				)
			)
		)
	)
	(zone
		(layers "In1.Cu" "In2.Cu")
		(hatch none 0.5)
		(connect_pads
			(clearance 0)
		)
		(min_thickness 0.25)
		(keepout
			(tracks not_allowed)
			(vias allowed)
			(pads allowed)
			(copperpour not_allowed)
			(footprints allowed)
		)
		(placement
			(enabled no)
			(sheetname "")
		)
		(fill yes
			(thermal_gap 0.5)
			(thermal_bridge_width 0.5)
			(island_removal_mode 0)
		)
		(polygon
			(pts
				(arc
					(start 266.974066 -300.37151)
					(mid 266.988945 -300.407431)
					(end 267.024866 -300.42231)
				)
				(arc
					(start 268.424406 -300.42231)
					(mid 268.460327 -300.407431)
					(end 268.475206 -300.37151)
				)
				(arc
					(start 268.475206 -299.96257)
					(mid 268.460327 -299.926649)
					(end 268.424406 -299.91177)
				)
				(arc
					(start 267.024866 -299.91177)
					(mid 266.988945 -299.926649)
					(end 266.974066 -299.96257)
				)
			)
		)
	)
	(zone
		(layers "In1.Cu" "In2.Cu")
		(hatch none 0.5)
		(connect_pads
			(clearance 0)
		)
		(min_thickness 0.25)
		(keepout
			(tracks not_allowed)
			(vias allowed)
			(pads allowed)
			(copperpour not_allowed)
			(footprints allowed)
		)
		(placement
			(enabled no)
			(sheetname "")
		)
		(fill yes
			(thermal_gap 0.5)
			(thermal_bridge_width 0.5)
			(island_removal_mode 0)
		)
		(polygon
			(pts
				(arc
					(start 410.103066 -246.821452)
					(mid 410.117945 -246.857373)
					(end 410.153866 -246.872252)
				)
				(arc
					(start 411.553406 -246.872252)
					(mid 411.589327 -246.857373)
					(end 411.604206 -246.821452)
				)
				(arc
					(start 411.604206 -246.412512)
					(mid 411.589327 -246.376591)
					(end 411.553406 -246.361712)
				)
				(arc
					(start 410.153866 -246.361712)
					(mid 410.117945 -246.376591)
					(end 410.103066 -246.412512)
				)
			)
		)
	)
	(zone
		(layers "In1.Cu" "In2.Cu")
		(hatch none 0.5)
		(connect_pads
			(clearance 0)
		)
		(min_thickness 0.25)
		(keepout
			(tracks not_allowed)
			(vias allowed)
			(pads allowed)
			(copperpour not_allowed)
			(footprints allowed)
		)
		(placement
			(enabled no)
			(sheetname "")
		)
		(fill yes
			(thermal_gap 0.5)
			(thermal_bridge_width 0.5)
			(island_removal_mode 0)
		)
		(polygon
			(pts
				(arc
					(start 214.969598 -197.521322)
					(mid 214.984477 -197.557243)
					(end 215.020398 -197.572122)
				)
				(arc
					(start 216.419938 -197.572122)
					(mid 216.455859 -197.557243)
					(end 216.470738 -197.521322)
				)
				(arc
					(start 216.470738 -197.112382)
					(mid 216.455859 -197.076461)
					(end 216.419938 -197.061582)
				)
				(arc
					(start 215.020398 -197.061582)
					(mid 214.984477 -197.076461)
					(end 214.969598 -197.112382)
				)
			)
		)
	)
	(zone
		(layers "In1.Cu" "In2.Cu")
		(hatch none 0.5)
		(connect_pads
			(clearance 0)
		)
		(min_thickness 0.25)
		(keepout
			(tracks not_allowed)
			(vias allowed)
			(pads allowed)
			(copperpour not_allowed)
			(footprints allowed)
		)
		(placement
			(enabled no)
			(sheetname "")
		)
		(fill yes
			(thermal_gap 0.5)
			(thermal_bridge_width 0.5)
			(island_removal_mode 0)
		)
		(polygon
			(pts
				(arc
					(start 425.190666 -206.871316)
					(mid 425.205545 -206.907237)
					(end 425.241466 -206.922116)
				)
				(arc
					(start 426.641006 -206.922116)
					(mid 426.676927 -206.907237)
					(end 426.691806 -206.871316)
				)
				(arc
					(start 426.691806 -206.462376)
					(mid 426.676927 -206.426455)
					(end 426.641006 -206.411576)
				)
				(arc
					(start 425.241466 -206.411576)
					(mid 425.205545 -206.426455)
					(end 425.190666 -206.462376)
				)
			)
		)
	)
	(zone
		(layers "In1.Cu" "In2.Cu")
		(hatch none 0.5)
		(connect_pads
			(clearance 0)
		)
		(min_thickness 0.25)
		(keepout
			(tracks not_allowed)
			(vias allowed)
			(pads allowed)
			(copperpour not_allowed)
			(footprints allowed)
		)
		(placement
			(enabled no)
			(sheetname "")
		)
		(fill yes
			(thermal_gap 0.5)
			(thermal_bridge_width 0.5)
			(island_removal_mode 0)
		)
		(polygon
			(pts
				(arc
					(start 19.033998 -302.071532)
					(mid 19.048877 -302.107453)
					(end 19.084798 -302.122332)
				)
				(arc
					(start 20.484338 -302.122332)
					(mid 20.520259 -302.107453)
					(end 20.535138 -302.071532)
				)
				(arc
					(start 20.535138 -301.662592)
					(mid 20.520259 -301.626671)
					(end 20.484338 -301.611792)
				)
				(arc
					(start 19.084798 -301.611792)
					(mid 19.048877 -301.626671)
					(end 19.033998 -301.662592)
				)
			)
		)
	)
	(zone
		(layers "In1.Cu" "In2.Cu")
		(hatch none 0.5)
		(connect_pads
			(clearance 0)
		)
		(min_thickness 0.25)
		(keepout
			(tracks not_allowed)
			(vias allowed)
			(pads allowed)
			(copperpour not_allowed)
			(footprints allowed)
		)
		(placement
			(enabled no)
			(sheetname "")
		)
		(fill yes
			(thermal_gap 0.5)
			(thermal_bridge_width 0.5)
			(island_removal_mode 0)
		)
		(polygon
			(pts
				(arc
					(start 60.19673 -206.021432)
					(mid 60.211609 -206.057353)
					(end 60.24753 -206.072232)
				)
				(arc
					(start 61.64707 -206.072232)
					(mid 61.682991 -206.057353)
					(end 61.69787 -206.021432)
				)
				(arc
					(start 61.69787 -205.612492)
					(mid 61.682991 -205.576571)
					(end 61.64707 -205.561692)
				)
				(arc
					(start 60.24753 -205.561692)
					(mid 60.211609 -205.576571)
					(end 60.19673 -205.612492)
				)
			)
		)
	)
	(zone
		(layers "In1.Cu" "In2.Cu")
		(hatch none 0.5)
		(connect_pads
			(clearance 0)
		)
		(min_thickness 0.25)
		(keepout
			(tracks not_allowed)
			(vias allowed)
			(pads allowed)
			(copperpour not_allowed)
			(footprints allowed)
		)
		(placement
			(enabled no)
			(sheetname "")
		)
		(fill yes
			(thermal_gap 0.5)
			(thermal_bridge_width 0.5)
			(island_removal_mode 0)
		)
		(polygon
			(pts
				(arc
					(start 436.178198 -284.221428)
					(mid 436.193077 -284.257349)
					(end 436.228998 -284.272228)
				)
				(arc
					(start 437.628538 -284.272228)
					(mid 437.664459 -284.257349)
					(end 437.679338 -284.221428)
				)
				(arc
					(start 437.679338 -283.812488)
					(mid 437.664459 -283.776567)
					(end 437.628538 -283.761688)
				)
				(arc
					(start 436.228998 -283.761688)
					(mid 436.193077 -283.776567)
					(end 436.178198 -283.812488)
				)
			)
		)
	)
	(zone
		(layers "In1.Cu" "In2.Cu")
		(hatch none 0.5)
		(connect_pads
			(clearance 0)
		)
		(min_thickness 0.25)
		(keepout
			(tracks not_allowed)
			(vias allowed)
			(pads allowed)
			(copperpour not_allowed)
			(footprints allowed)
		)
		(placement
			(enabled no)
			(sheetname "")
		)
		(fill yes
			(thermal_gap 0.5)
			(thermal_bridge_width 0.5)
			(island_removal_mode 0)
		)
		(polygon
			(pts
				(arc
					(start 49.209198 -206.871316)
					(mid 49.224077 -206.907237)
					(end 49.259998 -206.922116)
				)
				(arc
					(start 50.659538 -206.922116)
					(mid 50.695459 -206.907237)
					(end 50.710338 -206.871316)
				)
				(arc
					(start 50.710338 -206.462376)
					(mid 50.695459 -206.426455)
					(end 50.659538 -206.411576)
				)
				(arc
					(start 49.259998 -206.411576)
					(mid 49.224077 -206.426455)
					(end 49.209198 -206.462376)
				)
			)
		)
	)
	(zone
		(layers "In1.Cu" "In2.Cu")
		(hatch none 0.5)
		(connect_pads
			(clearance 0)
		)
		(min_thickness 0.25)
		(keepout
			(tracks not_allowed)
			(vias allowed)
			(pads allowed)
			(copperpour not_allowed)
			(footprints allowed)
		)
		(placement
			(enabled no)
			(sheetname "")
		)
		(fill yes
			(thermal_gap 0.5)
			(thermal_bridge_width 0.5)
			(island_removal_mode 0)
		)
		(polygon
			(pts
				(arc
					(start 26.577798 -251.921518)
					(mid 26.592677 -251.957439)
					(end 26.628598 -251.972318)
				)
				(arc
					(start 28.028138 -251.972318)
					(mid 28.064059 -251.957439)
					(end 28.078938 -251.921518)
				)
				(arc
					(start 28.078938 -251.512578)
					(mid 28.064059 -251.476657)
					(end 28.028138 -251.461778)
				)
				(arc
					(start 26.628598 -251.461778)
					(mid 26.592677 -251.476657)
					(end 26.577798 -251.512578)
				)
			)
		)
	)
	(zone
		(layers "In1.Cu" "In2.Cu")
		(hatch none 0.5)
		(connect_pads
			(clearance 0)
		)
		(min_thickness 0.25)
		(keepout
			(tracks not_allowed)
			(vias allowed)
			(pads allowed)
			(copperpour not_allowed)
			(footprints allowed)
		)
		(placement
			(enabled no)
			(sheetname "")
		)
		(fill yes
			(thermal_gap 0.5)
			(thermal_bridge_width 0.5)
			(island_removal_mode 0)
		)
		(polygon
			(pts
				(arc
					(start 19.033998 -274.02155)
					(mid 19.048877 -274.057471)
					(end 19.084798 -274.07235)
				)
				(arc
					(start 20.484338 -274.07235)
					(mid 20.520259 -274.057471)
					(end 20.535138 -274.02155)
				)
				(arc
					(start 20.535138 -273.61261)
					(mid 20.520259 -273.576689)
					(end 20.484338 -273.56181)
				)
				(arc
					(start 19.084798 -273.56181)
					(mid 19.048877 -273.576689)
					(end 19.033998 -273.61261)
				)
			)
		)
	)
	(zone
		(layers "In1.Cu" "In2.Cu")
		(hatch none 0.5)
		(connect_pads
			(clearance 0)
		)
		(min_thickness 0.25)
		(keepout
			(tracks not_allowed)
			(vias allowed)
			(pads allowed)
			(copperpour not_allowed)
			(footprints allowed)
		)
		(placement
			(enabled no)
			(sheetname "")
		)
		(fill yes
			(thermal_gap 0.5)
			(thermal_bridge_width 0.5)
			(island_removal_mode 0)
		)
		(polygon
			(pts
				(arc
					(start 440.278266 -283.371544)
					(mid 440.293145 -283.407465)
					(end 440.329066 -283.422344)
				)
				(arc
					(start 441.728606 -283.422344)
					(mid 441.764527 -283.407465)
					(end 441.779406 -283.371544)
				)
				(arc
					(start 441.779406 -282.962604)
					(mid 441.764527 -282.926683)
					(end 441.728606 -282.911804)
				)
				(arc
					(start 440.329066 -282.911804)
					(mid 440.293145 -282.926683)
					(end 440.278266 -282.962604)
				)
			)
		)
	)
	(zone
		(layers "In1.Cu" "In2.Cu")
		(hatch none 0.5)
		(connect_pads
			(clearance 0)
		)
		(min_thickness 0.25)
		(keepout
			(tracks not_allowed)
			(vias allowed)
			(pads allowed)
			(copperpour not_allowed)
			(footprints allowed)
		)
		(placement
			(enabled no)
			(sheetname "")
		)
		(fill yes
			(thermal_gap 0.5)
			(thermal_bridge_width 0.5)
			(island_removal_mode 0)
		)
		(polygon
			(pts
				(arc
					(start 277.961598 -261.271512)
					(mid 277.976477 -261.307433)
					(end 278.012398 -261.322312)
				)
				(arc
					(start 279.411938 -261.322312)
					(mid 279.447859 -261.307433)
					(end 279.462738 -261.271512)
				)
				(arc
					(start 279.462738 -260.862572)
					(mid 279.447859 -260.826651)
					(end 279.411938 -260.811772)
				)
				(arc
					(start 278.012398 -260.811772)
					(mid 277.976477 -260.826651)
					(end 277.961598 -260.862572)
				)
			)
		)
	)
	(zone
		(layers "In1.Cu" "In2.Cu")
		(hatch none 0.5)
		(connect_pads
			(clearance 0)
		)
		(min_thickness 0.25)
		(keepout
			(tracks not_allowed)
			(vias allowed)
			(pads allowed)
			(copperpour not_allowed)
			(footprints allowed)
		)
		(placement
			(enabled no)
			(sheetname "")
		)
		(fill yes
			(thermal_gap 0.5)
			(thermal_bridge_width 0.5)
			(island_removal_mode 0)
		)
		(polygon
			(pts
				(arc
					(start 14.93393 -245.971314)
					(mid 14.948809 -246.007235)
					(end 14.98473 -246.022114)
				)
				(arc
					(start 16.38427 -246.022114)
					(mid 16.420191 -246.007235)
					(end 16.43507 -245.971314)
				)
				(arc
					(start 16.43507 -245.562374)
					(mid 16.420191 -245.526453)
					(end 16.38427 -245.511574)
				)
				(arc
					(start 14.98473 -245.511574)
					(mid 14.948809 -245.526453)
					(end 14.93393 -245.562374)
				)
			)
		)
	)
	(zone
		(layers "In1.Cu" "In2.Cu")
		(hatch none 0.5)
		(connect_pads
			(clearance 0)
		)
		(min_thickness 0.25)
		(keepout
			(tracks not_allowed)
			(vias allowed)
			(pads allowed)
			(copperpour not_allowed)
			(footprints allowed)
		)
		(placement
			(enabled no)
			(sheetname "")
		)
		(fill yes
			(thermal_gap 0.5)
			(thermal_bridge_width 0.5)
			(island_removal_mode 0)
		)
		(polygon
			(pts
				(arc
					(start 26.577798 -262.121396)
					(mid 26.592677 -262.157317)
					(end 26.628598 -262.172196)
				)
				(arc
					(start 28.028138 -262.172196)
					(mid 28.064059 -262.157317)
					(end 28.078938 -262.121396)
				)
				(arc
					(start 28.078938 -261.712456)
					(mid 28.064059 -261.676535)
					(end 28.028138 -261.661656)
				)
				(arc
					(start 26.628598 -261.661656)
					(mid 26.592677 -261.676535)
					(end 26.577798 -261.712456)
				)
			)
		)
	)
	(zone
		(layers "In1.Cu" "In2.Cu")
		(hatch none 0.5)
		(connect_pads
			(clearance 0)
		)
		(min_thickness 0.25)
		(keepout
			(tracks not_allowed)
			(vias allowed)
			(pads allowed)
			(copperpour not_allowed)
			(footprints allowed)
		)
		(placement
			(enabled no)
			(sheetname "")
		)
		(fill yes
			(thermal_gap 0.5)
			(thermal_bridge_width 0.5)
			(island_removal_mode 0)
		)
		(polygon
			(pts
				(arc
					(start 56.752998 -308.021482)
					(mid 56.767877 -308.057403)
					(end 56.803798 -308.072282)
				)
				(arc
					(start 58.203338 -308.072282)
					(mid 58.239259 -308.057403)
					(end 58.254138 -308.021482)
				)
				(arc
					(start 58.254138 -307.612542)
					(mid 58.239259 -307.576621)
					(end 58.203338 -307.561742)
				)
				(arc
					(start 56.803798 -307.561742)
					(mid 56.767877 -307.576621)
					(end 56.752998 -307.612542)
				)
			)
		)
	)
	(zone
		(layers "In1.Cu" "In2.Cu")
		(hatch none 0.5)
		(connect_pads
			(clearance 0)
		)
		(min_thickness 0.25)
		(keepout
			(tracks not_allowed)
			(vias allowed)
			(pads allowed)
			(copperpour not_allowed)
			(footprints allowed)
		)
		(placement
			(enabled no)
			(sheetname "")
		)
		(fill yes
			(thermal_gap 0.5)
			(thermal_bridge_width 0.5)
			(island_removal_mode 0)
		)
		(polygon
			(pts
				(arc
					(start 421.090598 -290.171378)
					(mid 421.105477 -290.207299)
					(end 421.141398 -290.222178)
				)
				(arc
					(start 422.540938 -290.222178)
					(mid 422.576859 -290.207299)
					(end 422.591738 -290.171378)
				)
				(arc
					(start 422.591738 -289.762438)
					(mid 422.576859 -289.726517)
					(end 422.540938 -289.711638)
				)
				(arc
					(start 421.141398 -289.711638)
					(mid 421.105477 -289.726517)
					(end 421.090598 -289.762438)
				)
			)
		)
	)
	(zone
		(layers "In1.Cu" "In2.Cu")
		(hatch none 0.5)
		(connect_pads
			(clearance 0)
		)
		(min_thickness 0.25)
		(keepout
			(tracks not_allowed)
			(vias allowed)
			(pads allowed)
			(copperpour not_allowed)
			(footprints allowed)
		)
		(placement
			(enabled no)
			(sheetname "")
		)
		(fill yes
			(thermal_gap 0.5)
			(thermal_bridge_width 0.5)
			(island_removal_mode 0)
		)
		(polygon
			(pts
				(arc
					(start 34.121598 -284.221428)
					(mid 34.136477 -284.257349)
					(end 34.172398 -284.272228)
				)
				(arc
					(start 35.571938 -284.272228)
					(mid 35.607859 -284.257349)
					(end 35.622738 -284.221428)
				)
				(arc
					(start 35.622738 -283.812488)
					(mid 35.607859 -283.776567)
					(end 35.571938 -283.761688)
				)
				(arc
					(start 34.172398 -283.761688)
					(mid 34.136477 -283.776567)
					(end 34.121598 -283.812488)
				)
			)
		)
	)
	(zone
		(layers "In1.Cu" "In2.Cu")
		(hatch none 0.5)
		(connect_pads
			(clearance 0)
		)
		(min_thickness 0.25)
		(keepout
			(tracks not_allowed)
			(vias allowed)
			(pads allowed)
			(copperpour not_allowed)
			(footprints allowed)
		)
		(placement
			(enabled no)
			(sheetname "")
		)
		(fill yes
			(thermal_gap 0.5)
			(thermal_bridge_width 0.5)
			(island_removal_mode 0)
		)
		(polygon
			(pts
				(arc
					(start 285.505398 -234.071414)
					(mid 285.520277 -234.107335)
					(end 285.556198 -234.122214)
				)
				(arc
					(start 286.955738 -234.122214)
					(mid 286.991659 -234.107335)
					(end 287.006538 -234.071414)
				)
				(arc
					(start 287.006538 -233.662474)
					(mid 286.991659 -233.626553)
					(end 286.955738 -233.611674)
				)
				(arc
					(start 285.556198 -233.611674)
					(mid 285.520277 -233.626553)
					(end 285.505398 -233.662474)
				)
			)
		)
	)
	(zone
		(layers "In1.Cu" "In2.Cu")
		(hatch none 0.5)
		(connect_pads
			(clearance 0)
		)
		(min_thickness 0.25)
		(keepout
			(tracks not_allowed)
			(vias allowed)
			(pads allowed)
			(copperpour not_allowed)
			(footprints allowed)
		)
		(placement
			(enabled no)
			(sheetname "")
		)
		(fill yes
			(thermal_gap 0.5)
			(thermal_bridge_width 0.5)
			(island_removal_mode 0)
		)
		(polygon
			(pts
				(arc
					(start 64.296798 -251.921518)
					(mid 64.311677 -251.957439)
					(end 64.347598 -251.972318)
				)
				(arc
					(start 65.747138 -251.972318)
					(mid 65.783059 -251.957439)
					(end 65.797938 -251.921518)
				)
				(arc
					(start 65.797938 -251.512578)
					(mid 65.783059 -251.476657)
					(end 65.747138 -251.461778)
				)
				(arc
					(start 64.347598 -251.461778)
					(mid 64.311677 -251.476657)
					(end 64.296798 -251.512578)
				)
			)
		)
	)
	(zone
		(layers "In1.Cu" "In2.Cu")
		(hatch none 0.5)
		(connect_pads
			(clearance 0)
		)
		(min_thickness 0.25)
		(keepout
			(tracks not_allowed)
			(vias allowed)
			(pads allowed)
			(copperpour not_allowed)
			(footprints allowed)
		)
		(placement
			(enabled no)
			(sheetname "")
		)
		(fill yes
			(thermal_gap 0.5)
			(thermal_bridge_width 0.5)
			(island_removal_mode 0)
		)
		(polygon
			(pts
				(arc
					(start 188.23813 -247.671336)
					(mid 188.253009 -247.707257)
					(end 188.28893 -247.722136)
				)
				(arc
					(start 189.68847 -247.722136)
					(mid 189.724391 -247.707257)
					(end 189.73927 -247.671336)
				)
				(arc
					(start 189.73927 -247.262396)
					(mid 189.724391 -247.226475)
					(end 189.68847 -247.211596)
				)
				(arc
					(start 188.28893 -247.211596)
					(mid 188.253009 -247.226475)
					(end 188.23813 -247.262396)
				)
			)
		)
	)
	(zone
		(layers "In1.Cu" "In2.Cu")
		(hatch none 0.5)
		(connect_pads
			(clearance 0)
		)
		(min_thickness 0.25)
		(keepout
			(tracks not_allowed)
			(vias allowed)
			(pads allowed)
			(copperpour not_allowed)
			(footprints allowed)
		)
		(placement
			(enabled no)
			(sheetname "")
		)
		(fill yes
			(thermal_gap 0.5)
			(thermal_bridge_width 0.5)
			(island_removal_mode 0)
		)
		(polygon
			(pts
				(arc
					(start 184.794398 -309.721504)
					(mid 184.809277 -309.757425)
					(end 184.845198 -309.772304)
				)
				(arc
					(start 186.244738 -309.772304)
					(mid 186.280659 -309.757425)
					(end 186.295538 -309.721504)
				)
				(arc
					(start 186.295538 -309.312564)
					(mid 186.280659 -309.276643)
					(end 186.244738 -309.261764)
				)
				(arc
					(start 184.845198 -309.261764)
					(mid 184.809277 -309.276643)
					(end 184.794398 -309.312564)
				)
			)
		)
	)
	(zone
		(layers "In1.Cu" "In2.Cu")
		(hatch none 0.5)
		(connect_pads
			(clearance 0)
		)
		(min_thickness 0.25)
		(keepout
			(tracks not_allowed)
			(vias allowed)
			(pads allowed)
			(copperpour not_allowed)
			(footprints allowed)
		)
		(placement
			(enabled no)
			(sheetname "")
		)
		(fill yes
			(thermal_gap 0.5)
			(thermal_bridge_width 0.5)
			(island_removal_mode 0)
		)
		(polygon
			(pts
				(arc
					(start 413.546798 -244.271292)
					(mid 413.561677 -244.307213)
					(end 413.597598 -244.322092)
				)
				(arc
					(start 414.997138 -244.322092)
					(mid 415.033059 -244.307213)
					(end 415.047938 -244.271292)
				)
				(arc
					(start 415.047938 -243.862352)
					(mid 415.033059 -243.826431)
					(end 414.997138 -243.811552)
				)
				(arc
					(start 413.597598 -243.811552)
					(mid 413.561677 -243.826431)
					(end 413.546798 -243.862352)
				)
			)
		)
	)
	(zone
		(layers "In1.Cu" "In2.Cu")
		(hatch none 0.5)
		(connect_pads
			(clearance 0)
		)
		(min_thickness 0.25)
		(keepout
			(tracks not_allowed)
			(vias allowed)
			(pads allowed)
			(copperpour not_allowed)
			(footprints allowed)
		)
		(placement
			(enabled no)
			(sheetname "")
		)
		(fill yes
			(thermal_gap 0.5)
			(thermal_bridge_width 0.5)
			(island_removal_mode 0)
		)
		(polygon
			(pts
				(arc
					(start 451.265798 -288.471356)
					(mid 451.280677 -288.507277)
					(end 451.316598 -288.522156)
				)
				(arc
					(start 452.716138 -288.522156)
					(mid 452.752059 -288.507277)
					(end 452.766938 -288.471356)
				)
				(arc
					(start 452.766938 -288.062416)
					(mid 452.752059 -288.026495)
					(end 452.716138 -288.011616)
				)
				(arc
					(start 451.316598 -288.011616)
					(mid 451.280677 -288.026495)
					(end 451.265798 -288.062416)
				)
			)
		)
	)
	(zone
		(layers "In1.Cu" "In2.Cu")
		(hatch none 0.5)
		(connect_pads
			(clearance 0)
		)
		(min_thickness 0.25)
		(keepout
			(tracks not_allowed)
			(vias allowed)
			(pads allowed)
			(copperpour not_allowed)
			(footprints allowed)
		)
		(placement
			(enabled no)
			(sheetname "")
		)
		(fill yes
			(thermal_gap 0.5)
			(thermal_bridge_width 0.5)
			(island_removal_mode 0)
		)
		(polygon
			(pts
				(arc
					(start 440.278266 -248.521474)
					(mid 440.293145 -248.557395)
					(end 440.329066 -248.572274)
				)
				(arc
					(start 441.728606 -248.572274)
					(mid 441.764527 -248.557395)
					(end 441.779406 -248.521474)
				)
				(arc
					(start 441.779406 -248.112534)
					(mid 441.764527 -248.076613)
					(end 441.728606 -248.061734)
				)
				(arc
					(start 440.329066 -248.061734)
					(mid 440.293145 -248.076613)
					(end 440.278266 -248.112534)
				)
			)
		)
	)
	(zone
		(layers "In1.Cu" "In2.Cu")
		(hatch none 0.5)
		(connect_pads
			(clearance 0)
		)
		(min_thickness 0.25)
		(keepout
			(tracks not_allowed)
			(vias allowed)
			(pads allowed)
			(copperpour not_allowed)
			(footprints allowed)
		)
		(placement
			(enabled no)
			(sheetname "")
		)
		(fill yes
			(thermal_gap 0.5)
			(thermal_bridge_width 0.5)
			(island_removal_mode 0)
		)
		(polygon
			(pts
				(arc
					(start 207.425798 -285.92145)
					(mid 207.440677 -285.957371)
					(end 207.476598 -285.97225)
				)
				(arc
					(start 208.876138 -285.97225)
					(mid 208.912059 -285.957371)
					(end 208.926938 -285.92145)
				)
				(arc
					(start 208.926938 -285.51251)
					(mid 208.912059 -285.476589)
					(end 208.876138 -285.46171)
				)
				(arc
					(start 207.476598 -285.46171)
					(mid 207.440677 -285.476589)
					(end 207.425798 -285.51251)
				)
			)
		)
	)
	(zone
		(layers "In1.Cu" "In2.Cu")
		(hatch none 0.5)
		(connect_pads
			(clearance 0)
		)
		(min_thickness 0.25)
		(keepout
			(tracks not_allowed)
			(vias allowed)
			(pads allowed)
			(copperpour not_allowed)
			(footprints allowed)
		)
		(placement
			(enabled no)
			(sheetname "")
		)
		(fill yes
			(thermal_gap 0.5)
			(thermal_bridge_width 0.5)
			(island_removal_mode 0)
		)
		(polygon
			(pts
				(arc
					(start 207.425798 -291.021516)
					(mid 207.440677 -291.057437)
					(end 207.476598 -291.072316)
				)
				(arc
					(start 208.876138 -291.072316)
					(mid 208.912059 -291.057437)
					(end 208.926938 -291.021516)
				)
				(arc
					(start 208.926938 -290.612576)
					(mid 208.912059 -290.576655)
					(end 208.876138 -290.561776)
				)
				(arc
					(start 207.476598 -290.561776)
					(mid 207.440677 -290.576655)
					(end 207.425798 -290.612576)
				)
			)
		)
	)
	(zone
		(layers "In1.Cu" "In2.Cu")
		(hatch none 0.5)
		(connect_pads
			(clearance 0)
		)
		(min_thickness 0.25)
		(keepout
			(tracks not_allowed)
			(vias allowed)
			(pads allowed)
			(copperpour not_allowed)
			(footprints allowed)
		)
		(placement
			(enabled no)
			(sheetname "")
		)
		(fill yes
			(thermal_gap 0.5)
			(thermal_bridge_width 0.5)
			(island_removal_mode 0)
		)
		(polygon
			(pts
				(arc
					(start 210.86953 -217.071448)
					(mid 210.884409 -217.107369)
					(end 210.92033 -217.122248)
				)
				(arc
					(start 212.31987 -217.122248)
					(mid 212.355791 -217.107369)
					(end 212.37067 -217.071448)
				)
				(arc
					(start 212.37067 -216.662508)
					(mid 212.355791 -216.626587)
					(end 212.31987 -216.611708)
				)
				(arc
					(start 210.92033 -216.611708)
					(mid 210.884409 -216.626587)
					(end 210.86953 -216.662508)
				)
			)
		)
	)
	(zone
		(layers "In1.Cu" "In2.Cu")
		(hatch none 0.5)
		(connect_pads
			(clearance 0)
		)
		(min_thickness 0.25)
		(keepout
			(tracks not_allowed)
			(vias allowed)
			(pads allowed)
			(copperpour not_allowed)
			(footprints allowed)
		)
		(placement
			(enabled no)
			(sheetname "")
		)
		(fill yes
			(thermal_gap 0.5)
			(thermal_bridge_width 0.5)
			(island_removal_mode 0)
		)
		(polygon
			(pts
				(arc
					(start 45.10913 -211.971382)
					(mid 45.124009 -212.007303)
					(end 45.15993 -212.022182)
				)
				(arc
					(start 46.55947 -212.022182)
					(mid 46.595391 -212.007303)
					(end 46.61027 -211.971382)
				)
				(arc
					(start 46.61027 -211.562442)
					(mid 46.595391 -211.526521)
					(end 46.55947 -211.511642)
				)
				(arc
					(start 45.15993 -211.511642)
					(mid 45.124009 -211.526521)
					(end 45.10913 -211.562442)
				)
			)
		)
	)
	(zone
		(layers "In1.Cu" "In2.Cu")
		(hatch none 0.5)
		(connect_pads
			(clearance 0)
		)
		(min_thickness 0.25)
		(keepout
			(tracks not_allowed)
			(vias allowed)
			(pads allowed)
			(copperpour not_allowed)
			(footprints allowed)
		)
		(placement
			(enabled no)
			(sheetname "")
		)
		(fill yes
			(thermal_gap 0.5)
			(thermal_bridge_width 0.5)
			(island_removal_mode 0)
		)
		(polygon
			(pts
				(arc
					(start 293.049198 -228.121464)
					(mid 293.064077 -228.157385)
					(end 293.099998 -228.172264)
				)
				(arc
					(start 294.499538 -228.172264)
					(mid 294.535459 -228.157385)
					(end 294.550338 -228.121464)
				)
				(arc
					(start 294.550338 -227.712524)
					(mid 294.535459 -227.676603)
					(end 294.499538 -227.661724)
				)
				(arc
					(start 293.099998 -227.661724)
					(mid 293.064077 -227.676603)
					(end 293.049198 -227.712524)
				)
			)
		)
	)
	(zone
		(layers "In1.Cu" "In2.Cu")
		(hatch none 0.5)
		(connect_pads
			(clearance 0)
		)
		(min_thickness 0.25)
		(keepout
			(tracks not_allowed)
			(vias allowed)
			(pads allowed)
			(copperpour not_allowed)
			(footprints allowed)
		)
		(placement
			(enabled no)
			(sheetname "")
		)
		(fill yes
			(thermal_gap 0.5)
			(thermal_bridge_width 0.5)
			(island_removal_mode 0)
		)
		(polygon
			(pts
				(arc
					(start 293.049198 -301.221394)
					(mid 293.064077 -301.257315)
					(end 293.099998 -301.272194)
				)
				(arc
					(start 294.499538 -301.272194)
					(mid 294.535459 -301.257315)
					(end 294.550338 -301.221394)
				)
				(arc
					(start 294.550338 -300.812454)
					(mid 294.535459 -300.776533)
					(end 294.499538 -300.761654)
				)
				(arc
					(start 293.099998 -300.761654)
					(mid 293.064077 -300.776533)
					(end 293.049198 -300.812454)
				)
			)
		)
	)
	(zone
		(layers "In1.Cu" "In2.Cu")
		(hatch none 0.5)
		(connect_pads
			(clearance 0)
		)
		(min_thickness 0.25)
		(keepout
			(tracks not_allowed)
			(vias allowed)
			(pads allowed)
			(copperpour not_allowed)
			(footprints allowed)
		)
		(placement
			(enabled no)
			(sheetname "")
		)
		(fill yes
			(thermal_gap 0.5)
			(thermal_bridge_width 0.5)
			(island_removal_mode 0)
		)
		(polygon
			(pts
				(arc
					(start 270.417798 -200.071482)
					(mid 270.432677 -200.107403)
					(end 270.468598 -200.122282)
				)
				(arc
					(start 271.868138 -200.122282)
					(mid 271.904059 -200.107403)
					(end 271.918938 -200.071482)
				)
				(arc
					(start 271.918938 -199.662542)
					(mid 271.904059 -199.626621)
					(end 271.868138 -199.611742)
				)
				(arc
					(start 270.468598 -199.611742)
					(mid 270.432677 -199.626621)
					(end 270.417798 -199.662542)
				)
			)
		)
	)
	(zone
		(layers "In1.Cu" "In2.Cu")
		(hatch none 0.5)
		(connect_pads
			(clearance 0)
		)
		(min_thickness 0.25)
		(keepout
			(tracks not_allowed)
			(vias allowed)
			(pads allowed)
			(copperpour not_allowed)
			(footprints allowed)
		)
		(placement
			(enabled no)
			(sheetname "")
		)
		(fill yes
			(thermal_gap 0.5)
			(thermal_bridge_width 0.5)
			(island_removal_mode 0)
		)
		(polygon
			(pts
				(arc
					(start 447.822066 -220.471492)
					(mid 447.836945 -220.507413)
					(end 447.872866 -220.522292)
				)
				(arc
					(start 449.272406 -220.522292)
					(mid 449.308327 -220.507413)
					(end 449.323206 -220.471492)
				)
				(arc
					(start 449.323206 -220.062552)
					(mid 449.308327 -220.026631)
					(end 449.272406 -220.011752)
				)
				(arc
					(start 447.872866 -220.011752)
					(mid 447.836945 -220.026631)
					(end 447.822066 -220.062552)
				)
			)
		)
	)
	(zone
		(layers "In1.Cu" "In2.Cu")
		(hatch none 0.5)
		(connect_pads
			(clearance 0)
		)
		(min_thickness 0.25)
		(keepout
			(tracks not_allowed)
			(vias allowed)
			(pads allowed)
			(copperpour not_allowed)
			(footprints allowed)
		)
		(placement
			(enabled no)
			(sheetname "")
		)
		(fill yes
			(thermal_gap 0.5)
			(thermal_bridge_width 0.5)
			(island_removal_mode 0)
		)
		(polygon
			(pts
				(arc
					(start 207.425798 -260.421374)
					(mid 207.440677 -260.457295)
					(end 207.476598 -260.472174)
				)
				(arc
					(start 208.876138 -260.472174)
					(mid 208.912059 -260.457295)
					(end 208.926938 -260.421374)
				)
				(arc
					(start 208.926938 -260.012434)
					(mid 208.912059 -259.976513)
					(end 208.876138 -259.961634)
				)
				(arc
					(start 207.476598 -259.961634)
					(mid 207.440677 -259.976513)
					(end 207.425798 -260.012434)
				)
			)
		)
	)
	(zone
		(layers "In1.Cu" "In2.Cu")
		(hatch none 0.5)
		(connect_pads
			(clearance 0)
		)
		(min_thickness 0.25)
		(keepout
			(tracks not_allowed)
			(vias allowed)
			(pads allowed)
			(copperpour not_allowed)
			(footprints allowed)
		)
		(placement
			(enabled no)
			(sheetname "")
		)
		(fill yes
			(thermal_gap 0.5)
			(thermal_bridge_width 0.5)
			(island_removal_mode 0)
		)
		(polygon
			(pts
				(arc
					(start 49.209198 -306.32146)
					(mid 49.224077 -306.357381)
					(end 49.259998 -306.37226)
				)
				(arc
					(start 50.659538 -306.37226)
					(mid 50.695459 -306.357381)
					(end 50.710338 -306.32146)
				)
				(arc
					(start 50.710338 -305.91252)
					(mid 50.695459 -305.876599)
					(end 50.659538 -305.86172)
				)
				(arc
					(start 49.259998 -305.86172)
					(mid 49.224077 -305.876599)
					(end 49.209198 -305.91252)
				)
			)
		)
	)
	(zone
		(layers "In1.Cu" "In2.Cu")
		(hatch none 0.5)
		(connect_pads
			(clearance 0)
		)
		(min_thickness 0.25)
		(keepout
			(tracks not_allowed)
			(vias allowed)
			(pads allowed)
			(copperpour not_allowed)
			(footprints allowed)
		)
		(placement
			(enabled no)
			(sheetname "")
		)
		(fill yes
			(thermal_gap 0.5)
			(thermal_bridge_width 0.5)
			(island_removal_mode 0)
		)
		(polygon
			(pts
				(arc
					(start 297.149266 -209.421476)
					(mid 297.164145 -209.457397)
					(end 297.200066 -209.472276)
				)
				(arc
					(start 298.599606 -209.472276)
					(mid 298.635527 -209.457397)
					(end 298.650406 -209.421476)
				)
				(arc
					(start 298.650406 -209.012536)
					(mid 298.635527 -208.976615)
					(end 298.599606 -208.961736)
				)
				(arc
					(start 297.200066 -208.961736)
					(mid 297.164145 -208.976615)
					(end 297.149266 -209.012536)
				)
			)
		)
	)
	(zone
		(layers "In1.Cu" "In2.Cu")
		(hatch none 0.5)
		(connect_pads
			(clearance 0)
		)
		(min_thickness 0.25)
		(keepout
			(tracks not_allowed)
			(vias allowed)
			(pads allowed)
			(copperpour not_allowed)
			(footprints allowed)
		)
		(placement
			(enabled no)
			(sheetname "")
		)
		(fill yes
			(thermal_gap 0.5)
			(thermal_bridge_width 0.5)
			(island_removal_mode 0)
		)
		(polygon
			(pts
				(arc
					(start 173.15053 -279.121362)
					(mid 173.165409 -279.157283)
					(end 173.20133 -279.172162)
				)
				(arc
					(start 174.60087 -279.172162)
					(mid 174.636791 -279.157283)
					(end 174.65167 -279.121362)
				)
				(arc
					(start 174.65167 -278.712422)
					(mid 174.636791 -278.676501)
					(end 174.60087 -278.661622)
				)
				(arc
					(start 173.20133 -278.661622)
					(mid 173.165409 -278.676501)
					(end 173.15053 -278.712422)
				)
			)
		)
	)
	(zone
		(layers "In1.Cu" "In2.Cu")
		(hatch none 0.5)
		(connect_pads
			(clearance 0)
		)
		(min_thickness 0.25)
		(keepout
			(tracks not_allowed)
			(vias allowed)
			(pads allowed)
			(copperpour not_allowed)
			(footprints allowed)
		)
		(placement
			(enabled no)
			(sheetname "")
		)
		(fill yes
			(thermal_gap 0.5)
			(thermal_bridge_width 0.5)
			(island_removal_mode 0)
		)
		(polygon
			(pts
				(arc
					(start 49.209198 -309.721504)
					(mid 49.224077 -309.757425)
					(end 49.259998 -309.772304)
				)
				(arc
					(start 50.659538 -309.772304)
					(mid 50.695459 -309.757425)
					(end 50.710338 -309.721504)
				)
				(arc
					(start 50.710338 -309.312564)
					(mid 50.695459 -309.276643)
					(end 50.659538 -309.261764)
				)
				(arc
					(start 49.259998 -309.261764)
					(mid 49.224077 -309.276643)
					(end 49.209198 -309.312564)
				)
			)
		)
	)
	(zone
		(layers "In1.Cu" "In2.Cu")
		(hatch none 0.5)
		(connect_pads
			(clearance 0)
		)
		(min_thickness 0.25)
		(keepout
			(tracks not_allowed)
			(vias allowed)
			(pads allowed)
			(copperpour not_allowed)
			(footprints allowed)
		)
		(placement
			(enabled no)
			(sheetname "")
		)
		(fill yes
			(thermal_gap 0.5)
			(thermal_bridge_width 0.5)
			(island_removal_mode 0)
		)
		(polygon
			(pts
				(arc
					(start 293.049198 -316.521338)
					(mid 293.064077 -316.557259)
					(end 293.099998 -316.572138)
				)
				(arc
					(start 294.499538 -316.572138)
					(mid 294.535459 -316.557259)
					(end 294.550338 -316.521338)
				)
				(arc
					(start 294.550338 -316.112398)
					(mid 294.535459 -316.076477)
					(end 294.499538 -316.061598)
				)
				(arc
					(start 293.099998 -316.061598)
					(mid 293.064077 -316.076477)
					(end 293.049198 -316.112398)
				)
			)
		)
	)
	(zone
		(layers "In1.Cu" "In2.Cu")
		(hatch none 0.5)
		(connect_pads
			(clearance 0)
		)
		(min_thickness 0.25)
		(keepout
			(tracks not_allowed)
			(vias allowed)
			(pads allowed)
			(copperpour not_allowed)
			(footprints allowed)
		)
		(placement
			(enabled no)
			(sheetname "")
		)
		(fill yes
			(thermal_gap 0.5)
			(thermal_bridge_width 0.5)
			(island_removal_mode 0)
		)
		(polygon
			(pts
				(arc
					(start 52.65293 -288.471356)
					(mid 52.667809 -288.507277)
					(end 52.70373 -288.522156)
				)
				(arc
					(start 54.10327 -288.522156)
					(mid 54.139191 -288.507277)
					(end 54.15407 -288.471356)
				)
				(arc
					(start 54.15407 -288.062416)
					(mid 54.139191 -288.026495)
					(end 54.10327 -288.011616)
				)
				(arc
					(start 52.70373 -288.011616)
					(mid 52.667809 -288.026495)
					(end 52.65293 -288.062416)
				)
			)
		)
	)
	(zone
		(layers "In1.Cu" "In2.Cu")
		(hatch none 0.5)
		(connect_pads
			(clearance 0)
		)
		(min_thickness 0.25)
		(keepout
			(tracks not_allowed)
			(vias allowed)
			(pads allowed)
			(copperpour not_allowed)
			(footprints allowed)
		)
		(placement
			(enabled no)
			(sheetname "")
		)
		(fill yes
			(thermal_gap 0.5)
			(thermal_bridge_width 0.5)
			(island_removal_mode 0)
		)
		(polygon
			(pts
				(arc
					(start 255.330198 -307.171344)
					(mid 255.345077 -307.207265)
					(end 255.380998 -307.222144)
				)
				(arc
					(start 256.780538 -307.222144)
					(mid 256.816459 -307.207265)
					(end 256.831338 -307.171344)
				)
				(arc
					(start 256.831338 -306.762404)
					(mid 256.816459 -306.726483)
					(end 256.780538 -306.711604)
				)
				(arc
					(start 255.380998 -306.711604)
					(mid 255.345077 -306.726483)
					(end 255.330198 -306.762404)
				)
			)
		)
	)
	(zone
		(layers "In1.Cu" "In2.Cu")
		(hatch none 0.5)
		(connect_pads
			(clearance 0)
		)
		(min_thickness 0.25)
		(keepout
			(tracks not_allowed)
			(vias allowed)
			(pads allowed)
			(copperpour not_allowed)
			(footprints allowed)
		)
		(placement
			(enabled no)
			(sheetname "")
		)
		(fill yes
			(thermal_gap 0.5)
			(thermal_bridge_width 0.5)
			(island_removal_mode 0)
		)
		(polygon
			(pts
				(arc
					(start 447.822066 -197.521322)
					(mid 447.836945 -197.557243)
					(end 447.872866 -197.572122)
				)
				(arc
					(start 449.272406 -197.572122)
					(mid 449.308327 -197.557243)
					(end 449.323206 -197.521322)
				)
				(arc
					(start 449.323206 -197.112382)
					(mid 449.308327 -197.076461)
					(end 449.272406 -197.061582)
				)
				(arc
					(start 447.872866 -197.061582)
					(mid 447.836945 -197.076461)
					(end 447.822066 -197.112382)
				)
			)
		)
	)
	(zone
		(layers "In1.Cu" "In2.Cu")
		(hatch none 0.5)
		(connect_pads
			(clearance 0)
		)
		(min_thickness 0.25)
		(keepout
			(tracks not_allowed)
			(vias allowed)
			(pads allowed)
			(copperpour not_allowed)
			(footprints allowed)
		)
		(placement
			(enabled no)
			(sheetname "")
		)
		(fill yes
			(thermal_gap 0.5)
			(thermal_bridge_width 0.5)
			(island_removal_mode 0)
		)
		(polygon
			(pts
				(arc
					(start 304.693066 -234.921298)
					(mid 304.707945 -234.957219)
					(end 304.743866 -234.972098)
				)
				(arc
					(start 306.143406 -234.972098)
					(mid 306.179327 -234.957219)
					(end 306.194206 -234.921298)
				)
				(arc
					(start 306.194206 -234.512358)
					(mid 306.179327 -234.476437)
					(end 306.143406 -234.461558)
				)
				(arc
					(start 304.743866 -234.461558)
					(mid 304.707945 -234.476437)
					(end 304.693066 -234.512358)
				)
			)
		)
	)
	(zone
		(layers "In1.Cu" "In2.Cu")
		(hatch none 0.5)
		(connect_pads
			(clearance 0)
		)
		(min_thickness 0.25)
		(keepout
			(tracks not_allowed)
			(vias allowed)
			(pads allowed)
			(copperpour not_allowed)
			(footprints allowed)
		)
		(placement
			(enabled no)
			(sheetname "")
		)
		(fill yes
			(thermal_gap 0.5)
			(thermal_bridge_width 0.5)
			(island_removal_mode 0)
		)
		(polygon
			(pts
				(arc
					(start 274.517866 -245.12143)
					(mid 274.532745 -245.157351)
					(end 274.568666 -245.17223)
				)
				(arc
					(start 275.968206 -245.17223)
					(mid 276.004127 -245.157351)
					(end 276.019006 -245.12143)
				)
				(arc
					(start 276.019006 -244.71249)
					(mid 276.004127 -244.676569)
					(end 275.968206 -244.66169)
				)
				(arc
					(start 274.568666 -244.66169)
					(mid 274.532745 -244.676569)
					(end 274.517866 -244.71249)
				)
			)
		)
	)
	(zone
		(layers "In1.Cu" "In2.Cu")
		(hatch none 0.5)
		(connect_pads
			(clearance 0)
		)
		(min_thickness 0.25)
		(keepout
			(tracks not_allowed)
			(vias allowed)
			(pads allowed)
			(copperpour not_allowed)
			(footprints allowed)
		)
		(placement
			(enabled no)
			(sheetname "")
		)
		(fill yes
			(thermal_gap 0.5)
			(thermal_bridge_width 0.5)
			(island_removal_mode 0)
		)
		(polygon
			(pts
				(arc
					(start 425.190666 -281.671522)
					(mid 425.205545 -281.707443)
					(end 425.241466 -281.722322)
				)
				(arc
					(start 426.641006 -281.722322)
					(mid 426.676927 -281.707443)
					(end 426.691806 -281.671522)
				)
				(arc
					(start 426.691806 -281.262582)
					(mid 426.676927 -281.226661)
					(end 426.641006 -281.211782)
				)
				(arc
					(start 425.241466 -281.211782)
					(mid 425.205545 -281.226661)
					(end 425.190666 -281.262582)
				)
			)
		)
	)
	(zone
		(layers "In1.Cu" "In2.Cu")
		(hatch none 0.5)
		(connect_pads
			(clearance 0)
		)
		(min_thickness 0.25)
		(keepout
			(tracks not_allowed)
			(vias allowed)
			(pads allowed)
			(copperpour not_allowed)
			(footprints allowed)
		)
		(placement
			(enabled no)
			(sheetname "")
		)
		(fill yes
			(thermal_gap 0.5)
			(thermal_bridge_width 0.5)
			(island_removal_mode 0)
		)
		(polygon
			(pts
				(arc
					(start 158.06293 -230.67137)
					(mid 158.077809 -230.707291)
					(end 158.11373 -230.72217)
				)
				(arc
					(start 159.51327 -230.72217)
					(mid 159.549191 -230.707291)
					(end 159.56407 -230.67137)
				)
				(arc
					(start 159.56407 -230.26243)
					(mid 159.549191 -230.226509)
					(end 159.51327 -230.21163)
				)
				(arc
					(start 158.11373 -230.21163)
					(mid 158.077809 -230.226509)
					(end 158.06293 -230.26243)
				)
			)
		)
	)
	(zone
		(layers "In1.Cu" "In2.Cu")
		(hatch none 0.5)
		(connect_pads
			(clearance 0)
		)
		(min_thickness 0.25)
		(keepout
			(tracks not_allowed)
			(vias allowed)
			(pads allowed)
			(copperpour not_allowed)
			(footprints allowed)
		)
		(placement
			(enabled no)
			(sheetname "")
		)
		(fill yes
			(thermal_gap 0.5)
			(thermal_bridge_width 0.5)
			(island_removal_mode 0)
		)
		(polygon
			(pts
				(arc
					(start 451.265798 -294.421306)
					(mid 451.280677 -294.457227)
					(end 451.316598 -294.472106)
				)
				(arc
					(start 452.716138 -294.472106)
					(mid 452.752059 -294.457227)
					(end 452.766938 -294.421306)
				)
				(arc
					(start 452.766938 -294.012366)
					(mid 452.752059 -293.976445)
					(end 452.716138 -293.961566)
				)
				(arc
					(start 451.316598 -293.961566)
					(mid 451.280677 -293.976445)
					(end 451.265798 -294.012366)
				)
			)
		)
	)
	(zone
		(layers "In1.Cu" "In2.Cu")
		(hatch none 0.5)
		(connect_pads
			(clearance 0)
		)
		(min_thickness 0.25)
		(keepout
			(tracks not_allowed)
			(vias allowed)
			(pads allowed)
			(copperpour not_allowed)
			(footprints allowed)
		)
		(placement
			(enabled no)
			(sheetname "")
		)
		(fill yes
			(thermal_gap 0.5)
			(thermal_bridge_width 0.5)
			(island_removal_mode 0)
		)
		(polygon
			(pts
				(arc
					(start 455.365866 -309.721504)
					(mid 455.380745 -309.757425)
					(end 455.416666 -309.772304)
				)
				(arc
					(start 456.816206 -309.772304)
					(mid 456.852127 -309.757425)
					(end 456.867006 -309.721504)
				)
				(arc
					(start 456.867006 -309.312564)
					(mid 456.852127 -309.276643)
					(end 456.816206 -309.261764)
				)
				(arc
					(start 455.416666 -309.261764)
					(mid 455.380745 -309.276643)
					(end 455.365866 -309.312564)
				)
			)
		)
	)
	(zone
		(layers "In1.Cu" "In2.Cu")
		(hatch none 0.5)
		(connect_pads
			(clearance 0)
		)
		(min_thickness 0.25)
		(keepout
			(tracks not_allowed)
			(vias allowed)
			(pads allowed)
			(copperpour not_allowed)
			(footprints allowed)
		)
		(placement
			(enabled no)
			(sheetname "")
		)
		(fill yes
			(thermal_gap 0.5)
			(thermal_bridge_width 0.5)
			(island_removal_mode 0)
		)
		(polygon
			(pts
				(arc
					(start 214.969598 -265.52144)
					(mid 214.984477 -265.557361)
					(end 215.020398 -265.57224)
				)
				(arc
					(start 216.419938 -265.57224)
					(mid 216.455859 -265.557361)
					(end 216.470738 -265.52144)
				)
				(arc
					(start 216.470738 -265.1125)
					(mid 216.455859 -265.076579)
					(end 216.419938 -265.0617)
				)
				(arc
					(start 215.020398 -265.0617)
					(mid 214.984477 -265.076579)
					(end 214.969598 -265.1125)
				)
			)
		)
	)
	(zone
		(layers "In1.Cu" "In2.Cu")
		(hatch none 0.5)
		(connect_pads
			(clearance 0)
		)
		(min_thickness 0.25)
		(keepout
			(tracks not_allowed)
			(vias allowed)
			(pads allowed)
			(copperpour not_allowed)
			(footprints allowed)
		)
		(placement
			(enabled no)
			(sheetname "")
		)
		(fill yes
			(thermal_gap 0.5)
			(thermal_bridge_width 0.5)
			(island_removal_mode 0)
		)
		(polygon
			(pts
				(arc
					(start 262.873998 -228.971348)
					(mid 262.888877 -229.007269)
					(end 262.924798 -229.022148)
				)
				(arc
					(start 264.324338 -229.022148)
					(mid 264.360259 -229.007269)
					(end 264.375138 -228.971348)
				)
				(arc
					(start 264.375138 -228.562408)
					(mid 264.360259 -228.526487)
					(end 264.324338 -228.511608)
				)
				(arc
					(start 262.924798 -228.511608)
					(mid 262.888877 -228.526487)
					(end 262.873998 -228.562408)
				)
			)
		)
	)
	(zone
		(layers "In1.Cu" "In2.Cu")
		(hatch none 0.5)
		(connect_pads
			(clearance 0)
		)
		(min_thickness 0.25)
		(keepout
			(tracks not_allowed)
			(vias allowed)
			(pads allowed)
			(copperpour not_allowed)
			(footprints allowed)
		)
		(placement
			(enabled no)
			(sheetname "")
		)
		(fill yes
			(thermal_gap 0.5)
			(thermal_bridge_width 0.5)
			(island_removal_mode 0)
		)
		(polygon
			(pts
				(arc
					(start 192.338198 -291.021516)
					(mid 192.353077 -291.057437)
					(end 192.388998 -291.072316)
				)
				(arc
					(start 193.788538 -291.072316)
					(mid 193.824459 -291.057437)
					(end 193.839338 -291.021516)
				)
				(arc
					(start 193.839338 -290.612576)
					(mid 193.824459 -290.576655)
					(end 193.788538 -290.561776)
				)
				(arc
					(start 192.388998 -290.561776)
					(mid 192.353077 -290.576655)
					(end 192.338198 -290.612576)
				)
			)
		)
	)
	(zone
		(layers "In1.Cu" "In2.Cu")
		(hatch none 0.5)
		(connect_pads
			(clearance 0)
		)
		(min_thickness 0.25)
		(keepout
			(tracks not_allowed)
			(vias allowed)
			(pads allowed)
			(copperpour not_allowed)
			(footprints allowed)
		)
		(placement
			(enabled no)
			(sheetname "")
		)
		(fill yes
			(thermal_gap 0.5)
			(thermal_bridge_width 0.5)
			(island_removal_mode 0)
		)
		(polygon
			(pts
				(arc
					(start 177.250598 -306.32146)
					(mid 177.265477 -306.357381)
					(end 177.301398 -306.37226)
				)
				(arc
					(start 178.700938 -306.37226)
					(mid 178.736859 -306.357381)
					(end 178.751738 -306.32146)
				)
				(arc
					(start 178.751738 -305.91252)
					(mid 178.736859 -305.876599)
					(end 178.700938 -305.86172)
				)
				(arc
					(start 177.301398 -305.86172)
					(mid 177.265477 -305.876599)
					(end 177.250598 -305.91252)
				)
			)
		)
	)
	(zone
		(layers "In1.Cu" "In2.Cu")
		(hatch none 0.5)
		(connect_pads
			(clearance 0)
		)
		(min_thickness 0.25)
		(keepout
			(tracks not_allowed)
			(vias allowed)
			(pads allowed)
			(copperpour not_allowed)
			(footprints allowed)
		)
		(placement
			(enabled no)
			(sheetname "")
		)
		(fill yes
			(thermal_gap 0.5)
			(thermal_bridge_width 0.5)
			(island_removal_mode 0)
		)
		(polygon
			(pts
				(arc
					(start 300.592998 -271.47139)
					(mid 300.607877 -271.507311)
					(end 300.643798 -271.52219)
				)
				(arc
					(start 302.043338 -271.52219)
					(mid 302.079259 -271.507311)
					(end 302.094138 -271.47139)
				)
				(arc
					(start 302.094138 -271.06245)
					(mid 302.079259 -271.026529)
					(end 302.043338 -271.01165)
				)
				(arc
					(start 300.643798 -271.01165)
					(mid 300.607877 -271.026529)
					(end 300.592998 -271.06245)
				)
			)
		)
	)
	(zone
		(layers "In1.Cu" "In2.Cu")
		(hatch none 0.5)
		(connect_pads
			(clearance 0)
		)
		(min_thickness 0.25)
		(keepout
			(tracks not_allowed)
			(vias allowed)
			(pads allowed)
			(copperpour not_allowed)
			(footprints allowed)
		)
		(placement
			(enabled no)
			(sheetname "")
		)
		(fill yes
			(thermal_gap 0.5)
			(thermal_bridge_width 0.5)
			(island_removal_mode 0)
		)
		(polygon
			(pts
				(arc
					(start 270.417798 -301.221394)
					(mid 270.432677 -301.257315)
					(end 270.468598 -301.272194)
				)
				(arc
					(start 271.868138 -301.272194)
					(mid 271.904059 -301.257315)
					(end 271.918938 -301.221394)
				)
				(arc
					(start 271.918938 -300.812454)
					(mid 271.904059 -300.776533)
					(end 271.868138 -300.761654)
				)
				(arc
					(start 270.468598 -300.761654)
					(mid 270.432677 -300.776533)
					(end 270.417798 -300.812454)
				)
			)
		)
	)
	(zone
		(layers "In1.Cu" "In2.Cu")
		(hatch none 0.5)
		(connect_pads
			(clearance 0)
		)
		(min_thickness 0.25)
		(keepout
			(tracks not_allowed)
			(vias allowed)
			(pads allowed)
			(copperpour not_allowed)
			(footprints allowed)
		)
		(placement
			(enabled no)
			(sheetname "")
		)
		(fill yes
			(thermal_gap 0.5)
			(thermal_bridge_width 0.5)
			(island_removal_mode 0)
		)
		(polygon
			(pts
				(arc
					(start 455.365866 -302.071532)
					(mid 455.380745 -302.107453)
					(end 455.416666 -302.122332)
				)
				(arc
					(start 456.816206 -302.122332)
					(mid 456.852127 -302.107453)
					(end 456.867006 -302.071532)
				)
				(arc
					(start 456.867006 -301.662592)
					(mid 456.852127 -301.626671)
					(end 456.816206 -301.611792)
				)
				(arc
					(start 455.416666 -301.611792)
					(mid 455.380745 -301.626671)
					(end 455.365866 -301.662592)
				)
			)
		)
	)
	(zone
		(layers "In1.Cu" "In2.Cu")
		(hatch none 0.5)
		(connect_pads
			(clearance 0)
		)
		(min_thickness 0.25)
		(keepout
			(tracks not_allowed)
			(vias allowed)
			(pads allowed)
			(copperpour not_allowed)
			(footprints allowed)
		)
		(placement
			(enabled no)
			(sheetname "")
		)
		(fill yes
			(thermal_gap 0.5)
			(thermal_bridge_width 0.5)
			(island_removal_mode 0)
		)
		(polygon
			(pts
				(arc
					(start 462.909666 -296.971466)
					(mid 462.924545 -297.007387)
					(end 462.960466 -297.022266)
				)
				(arc
					(start 464.360006 -297.022266)
					(mid 464.395927 -297.007387)
					(end 464.410806 -296.971466)
				)
				(arc
					(start 464.410806 -296.562526)
					(mid 464.395927 -296.526605)
					(end 464.360006 -296.511726)
				)
				(arc
					(start 462.960466 -296.511726)
					(mid 462.924545 -296.526605)
					(end 462.909666 -296.562526)
				)
			)
		)
	)
	(zone
		(layers "In1.Cu" "In2.Cu")
		(hatch none 0.5)
		(connect_pads
			(clearance 0)
		)
		(min_thickness 0.25)
		(keepout
			(tracks not_allowed)
			(vias allowed)
			(pads allowed)
			(copperpour not_allowed)
			(footprints allowed)
		)
		(placement
			(enabled no)
			(sheetname "")
		)
		(fill yes
			(thermal_gap 0.5)
			(thermal_bridge_width 0.5)
			(island_removal_mode 0)
		)
		(polygon
			(pts
				(arc
					(start 192.338198 -274.871434)
					(mid 192.353077 -274.907355)
					(end 192.388998 -274.922234)
				)
				(arc
					(start 193.788538 -274.922234)
					(mid 193.824459 -274.907355)
					(end 193.839338 -274.871434)
				)
				(arc
					(start 193.839338 -274.462494)
					(mid 193.824459 -274.426573)
					(end 193.788538 -274.411694)
				)
				(arc
					(start 192.388998 -274.411694)
					(mid 192.353077 -274.426573)
					(end 192.338198 -274.462494)
				)
			)
		)
	)
	(zone
		(layers "In1.Cu" "In2.Cu")
		(hatch none 0.5)
		(connect_pads
			(clearance 0)
		)
		(min_thickness 0.25)
		(keepout
			(tracks not_allowed)
			(vias allowed)
			(pads allowed)
			(copperpour not_allowed)
			(footprints allowed)
		)
		(placement
			(enabled no)
			(sheetname "")
		)
		(fill yes
			(thermal_gap 0.5)
			(thermal_bridge_width 0.5)
			(island_removal_mode 0)
		)
		(polygon
			(pts
				(arc
					(start 425.190666 -283.371544)
					(mid 425.205545 -283.407465)
					(end 425.241466 -283.422344)
				)
				(arc
					(start 426.641006 -283.422344)
					(mid 426.676927 -283.407465)
					(end 426.691806 -283.371544)
				)
				(arc
					(start 426.691806 -282.962604)
					(mid 426.676927 -282.926683)
					(end 426.641006 -282.911804)
				)
				(arc
					(start 425.241466 -282.911804)
					(mid 425.205545 -282.926683)
					(end 425.190666 -282.962604)
				)
			)
		)
	)
	(zone
		(layers "In1.Cu" "In2.Cu")
		(hatch none 0.5)
		(connect_pads
			(clearance 0)
		)
		(min_thickness 0.25)
		(keepout
			(tracks not_allowed)
			(vias allowed)
			(pads allowed)
			(copperpour not_allowed)
			(footprints allowed)
		)
		(placement
			(enabled no)
			(sheetname "")
		)
		(fill yes
			(thermal_gap 0.5)
			(thermal_bridge_width 0.5)
			(island_removal_mode 0)
		)
		(polygon
			(pts
				(arc
					(start 26.577798 -295.271444)
					(mid 26.592677 -295.307365)
					(end 26.628598 -295.322244)
				)
				(arc
					(start 28.028138 -295.322244)
					(mid 28.064059 -295.307365)
					(end 28.078938 -295.271444)
				)
				(arc
					(start 28.078938 -294.862504)
					(mid 28.064059 -294.826583)
					(end 28.028138 -294.811704)
				)
				(arc
					(start 26.628598 -294.811704)
					(mid 26.592677 -294.826583)
					(end 26.577798 -294.862504)
				)
			)
		)
	)
	(zone
		(layers "In1.Cu" "In2.Cu")
		(hatch none 0.5)
		(connect_pads
			(clearance 0)
		)
		(min_thickness 0.25)
		(keepout
			(tracks not_allowed)
			(vias allowed)
			(pads allowed)
			(copperpour not_allowed)
			(footprints allowed)
		)
		(placement
			(enabled no)
			(sheetname "")
		)
		(fill yes
			(thermal_gap 0.5)
			(thermal_bridge_width 0.5)
			(island_removal_mode 0)
		)
		(polygon
			(pts
				(arc
					(start 285.505398 -209.421476)
					(mid 285.520277 -209.457397)
					(end 285.556198 -209.472276)
				)
				(arc
					(start 286.955738 -209.472276)
					(mid 286.991659 -209.457397)
					(end 287.006538 -209.421476)
				)
				(arc
					(start 287.006538 -209.012536)
					(mid 286.991659 -208.976615)
					(end 286.955738 -208.961736)
				)
				(arc
					(start 285.556198 -208.961736)
					(mid 285.520277 -208.976615)
					(end 285.505398 -209.012536)
				)
			)
		)
	)
	(zone
		(layers "In1.Cu" "In2.Cu")
		(hatch none 0.5)
		(connect_pads
			(clearance 0)
		)
		(min_thickness 0.25)
		(keepout
			(tracks not_allowed)
			(vias allowed)
			(pads allowed)
			(copperpour not_allowed)
			(footprints allowed)
		)
		(placement
			(enabled no)
			(sheetname "")
		)
		(fill yes
			(thermal_gap 0.5)
			(thermal_bridge_width 0.5)
			(island_removal_mode 0)
		)
		(polygon
			(pts
				(arc
					(start 304.693066 -308.021482)
					(mid 304.707945 -308.057403)
					(end 304.743866 -308.072282)
				)
				(arc
					(start 306.143406 -308.072282)
					(mid 306.179327 -308.057403)
					(end 306.194206 -308.021482)
				)
				(arc
					(start 306.194206 -307.612542)
					(mid 306.179327 -307.576621)
					(end 306.143406 -307.561742)
				)
				(arc
					(start 304.743866 -307.561742)
					(mid 304.707945 -307.576621)
					(end 304.693066 -307.612542)
				)
			)
		)
	)
	(zone
		(layers "In1.Cu" "In2.Cu")
		(hatch none 0.5)
		(connect_pads
			(clearance 0)
		)
		(min_thickness 0.25)
		(keepout
			(tracks not_allowed)
			(vias allowed)
			(pads allowed)
			(copperpour not_allowed)
			(footprints allowed)
		)
		(placement
			(enabled no)
			(sheetname "")
		)
		(fill yes
			(thermal_gap 0.5)
			(thermal_bridge_width 0.5)
			(island_removal_mode 0)
		)
		(polygon
			(pts
				(arc
					(start 421.090598 -202.621388)
					(mid 421.105477 -202.657309)
					(end 421.141398 -202.672188)
				)
				(arc
					(start 422.540938 -202.672188)
					(mid 422.576859 -202.657309)
					(end 422.591738 -202.621388)
				)
				(arc
					(start 422.591738 -202.212448)
					(mid 422.576859 -202.176527)
					(end 422.540938 -202.161648)
				)
				(arc
					(start 421.141398 -202.161648)
					(mid 421.105477 -202.176527)
					(end 421.090598 -202.212448)
				)
			)
		)
	)
	(zone
		(layers "In1.Cu" "In2.Cu")
		(hatch none 0.5)
		(connect_pads
			(clearance 0)
		)
		(min_thickness 0.25)
		(keepout
			(tracks not_allowed)
			(vias allowed)
			(pads allowed)
			(copperpour not_allowed)
			(footprints allowed)
		)
		(placement
			(enabled no)
			(sheetname "")
		)
		(fill yes
			(thermal_gap 0.5)
			(thermal_bridge_width 0.5)
			(island_removal_mode 0)
		)
		(polygon
			(pts
				(arc
					(start 432.734466 -263.821418)
					(mid 432.749345 -263.857339)
					(end 432.785266 -263.872218)
				)
				(arc
					(start 434.184806 -263.872218)
					(mid 434.220727 -263.857339)
					(end 434.235606 -263.821418)
				)
				(arc
					(start 434.235606 -263.412478)
					(mid 434.220727 -263.376557)
					(end 434.184806 -263.361678)
				)
				(arc
					(start 432.785266 -263.361678)
					(mid 432.749345 -263.376557)
					(end 432.734466 -263.412478)
				)
			)
		)
	)
	(zone
		(layers "In1.Cu" "In2.Cu")
		(hatch none 0.5)
		(connect_pads
			(clearance 0)
		)
		(min_thickness 0.25)
		(keepout
			(tracks not_allowed)
			(vias allowed)
			(pads allowed)
			(copperpour not_allowed)
			(footprints allowed)
		)
		(placement
			(enabled no)
			(sheetname "")
		)
		(fill yes
			(thermal_gap 0.5)
			(thermal_bridge_width 0.5)
			(island_removal_mode 0)
		)
		(polygon
			(pts
				(arc
					(start 312.236866 -270.621506)
					(mid 312.251745 -270.657427)
					(end 312.287666 -270.672306)
				)
				(arc
					(start 313.687206 -270.672306)
					(mid 313.723127 -270.657427)
					(end 313.738006 -270.621506)
				)
				(arc
					(start 313.738006 -270.212566)
					(mid 313.723127 -270.176645)
					(end 313.687206 -270.161766)
				)
				(arc
					(start 312.287666 -270.161766)
					(mid 312.251745 -270.176645)
					(end 312.236866 -270.212566)
				)
			)
		)
	)
	(zone
		(layers "In1.Cu" "In2.Cu")
		(hatch none 0.5)
		(connect_pads
			(clearance 0)
		)
		(min_thickness 0.25)
		(keepout
			(tracks not_allowed)
			(vias allowed)
			(pads allowed)
			(copperpour not_allowed)
			(footprints allowed)
		)
		(placement
			(enabled no)
			(sheetname "")
		)
		(fill yes
			(thermal_gap 0.5)
			(thermal_bridge_width 0.5)
			(island_removal_mode 0)
		)
		(polygon
			(pts
				(arc
					(start 421.090598 -228.121464)
					(mid 421.105477 -228.157385)
					(end 421.141398 -228.172264)
				)
				(arc
					(start 422.540938 -228.172264)
					(mid 422.576859 -228.157385)
					(end 422.591738 -228.121464)
				)
				(arc
					(start 422.591738 -227.712524)
					(mid 422.576859 -227.676603)
					(end 422.540938 -227.661724)
				)
				(arc
					(start 421.141398 -227.661724)
					(mid 421.105477 -227.676603)
					(end 421.090598 -227.712524)
				)
			)
		)
	)
	(zone
		(layers "In1.Cu" "In2.Cu")
		(hatch none 0.5)
		(connect_pads
			(clearance 0)
		)
		(min_thickness 0.25)
		(keepout
			(tracks not_allowed)
			(vias allowed)
			(pads allowed)
			(copperpour not_allowed)
			(footprints allowed)
		)
		(placement
			(enabled no)
			(sheetname "")
		)
		(fill yes
			(thermal_gap 0.5)
			(thermal_bridge_width 0.5)
			(island_removal_mode 0)
		)
		(polygon
			(pts
				(arc
					(start 436.178198 -252.771402)
					(mid 436.193077 -252.807323)
					(end 436.228998 -252.822202)
				)
				(arc
					(start 437.628538 -252.822202)
					(mid 437.664459 -252.807323)
					(end 437.679338 -252.771402)
				)
				(arc
					(start 437.679338 -252.362462)
					(mid 437.664459 -252.326541)
					(end 437.628538 -252.311662)
				)
				(arc
					(start 436.228998 -252.311662)
					(mid 436.193077 -252.326541)
					(end 436.178198 -252.362462)
				)
			)
		)
	)
	(zone
		(layers "In1.Cu" "In2.Cu")
		(hatch none 0.5)
		(connect_pads
			(clearance 0)
		)
		(min_thickness 0.25)
		(keepout
			(tracks not_allowed)
			(vias allowed)
			(pads allowed)
			(copperpour not_allowed)
			(footprints allowed)
		)
		(placement
			(enabled no)
			(sheetname "")
		)
		(fill yes
			(thermal_gap 0.5)
			(thermal_bridge_width 0.5)
			(island_removal_mode 0)
		)
		(polygon
			(pts
				(arc
					(start 169.706798 -229.821486)
					(mid 169.721677 -229.857407)
					(end 169.757598 -229.872286)
				)
				(arc
					(start 171.157138 -229.872286)
					(mid 171.193059 -229.857407)
					(end 171.207938 -229.821486)
				)
				(arc
					(start 171.207938 -229.412546)
					(mid 171.193059 -229.376625)
					(end 171.157138 -229.361746)
				)
				(arc
					(start 169.757598 -229.361746)
					(mid 169.721677 -229.376625)
					(end 169.706798 -229.412546)
				)
			)
		)
	)
	(zone
		(layers "In1.Cu" "In2.Cu")
		(hatch none 0.5)
		(connect_pads
			(clearance 0)
		)
		(min_thickness 0.25)
		(keepout
			(tracks not_allowed)
			(vias allowed)
			(pads allowed)
			(copperpour not_allowed)
			(footprints allowed)
		)
		(placement
			(enabled no)
			(sheetname "")
		)
		(fill yes
			(thermal_gap 0.5)
			(thermal_bridge_width 0.5)
			(island_removal_mode 0)
		)
		(polygon
			(pts
				(arc
					(start 289.605466 -205.171548)
					(mid 289.620345 -205.207469)
					(end 289.656266 -205.222348)
				)
				(arc
					(start 291.055806 -205.222348)
					(mid 291.091727 -205.207469)
					(end 291.106606 -205.171548)
				)
				(arc
					(start 291.106606 -204.762608)
					(mid 291.091727 -204.726687)
					(end 291.055806 -204.711808)
				)
				(arc
					(start 289.656266 -204.711808)
					(mid 289.620345 -204.726687)
					(end 289.605466 -204.762608)
				)
			)
		)
	)
	(zone
		(layers "In1.Cu" "In2.Cu")
		(hatch none 0.5)
		(connect_pads
			(clearance 0)
		)
		(min_thickness 0.25)
		(keepout
			(tracks not_allowed)
			(vias allowed)
			(pads allowed)
			(copperpour not_allowed)
			(footprints allowed)
		)
		(placement
			(enabled no)
			(sheetname "")
		)
		(fill yes
			(thermal_gap 0.5)
			(thermal_bridge_width 0.5)
			(island_removal_mode 0)
		)
		(polygon
			(pts
				(arc
					(start 22.47773 -274.871434)
					(mid 22.492609 -274.907355)
					(end 22.52853 -274.922234)
				)
				(arc
					(start 23.92807 -274.922234)
					(mid 23.963991 -274.907355)
					(end 23.97887 -274.871434)
				)
				(arc
					(start 23.97887 -274.462494)
					(mid 23.963991 -274.426573)
					(end 23.92807 -274.411694)
				)
				(arc
					(start 22.52853 -274.411694)
					(mid 22.492609 -274.426573)
					(end 22.47773 -274.462494)
				)
			)
		)
	)
	(zone
		(layers "In1.Cu" "In2.Cu")
		(hatch none 0.5)
		(connect_pads
			(clearance 0)
		)
		(min_thickness 0.25)
		(keepout
			(tracks not_allowed)
			(vias allowed)
			(pads allowed)
			(copperpour not_allowed)
			(footprints allowed)
		)
		(placement
			(enabled no)
			(sheetname "")
		)
		(fill yes
			(thermal_gap 0.5)
			(thermal_bridge_width 0.5)
			(island_removal_mode 0)
		)
		(polygon
			(pts
				(arc
					(start 440.278266 -223.871536)
					(mid 440.293145 -223.907457)
					(end 440.329066 -223.922336)
				)
				(arc
					(start 441.728606 -223.922336)
					(mid 441.764527 -223.907457)
					(end 441.779406 -223.871536)
				)
				(arc
					(start 441.779406 -223.462596)
					(mid 441.764527 -223.426675)
					(end 441.728606 -223.411796)
				)
				(arc
					(start 440.329066 -223.411796)
					(mid 440.293145 -223.426675)
					(end 440.278266 -223.462596)
				)
			)
		)
	)
	(zone
		(layers "In1.Cu" "In2.Cu")
		(hatch none 0.5)
		(connect_pads
			(clearance 0)
		)
		(min_thickness 0.25)
		(keepout
			(tracks not_allowed)
			(vias allowed)
			(pads allowed)
			(copperpour not_allowed)
			(footprints allowed)
		)
		(placement
			(enabled no)
			(sheetname "")
		)
		(fill yes
			(thermal_gap 0.5)
			(thermal_bridge_width 0.5)
			(island_removal_mode 0)
		)
		(polygon
			(pts
				(arc
					(start 64.296798 -302.071532)
					(mid 64.311677 -302.107453)
					(end 64.347598 -302.122332)
				)
				(arc
					(start 65.747138 -302.122332)
					(mid 65.783059 -302.107453)
					(end 65.797938 -302.071532)
				)
				(arc
					(start 65.797938 -301.662592)
					(mid 65.783059 -301.626671)
					(end 65.747138 -301.611792)
				)
				(arc
					(start 64.347598 -301.611792)
					(mid 64.311677 -301.626671)
					(end 64.296798 -301.662592)
				)
			)
		)
	)
	(zone
		(layers "In1.Cu" "In2.Cu")
		(hatch none 0.5)
		(connect_pads
			(clearance 0)
		)
		(min_thickness 0.25)
		(keepout
			(tracks not_allowed)
			(vias allowed)
			(pads allowed)
			(copperpour not_allowed)
			(footprints allowed)
		)
		(placement
			(enabled no)
			(sheetname "")
		)
		(fill yes
			(thermal_gap 0.5)
			(thermal_bridge_width 0.5)
			(island_removal_mode 0)
		)
		(polygon
			(pts
				(arc
					(start 436.178198 -232.371392)
					(mid 436.193077 -232.407313)
					(end 436.228998 -232.422192)
				)
				(arc
					(start 437.628538 -232.422192)
					(mid 437.664459 -232.407313)
					(end 437.679338 -232.371392)
				)
				(arc
					(start 437.679338 -231.962452)
					(mid 437.664459 -231.926531)
					(end 437.628538 -231.911652)
				)
				(arc
					(start 436.228998 -231.911652)
					(mid 436.193077 -231.926531)
					(end 436.178198 -231.962452)
				)
			)
		)
	)
	(zone
		(layers "In1.Cu" "In2.Cu")
		(hatch none 0.5)
		(connect_pads
			(clearance 0)
		)
		(min_thickness 0.25)
		(keepout
			(tracks not_allowed)
			(vias allowed)
			(pads allowed)
			(copperpour not_allowed)
			(footprints allowed)
		)
		(placement
			(enabled no)
			(sheetname "")
		)
		(fill yes
			(thermal_gap 0.5)
			(thermal_bridge_width 0.5)
			(island_removal_mode 0)
		)
		(polygon
			(pts
				(arc
					(start 207.425798 -214.521542)
					(mid 207.440677 -214.557463)
					(end 207.476598 -214.572342)
				)
				(arc
					(start 208.876138 -214.572342)
					(mid 208.912059 -214.557463)
					(end 208.926938 -214.521542)
				)
				(arc
					(start 208.926938 -214.112602)
					(mid 208.912059 -214.076681)
					(end 208.876138 -214.061802)
				)
				(arc
					(start 207.476598 -214.061802)
					(mid 207.440677 -214.076681)
					(end 207.425798 -214.112602)
				)
			)
		)
	)
	(zone
		(layers "In1.Cu" "In2.Cu")
		(hatch none 0.5)
		(connect_pads
			(clearance 0)
		)
		(min_thickness 0.25)
		(keepout
			(tracks not_allowed)
			(vias allowed)
			(pads allowed)
			(copperpour not_allowed)
			(footprints allowed)
		)
		(placement
			(enabled no)
			(sheetname "")
		)
		(fill yes
			(thermal_gap 0.5)
			(thermal_bridge_width 0.5)
			(island_removal_mode 0)
		)
		(polygon
			(pts
				(arc
					(start 14.93393 -262.971534)
					(mid 14.948809 -263.007455)
					(end 14.98473 -263.022334)
				)
				(arc
					(start 16.38427 -263.022334)
					(mid 16.420191 -263.007455)
					(end 16.43507 -262.971534)
				)
				(arc
					(start 16.43507 -262.562594)
					(mid 16.420191 -262.526673)
					(end 16.38427 -262.511794)
				)
				(arc
					(start 14.98473 -262.511794)
					(mid 14.948809 -262.526673)
					(end 14.93393 -262.562594)
				)
			)
		)
	)
	(zone
		(layers "In1.Cu" "In2.Cu")
		(hatch none 0.5)
		(connect_pads
			(clearance 0)
		)
		(min_thickness 0.25)
		(keepout
			(tracks not_allowed)
			(vias allowed)
			(pads allowed)
			(copperpour not_allowed)
			(footprints allowed)
		)
		(placement
			(enabled no)
			(sheetname "")
		)
		(fill yes
			(thermal_gap 0.5)
			(thermal_bridge_width 0.5)
			(island_removal_mode 0)
		)
		(polygon
			(pts
				(arc
					(start 214.969598 -302.921416)
					(mid 214.984477 -302.957337)
					(end 215.020398 -302.972216)
				)
				(arc
					(start 216.419938 -302.972216)
					(mid 216.455859 -302.957337)
					(end 216.470738 -302.921416)
				)
				(arc
					(start 216.470738 -302.512476)
					(mid 216.455859 -302.476555)
					(end 216.419938 -302.461676)
				)
				(arc
					(start 215.020398 -302.461676)
					(mid 214.984477 -302.476555)
					(end 214.969598 -302.512476)
				)
			)
		)
	)
	(zone
		(layers "In1.Cu" "In2.Cu")
		(hatch none 0.5)
		(connect_pads
			(clearance 0)
		)
		(min_thickness 0.25)
		(keepout
			(tracks not_allowed)
			(vias allowed)
			(pads allowed)
			(copperpour not_allowed)
			(footprints allowed)
		)
		(placement
			(enabled no)
			(sheetname "")
		)
		(fill yes
			(thermal_gap 0.5)
			(thermal_bridge_width 0.5)
			(island_removal_mode 0)
		)
		(polygon
			(pts
				(arc
					(start 11.490198 -214.521542)
					(mid 11.505077 -214.557463)
					(end 11.540998 -214.572342)
				)
				(arc
					(start 12.940538 -214.572342)
					(mid 12.976459 -214.557463)
					(end 12.991338 -214.521542)
				)
				(arc
					(start 12.991338 -214.112602)
					(mid 12.976459 -214.076681)
					(end 12.940538 -214.061802)
				)
				(arc
					(start 11.540998 -214.061802)
					(mid 11.505077 -214.076681)
					(end 11.490198 -214.112602)
				)
			)
		)
	)
	(zone
		(layers "In1.Cu" "In2.Cu")
		(hatch none 0.5)
		(connect_pads
			(clearance 0)
		)
		(min_thickness 0.25)
		(keepout
			(tracks not_allowed)
			(vias allowed)
			(pads allowed)
			(copperpour not_allowed)
			(footprints allowed)
		)
		(placement
			(enabled no)
			(sheetname "")
		)
		(fill yes
			(thermal_gap 0.5)
			(thermal_bridge_width 0.5)
			(island_removal_mode 0)
		)
		(polygon
			(pts
				(arc
					(start 195.78193 -312.27141)
					(mid 195.796809 -312.307331)
					(end 195.83273 -312.32221)
				)
				(arc
					(start 197.23227 -312.32221)
					(mid 197.268191 -312.307331)
					(end 197.28307 -312.27141)
				)
				(arc
					(start 197.28307 -311.86247)
					(mid 197.268191 -311.826549)
					(end 197.23227 -311.81167)
				)
				(arc
					(start 195.83273 -311.81167)
					(mid 195.796809 -311.826549)
					(end 195.78193 -311.86247)
				)
			)
		)
	)
	(zone
		(layers "In1.Cu" "In2.Cu")
		(hatch none 0.5)
		(connect_pads
			(clearance 0)
		)
		(min_thickness 0.25)
		(keepout
			(tracks not_allowed)
			(vias allowed)
			(pads allowed)
			(copperpour not_allowed)
			(footprints allowed)
		)
		(placement
			(enabled no)
			(sheetname "")
		)
		(fill yes
			(thermal_gap 0.5)
			(thermal_bridge_width 0.5)
			(island_removal_mode 0)
		)
		(polygon
			(pts
				(arc
					(start 458.809598 -302.921416)
					(mid 458.824477 -302.957337)
					(end 458.860398 -302.972216)
				)
				(arc
					(start 460.259938 -302.972216)
					(mid 460.295859 -302.957337)
					(end 460.310738 -302.921416)
				)
				(arc
					(start 460.310738 -302.512476)
					(mid 460.295859 -302.476555)
					(end 460.259938 -302.461676)
				)
				(arc
					(start 458.860398 -302.461676)
					(mid 458.824477 -302.476555)
					(end 458.809598 -302.512476)
				)
			)
		)
	)
	(zone
		(layers "In1.Cu" "In2.Cu")
		(hatch none 0.5)
		(connect_pads
			(clearance 0)
		)
		(min_thickness 0.25)
		(keepout
			(tracks not_allowed)
			(vias allowed)
			(pads allowed)
			(copperpour not_allowed)
			(footprints allowed)
		)
		(placement
			(enabled no)
			(sheetname "")
		)
		(fill yes
			(thermal_gap 0.5)
			(thermal_bridge_width 0.5)
			(island_removal_mode 0)
		)
		(polygon
			(pts
				(arc
					(start 173.15053 -297.82135)
					(mid 173.165409 -297.857271)
					(end 173.20133 -297.87215)
				)
				(arc
					(start 174.60087 -297.87215)
					(mid 174.636791 -297.857271)
					(end 174.65167 -297.82135)
				)
				(arc
					(start 174.65167 -297.41241)
					(mid 174.636791 -297.376489)
					(end 174.60087 -297.36161)
				)
				(arc
					(start 173.20133 -297.36161)
					(mid 173.165409 -297.376489)
					(end 173.15053 -297.41241)
				)
			)
		)
	)
	(zone
		(layers "In1.Cu" "In2.Cu")
		(hatch none 0.5)
		(connect_pads
			(clearance 0)
		)
		(min_thickness 0.25)
		(keepout
			(tracks not_allowed)
			(vias allowed)
			(pads allowed)
			(copperpour not_allowed)
			(footprints allowed)
		)
		(placement
			(enabled no)
			(sheetname "")
		)
		(fill yes
			(thermal_gap 0.5)
			(thermal_bridge_width 0.5)
			(island_removal_mode 0)
		)
		(polygon
			(pts
				(arc
					(start 56.752998 -278.271478)
					(mid 56.767877 -278.307399)
					(end 56.803798 -278.322278)
				)
				(arc
					(start 58.203338 -278.322278)
					(mid 58.239259 -278.307399)
					(end 58.254138 -278.271478)
				)
				(arc
					(start 58.254138 -277.862538)
					(mid 58.239259 -277.826617)
					(end 58.203338 -277.811738)
				)
				(arc
					(start 56.803798 -277.811738)
					(mid 56.767877 -277.826617)
					(end 56.752998 -277.862538)
				)
			)
		)
	)
	(zone
		(layers "In1.Cu" "In2.Cu")
		(hatch none 0.5)
		(connect_pads
			(clearance 0)
		)
		(min_thickness 0.25)
		(keepout
			(tracks not_allowed)
			(vias allowed)
			(pads allowed)
			(copperpour not_allowed)
			(footprints allowed)
		)
		(placement
			(enabled no)
			(sheetname "")
		)
		(fill yes
			(thermal_gap 0.5)
			(thermal_bridge_width 0.5)
			(island_removal_mode 0)
		)
		(polygon
			(pts
				(arc
					(start 158.06293 -240.021364)
					(mid 158.077809 -240.057285)
					(end 158.11373 -240.072164)
				)
				(arc
					(start 159.51327 -240.072164)
					(mid 159.549191 -240.057285)
					(end 159.56407 -240.021364)
				)
				(arc
					(start 159.56407 -239.612424)
					(mid 159.549191 -239.576503)
					(end 159.51327 -239.561624)
				)
				(arc
					(start 158.11373 -239.561624)
					(mid 158.077809 -239.576503)
					(end 158.06293 -239.612424)
				)
			)
		)
	)
	(zone
		(layers "In1.Cu" "In2.Cu")
		(hatch none 0.5)
		(connect_pads
			(clearance 0)
		)
		(min_thickness 0.25)
		(keepout
			(tracks not_allowed)
			(vias allowed)
			(pads allowed)
			(copperpour not_allowed)
			(footprints allowed)
		)
		(placement
			(enabled no)
			(sheetname "")
		)
		(fill yes
			(thermal_gap 0.5)
			(thermal_bridge_width 0.5)
			(island_removal_mode 0)
		)
		(polygon
			(pts
				(arc
					(start 421.090598 -234.071414)
					(mid 421.105477 -234.107335)
					(end 421.141398 -234.122214)
				)
				(arc
					(start 422.540938 -234.122214)
					(mid 422.576859 -234.107335)
					(end 422.591738 -234.071414)
				)
				(arc
					(start 422.591738 -233.662474)
					(mid 422.576859 -233.626553)
					(end 422.540938 -233.611674)
				)
				(arc
					(start 421.141398 -233.611674)
					(mid 421.105477 -233.626553)
					(end 421.090598 -233.662474)
				)
			)
		)
	)
	(zone
		(layers "In1.Cu" "In2.Cu")
		(hatch none 0.5)
		(connect_pads
			(clearance 0)
		)
		(min_thickness 0.25)
		(keepout
			(tracks not_allowed)
			(vias allowed)
			(pads allowed)
			(copperpour not_allowed)
			(footprints allowed)
		)
		(placement
			(enabled no)
			(sheetname "")
		)
		(fill yes
			(thermal_gap 0.5)
			(thermal_bridge_width 0.5)
			(island_removal_mode 0)
		)
		(polygon
			(pts
				(arc
					(start 26.577798 -287.621472)
					(mid 26.592677 -287.657393)
					(end 26.628598 -287.672272)
				)
				(arc
					(start 28.028138 -287.672272)
					(mid 28.064059 -287.657393)
					(end 28.078938 -287.621472)
				)
				(arc
					(start 28.078938 -287.212532)
					(mid 28.064059 -287.176611)
					(end 28.028138 -287.161732)
				)
				(arc
					(start 26.628598 -287.161732)
					(mid 26.592677 -287.176611)
					(end 26.577798 -287.212532)
				)
			)
		)
	)
	(zone
		(layers "In1.Cu" "In2.Cu")
		(hatch none 0.5)
		(connect_pads
			(clearance 0)
		)
		(min_thickness 0.25)
		(keepout
			(tracks not_allowed)
			(vias allowed)
			(pads allowed)
			(copperpour not_allowed)
			(footprints allowed)
		)
		(placement
			(enabled no)
			(sheetname "")
		)
		(fill yes
			(thermal_gap 0.5)
			(thermal_bridge_width 0.5)
			(island_removal_mode 0)
		)
		(polygon
			(pts
				(arc
					(start 162.162998 -236.62132)
					(mid 162.177877 -236.657241)
					(end 162.213798 -236.67212)
				)
				(arc
					(start 163.613338 -236.67212)
					(mid 163.649259 -236.657241)
					(end 163.664138 -236.62132)
				)
				(arc
					(start 163.664138 -236.21238)
					(mid 163.649259 -236.176459)
					(end 163.613338 -236.16158)
				)
				(arc
					(start 162.213798 -236.16158)
					(mid 162.177877 -236.176459)
					(end 162.162998 -236.21238)
				)
			)
		)
	)
	(zone
		(layers "In1.Cu" "In2.Cu")
		(hatch none 0.5)
		(connect_pads
			(clearance 0)
		)
		(min_thickness 0.25)
		(keepout
			(tracks not_allowed)
			(vias allowed)
			(pads allowed)
			(copperpour not_allowed)
			(footprints allowed)
		)
		(placement
			(enabled no)
			(sheetname "")
		)
		(fill yes
			(thermal_gap 0.5)
			(thermal_bridge_width 0.5)
			(island_removal_mode 0)
		)
		(polygon
			(pts
				(arc
					(start 406.002998 -221.321376)
					(mid 406.017877 -221.357297)
					(end 406.053798 -221.372176)
				)
				(arc
					(start 407.453338 -221.372176)
					(mid 407.489259 -221.357297)
					(end 407.504138 -221.321376)
				)
				(arc
					(start 407.504138 -220.912436)
					(mid 407.489259 -220.876515)
					(end 407.453338 -220.861636)
				)
				(arc
					(start 406.053798 -220.861636)
					(mid 406.017877 -220.876515)
					(end 406.002998 -220.912436)
				)
			)
		)
	)
	(zone
		(layers "In1.Cu" "In2.Cu")
		(hatch none 0.5)
		(connect_pads
			(clearance 0)
		)
		(min_thickness 0.25)
		(keepout
			(tracks not_allowed)
			(vias allowed)
			(pads allowed)
			(copperpour not_allowed)
			(footprints allowed)
		)
		(placement
			(enabled no)
			(sheetname "")
		)
		(fill yes
			(thermal_gap 0.5)
			(thermal_bridge_width 0.5)
			(island_removal_mode 0)
		)
		(polygon
			(pts
				(arc
					(start 30.02153 -249.371358)
					(mid 30.036409 -249.407279)
					(end 30.07233 -249.422158)
				)
				(arc
					(start 31.47187 -249.422158)
					(mid 31.507791 -249.407279)
					(end 31.52267 -249.371358)
				)
				(arc
					(start 31.52267 -248.962418)
					(mid 31.507791 -248.926497)
					(end 31.47187 -248.911618)
				)
				(arc
					(start 30.07233 -248.911618)
					(mid 30.036409 -248.926497)
					(end 30.02153 -248.962418)
				)
			)
		)
	)
	(zone
		(layers "In1.Cu" "In2.Cu")
		(hatch none 0.5)
		(connect_pads
			(clearance 0)
		)
		(min_thickness 0.25)
		(keepout
			(tracks not_allowed)
			(vias allowed)
			(pads allowed)
			(copperpour not_allowed)
			(footprints allowed)
		)
		(placement
			(enabled no)
			(sheetname "")
		)
		(fill yes
			(thermal_gap 0.5)
			(thermal_bridge_width 0.5)
			(island_removal_mode 0)
		)
		(polygon
			(pts
				(arc
					(start 443.721998 -313.121294)
					(mid 443.736877 -313.157215)
					(end 443.772798 -313.172094)
				)
				(arc
					(start 445.172338 -313.172094)
					(mid 445.208259 -313.157215)
					(end 445.223138 -313.121294)
				)
				(arc
					(start 445.223138 -312.712354)
					(mid 445.208259 -312.676433)
					(end 445.172338 -312.661554)
				)
				(arc
					(start 443.772798 -312.661554)
					(mid 443.736877 -312.676433)
					(end 443.721998 -312.712354)
				)
			)
		)
	)
	(zone
		(layers "In1.Cu" "In2.Cu")
		(hatch none 0.5)
		(connect_pads
			(clearance 0)
		)
		(min_thickness 0.25)
		(keepout
			(tracks not_allowed)
			(vias allowed)
			(pads allowed)
			(copperpour not_allowed)
			(footprints allowed)
		)
		(placement
			(enabled no)
			(sheetname "")
		)
		(fill yes
			(thermal_gap 0.5)
			(thermal_bridge_width 0.5)
			(island_removal_mode 0)
		)
		(polygon
			(pts
				(arc
					(start 45.10913 -232.371392)
					(mid 45.124009 -232.407313)
					(end 45.15993 -232.422192)
				)
				(arc
					(start 46.55947 -232.422192)
					(mid 46.595391 -232.407313)
					(end 46.61027 -232.371392)
				)
				(arc
					(start 46.61027 -231.962452)
					(mid 46.595391 -231.926531)
					(end 46.55947 -231.911652)
				)
				(arc
					(start 45.15993 -231.911652)
					(mid 45.124009 -231.926531)
					(end 45.10913 -231.962452)
				)
			)
		)
	)
	(zone
		(layers "In1.Cu" "In2.Cu")
		(hatch none 0.5)
		(connect_pads
			(clearance 0)
		)
		(min_thickness 0.25)
		(keepout
			(tracks not_allowed)
			(vias allowed)
			(pads allowed)
			(copperpour not_allowed)
			(footprints allowed)
		)
		(placement
			(enabled no)
			(sheetname "")
		)
		(fill yes
			(thermal_gap 0.5)
			(thermal_bridge_width 0.5)
			(island_removal_mode 0)
		)
		(polygon
			(pts
				(arc
					(start 195.78193 -268.071346)
					(mid 195.796809 -268.107267)
					(end 195.83273 -268.122146)
				)
				(arc
					(start 197.23227 -268.122146)
					(mid 197.268191 -268.107267)
					(end 197.28307 -268.071346)
				)
				(arc
					(start 197.28307 -267.662406)
					(mid 197.268191 -267.626485)
					(end 197.23227 -267.611606)
				)
				(arc
					(start 195.83273 -267.611606)
					(mid 195.796809 -267.626485)
					(end 195.78193 -267.662406)
				)
			)
		)
	)
	(zone
		(layers "In1.Cu" "In2.Cu")
		(hatch none 0.5)
		(connect_pads
			(clearance 0)
		)
		(min_thickness 0.25)
		(keepout
			(tracks not_allowed)
			(vias allowed)
			(pads allowed)
			(copperpour not_allowed)
			(footprints allowed)
		)
		(placement
			(enabled no)
			(sheetname "")
		)
		(fill yes
			(thermal_gap 0.5)
			(thermal_bridge_width 0.5)
			(island_removal_mode 0)
		)
		(polygon
			(pts
				(arc
					(start 180.69433 -271.47139)
					(mid 180.709209 -271.507311)
					(end 180.74513 -271.52219)
				)
				(arc
					(start 182.14467 -271.52219)
					(mid 182.180591 -271.507311)
					(end 182.19547 -271.47139)
				)
				(arc
					(start 182.19547 -271.06245)
					(mid 182.180591 -271.026529)
					(end 182.14467 -271.01165)
				)
				(arc
					(start 180.74513 -271.01165)
					(mid 180.709209 -271.026529)
					(end 180.69433 -271.06245)
				)
			)
		)
	)
	(zone
		(layers "In1.Cu" "In2.Cu")
		(hatch none 0.5)
		(connect_pads
			(clearance 0)
		)
		(min_thickness 0.25)
		(keepout
			(tracks not_allowed)
			(vias allowed)
			(pads allowed)
			(copperpour not_allowed)
			(footprints allowed)
		)
		(placement
			(enabled no)
			(sheetname "")
		)
		(fill yes
			(thermal_gap 0.5)
			(thermal_bridge_width 0.5)
			(island_removal_mode 0)
		)
		(polygon
			(pts
				(arc
					(start 421.090598 -217.071448)
					(mid 421.105477 -217.107369)
					(end 421.141398 -217.122248)
				)
				(arc
					(start 422.540938 -217.122248)
					(mid 422.576859 -217.107369)
					(end 422.591738 -217.071448)
				)
				(arc
					(start 422.591738 -216.662508)
					(mid 422.576859 -216.626587)
					(end 422.540938 -216.611708)
				)
				(arc
					(start 421.141398 -216.611708)
					(mid 421.105477 -216.626587)
					(end 421.090598 -216.662508)
				)
			)
		)
	)
	(zone
		(layers "In1.Cu" "In2.Cu")
		(hatch none 0.5)
		(connect_pads
			(clearance 0)
		)
		(min_thickness 0.25)
		(keepout
			(tracks not_allowed)
			(vias allowed)
			(pads allowed)
			(copperpour not_allowed)
			(footprints allowed)
		)
		(placement
			(enabled no)
			(sheetname "")
		)
		(fill yes
			(thermal_gap 0.5)
			(thermal_bridge_width 0.5)
			(island_removal_mode 0)
		)
		(polygon
			(pts
				(arc
					(start 177.250598 -291.021516)
					(mid 177.265477 -291.057437)
					(end 177.301398 -291.072316)
				)
				(arc
					(start 178.700938 -291.072316)
					(mid 178.736859 -291.057437)
					(end 178.751738 -291.021516)
				)
				(arc
					(start 178.751738 -290.612576)
					(mid 178.736859 -290.576655)
					(end 178.700938 -290.561776)
				)
				(arc
					(start 177.301398 -290.561776)
					(mid 177.265477 -290.576655)
					(end 177.250598 -290.612576)
				)
			)
		)
	)
	(zone
		(layers "In1.Cu" "In2.Cu")
		(hatch none 0.5)
		(connect_pads
			(clearance 0)
		)
		(min_thickness 0.25)
		(keepout
			(tracks not_allowed)
			(vias allowed)
			(pads allowed)
			(copperpour not_allowed)
			(footprints allowed)
		)
		(placement
			(enabled no)
			(sheetname "")
		)
		(fill yes
			(thermal_gap 0.5)
			(thermal_bridge_width 0.5)
			(island_removal_mode 0)
		)
		(polygon
			(pts
				(arc
					(start 312.236866 -304.621438)
					(mid 312.251745 -304.657359)
					(end 312.287666 -304.672238)
				)
				(arc
					(start 313.687206 -304.672238)
					(mid 313.723127 -304.657359)
					(end 313.738006 -304.621438)
				)
				(arc
					(start 313.738006 -304.212498)
					(mid 313.723127 -304.176577)
					(end 313.687206 -304.161698)
				)
				(arc
					(start 312.287666 -304.161698)
					(mid 312.251745 -304.176577)
					(end 312.236866 -304.212498)
				)
			)
		)
	)
	(zone
		(layers "In1.Cu" "In2.Cu")
		(hatch none 0.5)
		(connect_pads
			(clearance 0)
		)
		(min_thickness 0.25)
		(keepout
			(tracks not_allowed)
			(vias allowed)
			(pads allowed)
			(copperpour not_allowed)
			(footprints allowed)
		)
		(placement
			(enabled no)
			(sheetname "")
		)
		(fill yes
			(thermal_gap 0.5)
			(thermal_bridge_width 0.5)
			(island_removal_mode 0)
		)
		(polygon
			(pts
				(arc
					(start 14.93393 -210.27136)
					(mid 14.948809 -210.307281)
					(end 14.98473 -210.32216)
				)
				(arc
					(start 16.38427 -210.32216)
					(mid 16.420191 -210.307281)
					(end 16.43507 -210.27136)
				)
				(arc
					(start 16.43507 -209.86242)
					(mid 16.420191 -209.826499)
					(end 16.38427 -209.81162)
				)
				(arc
					(start 14.98473 -209.81162)
					(mid 14.948809 -209.826499)
					(end 14.93393 -209.86242)
				)
			)
		)
	)
	(zone
		(layers "In1.Cu" "In2.Cu")
		(hatch none 0.5)
		(connect_pads
			(clearance 0)
		)
		(min_thickness 0.25)
		(keepout
			(tracks not_allowed)
			(vias allowed)
			(pads allowed)
			(copperpour not_allowed)
			(footprints allowed)
		)
		(placement
			(enabled no)
			(sheetname "")
		)
		(fill yes
			(thermal_gap 0.5)
			(thermal_bridge_width 0.5)
			(island_removal_mode 0)
		)
		(polygon
			(pts
				(arc
					(start 162.162998 -218.77147)
					(mid 162.177877 -218.807391)
					(end 162.213798 -218.82227)
				)
				(arc
					(start 163.613338 -218.82227)
					(mid 163.649259 -218.807391)
					(end 163.664138 -218.77147)
				)
				(arc
					(start 163.664138 -218.36253)
					(mid 163.649259 -218.326609)
					(end 163.613338 -218.31173)
				)
				(arc
					(start 162.213798 -218.31173)
					(mid 162.177877 -218.326609)
					(end 162.162998 -218.36253)
				)
			)
		)
	)
	(zone
		(layers "In1.Cu" "In2.Cu")
		(hatch none 0.5)
		(connect_pads
			(clearance 0)
		)
		(min_thickness 0.25)
		(keepout
			(tracks not_allowed)
			(vias allowed)
			(pads allowed)
			(copperpour not_allowed)
			(footprints allowed)
		)
		(placement
			(enabled no)
			(sheetname "")
		)
		(fill yes
			(thermal_gap 0.5)
			(thermal_bridge_width 0.5)
			(island_removal_mode 0)
		)
		(polygon
			(pts
				(arc
					(start 410.103066 -309.721504)
					(mid 410.117945 -309.757425)
					(end 410.153866 -309.772304)
				)
				(arc
					(start 411.553406 -309.772304)
					(mid 411.589327 -309.757425)
					(end 411.604206 -309.721504)
				)
				(arc
					(start 411.604206 -309.312564)
					(mid 411.589327 -309.276643)
					(end 411.553406 -309.261764)
				)
				(arc
					(start 410.153866 -309.261764)
					(mid 410.117945 -309.276643)
					(end 410.103066 -309.312564)
				)
			)
		)
	)
	(zone
		(layers "In1.Cu" "In2.Cu")
		(hatch none 0.5)
		(connect_pads
			(clearance 0)
		)
		(min_thickness 0.25)
		(keepout
			(tracks not_allowed)
			(vias allowed)
			(pads allowed)
			(copperpour not_allowed)
			(footprints allowed)
		)
		(placement
			(enabled no)
			(sheetname "")
		)
		(fill yes
			(thermal_gap 0.5)
			(thermal_bridge_width 0.5)
			(island_removal_mode 0)
		)
		(polygon
			(pts
				(arc
					(start 11.490198 -205.171548)
					(mid 11.505077 -205.207469)
					(end 11.540998 -205.222348)
				)
				(arc
					(start 12.940538 -205.222348)
					(mid 12.976459 -205.207469)
					(end 12.991338 -205.171548)
				)
				(arc
					(start 12.991338 -204.762608)
					(mid 12.976459 -204.726687)
					(end 12.940538 -204.711808)
				)
				(arc
					(start 11.540998 -204.711808)
					(mid 11.505077 -204.726687)
					(end 11.490198 -204.762608)
				)
			)
		)
	)
	(zone
		(layers "In1.Cu" "In2.Cu")
		(hatch none 0.5)
		(connect_pads
			(clearance 0)
		)
		(min_thickness 0.25)
		(keepout
			(tracks not_allowed)
			(vias allowed)
			(pads allowed)
			(copperpour not_allowed)
			(footprints allowed)
		)
		(placement
			(enabled no)
			(sheetname "")
		)
		(fill yes
			(thermal_gap 0.5)
			(thermal_bridge_width 0.5)
			(island_removal_mode 0)
		)
		(polygon
			(pts
				(arc
					(start 277.961598 -237.471458)
					(mid 277.976477 -237.507379)
					(end 278.012398 -237.522258)
				)
				(arc
					(start 279.411938 -237.522258)
					(mid 279.447859 -237.507379)
					(end 279.462738 -237.471458)
				)
				(arc
					(start 279.462738 -237.062518)
					(mid 279.447859 -237.026597)
					(end 279.411938 -237.011718)
				)
				(arc
					(start 278.012398 -237.011718)
					(mid 277.976477 -237.026597)
					(end 277.961598 -237.062518)
				)
			)
		)
	)
	(zone
		(layers "In1.Cu" "In2.Cu")
		(hatch none 0.5)
		(connect_pads
			(clearance 0)
		)
		(min_thickness 0.25)
		(keepout
			(tracks not_allowed)
			(vias allowed)
			(pads allowed)
			(copperpour not_allowed)
			(footprints allowed)
		)
		(placement
			(enabled no)
			(sheetname "")
		)
		(fill yes
			(thermal_gap 0.5)
			(thermal_bridge_width 0.5)
			(island_removal_mode 0)
		)
		(polygon
			(pts
				(arc
					(start 34.121598 -240.871502)
					(mid 34.136477 -240.907423)
					(end 34.172398 -240.922302)
				)
				(arc
					(start 35.571938 -240.922302)
					(mid 35.607859 -240.907423)
					(end 35.622738 -240.871502)
				)
				(arc
					(start 35.622738 -240.462562)
					(mid 35.607859 -240.426641)
					(end 35.571938 -240.411762)
				)
				(arc
					(start 34.172398 -240.411762)
					(mid 34.136477 -240.426641)
					(end 34.121598 -240.462562)
				)
			)
		)
	)
	(zone
		(layers "In1.Cu" "In2.Cu")
		(hatch none 0.5)
		(connect_pads
			(clearance 0)
		)
		(min_thickness 0.25)
		(keepout
			(tracks not_allowed)
			(vias allowed)
			(pads allowed)
			(copperpour not_allowed)
			(footprints allowed)
		)
		(placement
			(enabled no)
			(sheetname "")
		)
		(fill yes
			(thermal_gap 0.5)
			(thermal_bridge_width 0.5)
			(island_removal_mode 0)
		)
		(polygon
			(pts
				(arc
					(start 162.162998 -289.321494)
					(mid 162.177877 -289.357415)
					(end 162.213798 -289.372294)
				)
				(arc
					(start 163.613338 -289.372294)
					(mid 163.649259 -289.357415)
					(end 163.664138 -289.321494)
				)
				(arc
					(start 163.664138 -288.912554)
					(mid 163.649259 -288.876633)
					(end 163.613338 -288.861754)
				)
				(arc
					(start 162.213798 -288.861754)
					(mid 162.177877 -288.876633)
					(end 162.162998 -288.912554)
				)
			)
		)
	)
	(zone
		(layers "In1.Cu" "In2.Cu")
		(hatch none 0.5)
		(connect_pads
			(clearance 0)
		)
		(min_thickness 0.25)
		(keepout
			(tracks not_allowed)
			(vias allowed)
			(pads allowed)
			(copperpour not_allowed)
			(footprints allowed)
		)
		(placement
			(enabled no)
			(sheetname "")
		)
		(fill yes
			(thermal_gap 0.5)
			(thermal_bridge_width 0.5)
			(island_removal_mode 0)
		)
		(polygon
			(pts
				(arc
					(start 462.909666 -234.921298)
					(mid 462.924545 -234.957219)
					(end 462.960466 -234.972098)
				)
				(arc
					(start 464.360006 -234.972098)
					(mid 464.395927 -234.957219)
					(end 464.410806 -234.921298)
				)
				(arc
					(start 464.410806 -234.512358)
					(mid 464.395927 -234.476437)
					(end 464.360006 -234.461558)
				)
				(arc
					(start 462.960466 -234.461558)
					(mid 462.924545 -234.476437)
					(end 462.909666 -234.512358)
				)
			)
		)
	)
	(zone
		(layers "In1.Cu" "In2.Cu")
		(hatch none 0.5)
		(connect_pads
			(clearance 0)
		)
		(min_thickness 0.25)
		(keepout
			(tracks not_allowed)
			(vias allowed)
			(pads allowed)
			(copperpour not_allowed)
			(footprints allowed)
		)
		(placement
			(enabled no)
			(sheetname "")
		)
		(fill yes
			(thermal_gap 0.5)
			(thermal_bridge_width 0.5)
			(island_removal_mode 0)
		)
		(polygon
			(pts
				(arc
					(start 277.961598 -279.121362)
					(mid 277.976477 -279.157283)
					(end 278.012398 -279.172162)
				)
				(arc
					(start 279.411938 -279.172162)
					(mid 279.447859 -279.157283)
					(end 279.462738 -279.121362)
				)
				(arc
					(start 279.462738 -278.712422)
					(mid 279.447859 -278.676501)
					(end 279.411938 -278.661622)
				)
				(arc
					(start 278.012398 -278.661622)
					(mid 277.976477 -278.676501)
					(end 277.961598 -278.712422)
				)
			)
		)
	)
	(zone
		(layers "In1.Cu" "In2.Cu")
		(hatch none 0.5)
		(connect_pads
			(clearance 0)
		)
		(min_thickness 0.25)
		(keepout
			(tracks not_allowed)
			(vias allowed)
			(pads allowed)
			(copperpour not_allowed)
			(footprints allowed)
		)
		(placement
			(enabled no)
			(sheetname "")
		)
		(fill yes
			(thermal_gap 0.5)
			(thermal_bridge_width 0.5)
			(island_removal_mode 0)
		)
		(polygon
			(pts
				(arc
					(start 312.236866 -312.27141)
					(mid 312.251745 -312.307331)
					(end 312.287666 -312.32221)
				)
				(arc
					(start 313.687206 -312.32221)
					(mid 313.723127 -312.307331)
					(end 313.738006 -312.27141)
				)
				(arc
					(start 313.738006 -311.86247)
					(mid 313.723127 -311.826549)
					(end 313.687206 -311.81167)
				)
				(arc
					(start 312.287666 -311.81167)
					(mid 312.251745 -311.826549)
					(end 312.236866 -311.86247)
				)
			)
		)
	)
	(zone
		(layers "In1.Cu" "In2.Cu")
		(hatch none 0.5)
		(connect_pads
			(clearance 0)
		)
		(min_thickness 0.25)
		(keepout
			(tracks not_allowed)
			(vias allowed)
			(pads allowed)
			(copperpour not_allowed)
			(footprints allowed)
		)
		(placement
			(enabled no)
			(sheetname "")
		)
		(fill yes
			(thermal_gap 0.5)
			(thermal_bridge_width 0.5)
			(island_removal_mode 0)
		)
		(polygon
			(pts
				(arc
					(start 184.794398 -223.871536)
					(mid 184.809277 -223.907457)
					(end 184.845198 -223.922336)
				)
				(arc
					(start 186.244738 -223.922336)
					(mid 186.280659 -223.907457)
					(end 186.295538 -223.871536)
				)
				(arc
					(start 186.295538 -223.462596)
					(mid 186.280659 -223.426675)
					(end 186.244738 -223.411796)
				)
				(arc
					(start 184.845198 -223.411796)
					(mid 184.809277 -223.426675)
					(end 184.794398 -223.462596)
				)
			)
		)
	)
	(zone
		(layers "In1.Cu" "In2.Cu")
		(hatch none 0.5)
		(connect_pads
			(clearance 0)
		)
		(min_thickness 0.25)
		(keepout
			(tracks not_allowed)
			(vias allowed)
			(pads allowed)
			(copperpour not_allowed)
			(footprints allowed)
		)
		(placement
			(enabled no)
			(sheetname "")
		)
		(fill yes
			(thermal_gap 0.5)
			(thermal_bridge_width 0.5)
			(island_removal_mode 0)
		)
		(polygon
			(pts
				(arc
					(start 203.32573 -235.771436)
					(mid 203.340609 -235.807357)
					(end 203.37653 -235.822236)
				)
				(arc
					(start 204.77607 -235.822236)
					(mid 204.811991 -235.807357)
					(end 204.82687 -235.771436)
				)
				(arc
					(start 204.82687 -235.362496)
					(mid 204.811991 -235.326575)
					(end 204.77607 -235.311696)
				)
				(arc
					(start 203.37653 -235.311696)
					(mid 203.340609 -235.326575)
					(end 203.32573 -235.362496)
				)
			)
		)
	)
	(zone
		(layers "In1.Cu" "In2.Cu")
		(hatch none 0.5)
		(connect_pads
			(clearance 0)
		)
		(min_thickness 0.25)
		(keepout
			(tracks not_allowed)
			(vias allowed)
			(pads allowed)
			(copperpour not_allowed)
			(footprints allowed)
		)
		(placement
			(enabled no)
			(sheetname "")
		)
		(fill yes
			(thermal_gap 0.5)
			(thermal_bridge_width 0.5)
			(island_removal_mode 0)
		)
		(polygon
			(pts
				(arc
					(start 177.250598 -268.921484)
					(mid 177.265477 -268.957405)
					(end 177.301398 -268.972284)
				)
				(arc
					(start 178.700938 -268.972284)
					(mid 178.736859 -268.957405)
					(end 178.751738 -268.921484)
				)
				(arc
					(start 178.751738 -268.512544)
					(mid 178.736859 -268.476623)
					(end 178.700938 -268.461744)
				)
				(arc
					(start 177.301398 -268.461744)
					(mid 177.265477 -268.476623)
					(end 177.250598 -268.512544)
				)
			)
		)
	)
	(zone
		(layers "In1.Cu" "In2.Cu")
		(hatch none 0.5)
		(connect_pads
			(clearance 0)
		)
		(min_thickness 0.25)
		(keepout
			(tracks not_allowed)
			(vias allowed)
			(pads allowed)
			(copperpour not_allowed)
			(footprints allowed)
		)
		(placement
			(enabled no)
			(sheetname "")
		)
		(fill yes
			(thermal_gap 0.5)
			(thermal_bridge_width 0.5)
			(island_removal_mode 0)
		)
		(polygon
			(pts
				(arc
					(start 274.517866 -218.77147)
					(mid 274.532745 -218.807391)
					(end 274.568666 -218.82227)
				)
				(arc
					(start 275.968206 -218.82227)
					(mid 276.004127 -218.807391)
					(end 276.019006 -218.77147)
				)
				(arc
					(start 276.019006 -218.36253)
					(mid 276.004127 -218.326609)
					(end 275.968206 -218.31173)
				)
				(arc
					(start 274.568666 -218.31173)
					(mid 274.532745 -218.326609)
					(end 274.517866 -218.36253)
				)
			)
		)
	)
	(zone
		(layers "In1.Cu" "In2.Cu")
		(hatch none 0.5)
		(connect_pads
			(clearance 0)
		)
		(min_thickness 0.25)
		(keepout
			(tracks not_allowed)
			(vias allowed)
			(pads allowed)
			(copperpour not_allowed)
			(footprints allowed)
		)
		(placement
			(enabled no)
			(sheetname "")
		)
		(fill yes
			(thermal_gap 0.5)
			(thermal_bridge_width 0.5)
			(island_removal_mode 0)
		)
		(polygon
			(pts
				(arc
					(start 195.78193 -244.271292)
					(mid 195.796809 -244.307213)
					(end 195.83273 -244.322092)
				)
				(arc
					(start 197.23227 -244.322092)
					(mid 197.268191 -244.307213)
					(end 197.28307 -244.271292)
				)
				(arc
					(start 197.28307 -243.862352)
					(mid 197.268191 -243.826431)
					(end 197.23227 -243.811552)
				)
				(arc
					(start 195.83273 -243.811552)
					(mid 195.796809 -243.826431)
					(end 195.78193 -243.862352)
				)
			)
		)
	)
	(zone
		(layers "In1.Cu" "In2.Cu")
		(hatch none 0.5)
		(connect_pads
			(clearance 0)
		)
		(min_thickness 0.25)
		(keepout
			(tracks not_allowed)
			(vias allowed)
			(pads allowed)
			(copperpour not_allowed)
			(footprints allowed)
		)
		(placement
			(enabled no)
			(sheetname "")
		)
		(fill yes
			(thermal_gap 0.5)
			(thermal_bridge_width 0.5)
			(island_removal_mode 0)
		)
		(polygon
			(pts
				(arc
					(start 297.149266 -197.521322)
					(mid 297.164145 -197.557243)
					(end 297.200066 -197.572122)
				)
				(arc
					(start 298.599606 -197.572122)
					(mid 298.635527 -197.557243)
					(end 298.650406 -197.521322)
				)
				(arc
					(start 298.650406 -197.112382)
					(mid 298.635527 -197.076461)
					(end 298.599606 -197.061582)
				)
				(arc
					(start 297.200066 -197.061582)
					(mid 297.164145 -197.076461)
					(end 297.149266 -197.112382)
				)
			)
		)
	)
	(zone
		(layers "In1.Cu" "In2.Cu")
		(hatch none 0.5)
		(connect_pads
			(clearance 0)
		)
		(min_thickness 0.25)
		(keepout
			(tracks not_allowed)
			(vias allowed)
			(pads allowed)
			(copperpour not_allowed)
			(footprints allowed)
		)
		(placement
			(enabled no)
			(sheetname "")
		)
		(fill yes
			(thermal_gap 0.5)
			(thermal_bridge_width 0.5)
			(island_removal_mode 0)
		)
		(polygon
			(pts
				(arc
					(start 162.162998 -313.971432)
					(mid 162.177877 -314.007353)
					(end 162.213798 -314.022232)
				)
				(arc
					(start 163.613338 -314.022232)
					(mid 163.649259 -314.007353)
					(end 163.664138 -313.971432)
				)
				(arc
					(start 163.664138 -313.562492)
					(mid 163.649259 -313.526571)
					(end 163.613338 -313.511692)
				)
				(arc
					(start 162.213798 -313.511692)
					(mid 162.177877 -313.526571)
					(end 162.162998 -313.562492)
				)
			)
		)
	)
	(zone
		(layers "In1.Cu" "In2.Cu")
		(hatch none 0.5)
		(connect_pads
			(clearance 0)
		)
		(min_thickness 0.25)
		(keepout
			(tracks not_allowed)
			(vias allowed)
			(pads allowed)
			(copperpour not_allowed)
			(footprints allowed)
		)
		(placement
			(enabled no)
			(sheetname "")
		)
		(fill yes
			(thermal_gap 0.5)
			(thermal_bridge_width 0.5)
			(island_removal_mode 0)
		)
		(polygon
			(pts
				(arc
					(start 30.02153 -213.671404)
					(mid 30.036409 -213.707325)
					(end 30.07233 -213.722204)
				)
				(arc
					(start 31.47187 -213.722204)
					(mid 31.507791 -213.707325)
					(end 31.52267 -213.671404)
				)
				(arc
					(start 31.52267 -213.262464)
					(mid 31.507791 -213.226543)
					(end 31.47187 -213.211664)
				)
				(arc
					(start 30.07233 -213.211664)
					(mid 30.036409 -213.226543)
					(end 30.02153 -213.262464)
				)
			)
		)
	)
	(zone
		(layers "In1.Cu" "In2.Cu")
		(hatch none 0.5)
		(connect_pads
			(clearance 0)
		)
		(min_thickness 0.25)
		(keepout
			(tracks not_allowed)
			(vias allowed)
			(pads allowed)
			(copperpour not_allowed)
			(footprints allowed)
		)
		(placement
			(enabled no)
			(sheetname "")
		)
		(fill yes
			(thermal_gap 0.5)
			(thermal_bridge_width 0.5)
			(island_removal_mode 0)
		)
		(polygon
			(pts
				(arc
					(start 214.969598 -248.521474)
					(mid 214.984477 -248.557395)
					(end 215.020398 -248.572274)
				)
				(arc
					(start 216.419938 -248.572274)
					(mid 216.455859 -248.557395)
					(end 216.470738 -248.521474)
				)
				(arc
					(start 216.470738 -248.112534)
					(mid 216.455859 -248.076613)
					(end 216.419938 -248.061734)
				)
				(arc
					(start 215.020398 -248.061734)
					(mid 214.984477 -248.076613)
					(end 214.969598 -248.112534)
				)
			)
		)
	)
	(zone
		(layers "In1.Cu" "In2.Cu")
		(hatch none 0.5)
		(connect_pads
			(clearance 0)
		)
		(min_thickness 0.25)
		(keepout
			(tracks not_allowed)
			(vias allowed)
			(pads allowed)
			(copperpour not_allowed)
			(footprints allowed)
		)
		(placement
			(enabled no)
			(sheetname "")
		)
		(fill yes
			(thermal_gap 0.5)
			(thermal_bridge_width 0.5)
			(island_removal_mode 0)
		)
		(polygon
			(pts
				(arc
					(start 41.665398 -292.721538)
					(mid 41.680277 -292.757459)
					(end 41.716198 -292.772338)
				)
				(arc
					(start 43.115738 -292.772338)
					(mid 43.151659 -292.757459)
					(end 43.166538 -292.721538)
				)
				(arc
					(start 43.166538 -292.312598)
					(mid 43.151659 -292.276677)
					(end 43.115738 -292.261798)
				)
				(arc
					(start 41.716198 -292.261798)
					(mid 41.680277 -292.276677)
					(end 41.665398 -292.312598)
				)
			)
		)
	)
	(zone
		(layers "In1.Cu" "In2.Cu")
		(hatch none 0.5)
		(connect_pads
			(clearance 0)
		)
		(min_thickness 0.25)
		(keepout
			(tracks not_allowed)
			(vias allowed)
			(pads allowed)
			(copperpour not_allowed)
			(footprints allowed)
		)
		(placement
			(enabled no)
			(sheetname "")
		)
		(fill yes
			(thermal_gap 0.5)
			(thermal_bridge_width 0.5)
			(island_removal_mode 0)
		)
		(polygon
			(pts
				(arc
					(start 22.47773 -230.67137)
					(mid 22.492609 -230.707291)
					(end 22.52853 -230.72217)
				)
				(arc
					(start 23.92807 -230.72217)
					(mid 23.963991 -230.707291)
					(end 23.97887 -230.67137)
				)
				(arc
					(start 23.97887 -230.26243)
					(mid 23.963991 -230.226509)
					(end 23.92807 -230.21163)
				)
				(arc
					(start 22.52853 -230.21163)
					(mid 22.492609 -230.226509)
					(end 22.47773 -230.26243)
				)
			)
		)
	)
	(zone
		(layers "In1.Cu" "In2.Cu")
		(hatch none 0.5)
		(connect_pads
			(clearance 0)
		)
		(min_thickness 0.25)
		(keepout
			(tracks not_allowed)
			(vias allowed)
			(pads allowed)
			(copperpour not_allowed)
			(footprints allowed)
		)
		(placement
			(enabled no)
			(sheetname "")
		)
		(fill yes
			(thermal_gap 0.5)
			(thermal_bridge_width 0.5)
			(island_removal_mode 0)
		)
		(polygon
			(pts
				(arc
					(start 293.049198 -221.321376)
					(mid 293.064077 -221.357297)
					(end 293.099998 -221.372176)
				)
				(arc
					(start 294.499538 -221.372176)
					(mid 294.535459 -221.357297)
					(end 294.550338 -221.321376)
				)
				(arc
					(start 294.550338 -220.912436)
					(mid 294.535459 -220.876515)
					(end 294.499538 -220.861636)
				)
				(arc
					(start 293.099998 -220.861636)
					(mid 293.064077 -220.876515)
					(end 293.049198 -220.912436)
				)
			)
		)
	)
	(zone
		(layers "In1.Cu" "In2.Cu")
		(hatch none 0.5)
		(connect_pads
			(clearance 0)
		)
		(min_thickness 0.25)
		(keepout
			(tracks not_allowed)
			(vias allowed)
			(pads allowed)
			(copperpour not_allowed)
			(footprints allowed)
		)
		(placement
			(enabled no)
			(sheetname "")
		)
		(fill yes
			(thermal_gap 0.5)
			(thermal_bridge_width 0.5)
			(island_removal_mode 0)
		)
		(polygon
			(pts
				(arc
					(start 180.69433 -299.521372)
					(mid 180.709209 -299.557293)
					(end 180.74513 -299.572172)
				)
				(arc
					(start 182.14467 -299.572172)
					(mid 182.180591 -299.557293)
					(end 182.19547 -299.521372)
				)
				(arc
					(start 182.19547 -299.112432)
					(mid 182.180591 -299.076511)
					(end 182.14467 -299.061632)
				)
				(arc
					(start 180.74513 -299.061632)
					(mid 180.709209 -299.076511)
					(end 180.69433 -299.112432)
				)
			)
		)
	)
	(zone
		(layers "In1.Cu" "In2.Cu")
		(hatch none 0.5)
		(connect_pads
			(clearance 0)
		)
		(min_thickness 0.25)
		(keepout
			(tracks not_allowed)
			(vias allowed)
			(pads allowed)
			(copperpour not_allowed)
			(footprints allowed)
		)
		(placement
			(enabled no)
			(sheetname "")
		)
		(fill yes
			(thermal_gap 0.5)
			(thermal_bridge_width 0.5)
			(island_removal_mode 0)
		)
		(polygon
			(pts
				(arc
					(start 440.278266 -302.071532)
					(mid 440.293145 -302.107453)
					(end 440.329066 -302.122332)
				)
				(arc
					(start 441.728606 -302.122332)
					(mid 441.764527 -302.107453)
					(end 441.779406 -302.071532)
				)
				(arc
					(start 441.779406 -301.662592)
					(mid 441.764527 -301.626671)
					(end 441.728606 -301.611792)
				)
				(arc
					(start 440.329066 -301.611792)
					(mid 440.293145 -301.626671)
					(end 440.278266 -301.662592)
				)
			)
		)
	)
	(zone
		(layers "In1.Cu" "In2.Cu")
		(hatch none 0.5)
		(connect_pads
			(clearance 0)
		)
		(min_thickness 0.25)
		(keepout
			(tracks not_allowed)
			(vias allowed)
			(pads allowed)
			(copperpour not_allowed)
			(footprints allowed)
		)
		(placement
			(enabled no)
			(sheetname "")
		)
		(fill yes
			(thermal_gap 0.5)
			(thermal_bridge_width 0.5)
			(island_removal_mode 0)
		)
		(polygon
			(pts
				(arc
					(start 282.061666 -315.671454)
					(mid 282.076545 -315.707375)
					(end 282.112466 -315.722254)
				)
				(arc
					(start 283.512006 -315.722254)
					(mid 283.547927 -315.707375)
					(end 283.562806 -315.671454)
				)
				(arc
					(start 283.562806 -315.262514)
					(mid 283.547927 -315.226593)
					(end 283.512006 -315.211714)
				)
				(arc
					(start 282.112466 -315.211714)
					(mid 282.076545 -315.226593)
					(end 282.061666 -315.262514)
				)
			)
		)
	)
	(zone
		(layers "In1.Cu" "In2.Cu")
		(hatch none 0.5)
		(connect_pads
			(clearance 0)
		)
		(min_thickness 0.25)
		(keepout
			(tracks not_allowed)
			(vias allowed)
			(pads allowed)
			(copperpour not_allowed)
			(footprints allowed)
		)
		(placement
			(enabled no)
			(sheetname "")
		)
		(fill yes
			(thermal_gap 0.5)
			(thermal_bridge_width 0.5)
			(island_removal_mode 0)
		)
		(polygon
			(pts
				(arc
					(start 22.47773 -288.471356)
					(mid 22.492609 -288.507277)
					(end 22.52853 -288.522156)
				)
				(arc
					(start 23.92807 -288.522156)
					(mid 23.963991 -288.507277)
					(end 23.97887 -288.471356)
				)
				(arc
					(start 23.97887 -288.062416)
					(mid 23.963991 -288.026495)
					(end 23.92807 -288.011616)
				)
				(arc
					(start 22.52853 -288.011616)
					(mid 22.492609 -288.026495)
					(end 22.47773 -288.062416)
				)
			)
		)
	)
	(zone
		(layers "In1.Cu" "In2.Cu")
		(hatch none 0.5)
		(connect_pads
			(clearance 0)
		)
		(min_thickness 0.25)
		(keepout
			(tracks not_allowed)
			(vias allowed)
			(pads allowed)
			(copperpour not_allowed)
			(footprints allowed)
		)
		(placement
			(enabled no)
			(sheetname "")
		)
		(fill yes
			(thermal_gap 0.5)
			(thermal_bridge_width 0.5)
			(island_removal_mode 0)
		)
		(polygon
			(pts
				(arc
					(start 158.06293 -249.371358)
					(mid 158.077809 -249.407279)
					(end 158.11373 -249.422158)
				)
				(arc
					(start 159.51327 -249.422158)
					(mid 159.549191 -249.407279)
					(end 159.56407 -249.371358)
				)
				(arc
					(start 159.56407 -248.962418)
					(mid 159.549191 -248.926497)
					(end 159.51327 -248.911618)
				)
				(arc
					(start 158.11373 -248.911618)
					(mid 158.077809 -248.926497)
					(end 158.06293 -248.962418)
				)
			)
		)
	)
	(zone
		(layers "In1.Cu" "In2.Cu")
		(hatch none 0.5)
		(connect_pads
			(clearance 0)
		)
		(min_thickness 0.25)
		(keepout
			(tracks not_allowed)
			(vias allowed)
			(pads allowed)
			(copperpour not_allowed)
			(footprints allowed)
		)
		(placement
			(enabled no)
			(sheetname "")
		)
		(fill yes
			(thermal_gap 0.5)
			(thermal_bridge_width 0.5)
			(island_removal_mode 0)
		)
		(polygon
			(pts
				(arc
					(start 455.365866 -223.871536)
					(mid 455.380745 -223.907457)
					(end 455.416666 -223.922336)
				)
				(arc
					(start 456.816206 -223.922336)
					(mid 456.852127 -223.907457)
					(end 456.867006 -223.871536)
				)
				(arc
					(start 456.867006 -223.462596)
					(mid 456.852127 -223.426675)
					(end 456.816206 -223.411796)
				)
				(arc
					(start 455.416666 -223.411796)
					(mid 455.380745 -223.426675)
					(end 455.365866 -223.462596)
				)
			)
		)
	)
	(zone
		(layers "In1.Cu" "In2.Cu")
		(hatch none 0.5)
		(connect_pads
			(clearance 0)
		)
		(min_thickness 0.25)
		(keepout
			(tracks not_allowed)
			(vias allowed)
			(pads allowed)
			(copperpour not_allowed)
			(footprints allowed)
		)
		(placement
			(enabled no)
			(sheetname "")
		)
		(fill yes
			(thermal_gap 0.5)
			(thermal_bridge_width 0.5)
			(island_removal_mode 0)
		)
		(polygon
			(pts
				(arc
					(start 14.93393 -244.271292)
					(mid 14.948809 -244.307213)
					(end 14.98473 -244.322092)
				)
				(arc
					(start 16.38427 -244.322092)
					(mid 16.420191 -244.307213)
					(end 16.43507 -244.271292)
				)
				(arc
					(start 16.43507 -243.862352)
					(mid 16.420191 -243.826431)
					(end 16.38427 -243.811552)
				)
				(arc
					(start 14.98473 -243.811552)
					(mid 14.948809 -243.826431)
					(end 14.93393 -243.862352)
				)
			)
		)
	)
	(zone
		(layers "In1.Cu" "In2.Cu")
		(hatch none 0.5)
		(connect_pads
			(clearance 0)
		)
		(min_thickness 0.25)
		(keepout
			(tracks not_allowed)
			(vias allowed)
			(pads allowed)
			(copperpour not_allowed)
			(footprints allowed)
		)
		(placement
			(enabled no)
			(sheetname "")
		)
		(fill yes
			(thermal_gap 0.5)
			(thermal_bridge_width 0.5)
			(island_removal_mode 0)
		)
		(polygon
			(pts
				(arc
					(start 45.10913 -238.321342)
					(mid 45.124009 -238.357263)
					(end 45.15993 -238.372142)
				)
				(arc
					(start 46.55947 -238.372142)
					(mid 46.595391 -238.357263)
					(end 46.61027 -238.321342)
				)
				(arc
					(start 46.61027 -237.912402)
					(mid 46.595391 -237.876481)
					(end 46.55947 -237.861602)
				)
				(arc
					(start 45.15993 -237.861602)
					(mid 45.124009 -237.876481)
					(end 45.10913 -237.912402)
				)
			)
		)
	)
	(zone
		(layers "In1.Cu" "In2.Cu")
		(hatch none 0.5)
		(connect_pads
			(clearance 0)
		)
		(min_thickness 0.25)
		(keepout
			(tracks not_allowed)
			(vias allowed)
			(pads allowed)
			(copperpour not_allowed)
			(footprints allowed)
		)
		(placement
			(enabled no)
			(sheetname "")
		)
		(fill yes
			(thermal_gap 0.5)
			(thermal_bridge_width 0.5)
			(island_removal_mode 0)
		)
		(polygon
			(pts
				(arc
					(start 22.47773 -294.421306)
					(mid 22.492609 -294.457227)
					(end 22.52853 -294.472106)
				)
				(arc
					(start 23.92807 -294.472106)
					(mid 23.963991 -294.457227)
					(end 23.97887 -294.421306)
				)
				(arc
					(start 23.97887 -294.012366)
					(mid 23.963991 -293.976445)
					(end 23.92807 -293.961566)
				)
				(arc
					(start 22.52853 -293.961566)
					(mid 22.492609 -293.976445)
					(end 22.47773 -294.012366)
				)
			)
		)
	)
	(zone
		(layers "In1.Cu" "In2.Cu")
		(hatch none 0.5)
		(connect_pads
			(clearance 0)
		)
		(min_thickness 0.25)
		(keepout
			(tracks not_allowed)
			(vias allowed)
			(pads allowed)
			(copperpour not_allowed)
			(footprints allowed)
		)
		(placement
			(enabled no)
			(sheetname "")
		)
		(fill yes
			(thermal_gap 0.5)
			(thermal_bridge_width 0.5)
			(island_removal_mode 0)
		)
		(polygon
			(pts
				(arc
					(start 192.338198 -285.92145)
					(mid 192.353077 -285.957371)
					(end 192.388998 -285.97225)
				)
				(arc
					(start 193.788538 -285.97225)
					(mid 193.824459 -285.957371)
					(end 193.839338 -285.92145)
				)
				(arc
					(start 193.839338 -285.51251)
					(mid 193.824459 -285.476589)
					(end 193.788538 -285.46171)
				)
				(arc
					(start 192.388998 -285.46171)
					(mid 192.353077 -285.476589)
					(end 192.338198 -285.51251)
				)
			)
		)
	)
	(zone
		(layers "In1.Cu" "In2.Cu")
		(hatch none 0.5)
		(connect_pads
			(clearance 0)
		)
		(min_thickness 0.25)
		(keepout
			(tracks not_allowed)
			(vias allowed)
			(pads allowed)
			(copperpour not_allowed)
			(footprints allowed)
		)
		(placement
			(enabled no)
			(sheetname "")
		)
		(fill yes
			(thermal_gap 0.5)
			(thermal_bridge_width 0.5)
			(island_removal_mode 0)
		)
		(polygon
			(pts
				(arc
					(start 451.265798 -224.72142)
					(mid 451.280677 -224.757341)
					(end 451.316598 -224.77222)
				)
				(arc
					(start 452.716138 -224.77222)
					(mid 452.752059 -224.757341)
					(end 452.766938 -224.72142)
				)
				(arc
					(start 452.766938 -224.31248)
					(mid 452.752059 -224.276559)
					(end 452.716138 -224.26168)
				)
				(arc
					(start 451.316598 -224.26168)
					(mid 451.280677 -224.276559)
					(end 451.265798 -224.31248)
				)
			)
		)
	)
	(zone
		(layers "In1.Cu" "In2.Cu")
		(hatch none 0.5)
		(connect_pads
			(clearance 0)
		)
		(min_thickness 0.25)
		(keepout
			(tracks not_allowed)
			(vias allowed)
			(pads allowed)
			(copperpour not_allowed)
			(footprints allowed)
		)
		(placement
			(enabled no)
			(sheetname "")
		)
		(fill yes
			(thermal_gap 0.5)
			(thermal_bridge_width 0.5)
			(island_removal_mode 0)
		)
		(polygon
			(pts
				(arc
					(start 34.121598 -308.021482)
					(mid 34.136477 -308.057403)
					(end 34.172398 -308.072282)
				)
				(arc
					(start 35.571938 -308.072282)
					(mid 35.607859 -308.057403)
					(end 35.622738 -308.021482)
				)
				(arc
					(start 35.622738 -307.612542)
					(mid 35.607859 -307.576621)
					(end 35.571938 -307.561742)
				)
				(arc
					(start 34.172398 -307.561742)
					(mid 34.136477 -307.576621)
					(end 34.121598 -307.612542)
				)
			)
		)
	)
	(zone
		(layers "In1.Cu" "In2.Cu")
		(hatch none 0.5)
		(connect_pads
			(clearance 0)
		)
		(min_thickness 0.25)
		(keepout
			(tracks not_allowed)
			(vias allowed)
			(pads allowed)
			(copperpour not_allowed)
			(footprints allowed)
		)
		(placement
			(enabled no)
			(sheetname "")
		)
		(fill yes
			(thermal_gap 0.5)
			(thermal_bridge_width 0.5)
			(island_removal_mode 0)
		)
		(polygon
			(pts
				(arc
					(start 195.78193 -297.82135)
					(mid 195.796809 -297.857271)
					(end 195.83273 -297.87215)
				)
				(arc
					(start 197.23227 -297.87215)
					(mid 197.268191 -297.857271)
					(end 197.28307 -297.82135)
				)
				(arc
					(start 197.28307 -297.41241)
					(mid 197.268191 -297.376489)
					(end 197.23227 -297.36161)
				)
				(arc
					(start 195.83273 -297.36161)
					(mid 195.796809 -297.376489)
					(end 195.78193 -297.41241)
				)
			)
		)
	)
	(zone
		(layers "In1.Cu" "In2.Cu")
		(hatch none 0.5)
		(connect_pads
			(clearance 0)
		)
		(min_thickness 0.25)
		(keepout
			(tracks not_allowed)
			(vias allowed)
			(pads allowed)
			(copperpour not_allowed)
			(footprints allowed)
		)
		(placement
			(enabled no)
			(sheetname "")
		)
		(fill yes
			(thermal_gap 0.5)
			(thermal_bridge_width 0.5)
			(island_removal_mode 0)
		)
		(polygon
			(pts
				(arc
					(start 451.265798 -200.921366)
					(mid 451.280677 -200.957287)
					(end 451.316598 -200.972166)
				)
				(arc
					(start 452.716138 -200.972166)
					(mid 452.752059 -200.957287)
					(end 452.766938 -200.921366)
				)
				(arc
					(start 452.766938 -200.512426)
					(mid 452.752059 -200.476505)
					(end 452.716138 -200.461626)
				)
				(arc
					(start 451.316598 -200.461626)
					(mid 451.280677 -200.476505)
					(end 451.265798 -200.512426)
				)
			)
		)
	)
	(zone
		(layers "In1.Cu" "In2.Cu")
		(hatch none 0.5)
		(connect_pads
			(clearance 0)
		)
		(min_thickness 0.25)
		(keepout
			(tracks not_allowed)
			(vias allowed)
			(pads allowed)
			(copperpour not_allowed)
			(footprints allowed)
		)
		(placement
			(enabled no)
			(sheetname "")
		)
		(fill yes
			(thermal_gap 0.5)
			(thermal_bridge_width 0.5)
			(island_removal_mode 0)
		)
		(polygon
			(pts
				(arc
					(start 41.665398 -270.621506)
					(mid 41.680277 -270.657427)
					(end 41.716198 -270.672306)
				)
				(arc
					(start 43.115738 -270.672306)
					(mid 43.151659 -270.657427)
					(end 43.166538 -270.621506)
				)
				(arc
					(start 43.166538 -270.212566)
					(mid 43.151659 -270.176645)
					(end 43.115738 -270.161766)
				)
				(arc
					(start 41.716198 -270.161766)
					(mid 41.680277 -270.176645)
					(end 41.665398 -270.212566)
				)
			)
		)
	)
	(zone
		(layers "In1.Cu" "In2.Cu")
		(hatch none 0.5)
		(connect_pads
			(clearance 0)
		)
		(min_thickness 0.25)
		(keepout
			(tracks not_allowed)
			(vias allowed)
			(pads allowed)
			(copperpour not_allowed)
			(footprints allowed)
		)
		(placement
			(enabled no)
			(sheetname "")
		)
		(fill yes
			(thermal_gap 0.5)
			(thermal_bridge_width 0.5)
			(island_removal_mode 0)
		)
		(polygon
			(pts
				(arc
					(start 207.425798 -227.271326)
					(mid 207.440677 -227.307247)
					(end 207.476598 -227.322126)
				)
				(arc
					(start 208.876138 -227.322126)
					(mid 208.912059 -227.307247)
					(end 208.926938 -227.271326)
				)
				(arc
					(start 208.926938 -226.862386)
					(mid 208.912059 -226.826465)
					(end 208.876138 -226.811586)
				)
				(arc
					(start 207.476598 -226.811586)
					(mid 207.440677 -226.826465)
					(end 207.425798 -226.862386)
				)
			)
		)
	)
	(zone
		(layers "In1.Cu" "In2.Cu")
		(hatch none 0.5)
		(connect_pads
			(clearance 0)
		)
		(min_thickness 0.25)
		(keepout
			(tracks not_allowed)
			(vias allowed)
			(pads allowed)
			(copperpour not_allowed)
			(footprints allowed)
		)
		(placement
			(enabled no)
			(sheetname "")
		)
		(fill yes
			(thermal_gap 0.5)
			(thermal_bridge_width 0.5)
			(island_removal_mode 0)
		)
		(polygon
			(pts
				(arc
					(start 64.296798 -300.37151)
					(mid 64.311677 -300.407431)
					(end 64.347598 -300.42231)
				)
				(arc
					(start 65.747138 -300.42231)
					(mid 65.783059 -300.407431)
					(end 65.797938 -300.37151)
				)
				(arc
					(start 65.797938 -299.96257)
					(mid 65.783059 -299.926649)
					(end 65.747138 -299.91177)
				)
				(arc
					(start 64.347598 -299.91177)
					(mid 64.311677 -299.926649)
					(end 64.296798 -299.96257)
				)
			)
		)
	)
	(zone
		(layers "In1.Cu" "In2.Cu")
		(hatch none 0.5)
		(connect_pads
			(clearance 0)
		)
		(min_thickness 0.25)
		(keepout
			(tracks not_allowed)
			(vias allowed)
			(pads allowed)
			(copperpour not_allowed)
			(footprints allowed)
		)
		(placement
			(enabled no)
			(sheetname "")
		)
		(fill yes
			(thermal_gap 0.5)
			(thermal_bridge_width 0.5)
			(island_removal_mode 0)
		)
		(polygon
			(pts
				(arc
					(start 30.02153 -238.321342)
					(mid 30.036409 -238.357263)
					(end 30.07233 -238.372142)
				)
				(arc
					(start 31.47187 -238.372142)
					(mid 31.507791 -238.357263)
					(end 31.52267 -238.321342)
				)
				(arc
					(start 31.52267 -237.912402)
					(mid 31.507791 -237.876481)
					(end 31.47187 -237.861602)
				)
				(arc
					(start 30.07233 -237.861602)
					(mid 30.036409 -237.876481)
					(end 30.02153 -237.912402)
				)
			)
		)
	)
	(zone
		(layers "In1.Cu" "In2.Cu")
		(hatch none 0.5)
		(connect_pads
			(clearance 0)
		)
		(min_thickness 0.25)
		(keepout
			(tracks not_allowed)
			(vias allowed)
			(pads allowed)
			(copperpour not_allowed)
			(footprints allowed)
		)
		(placement
			(enabled no)
			(sheetname "")
		)
		(fill yes
			(thermal_gap 0.5)
			(thermal_bridge_width 0.5)
			(island_removal_mode 0)
		)
		(polygon
			(pts
				(arc
					(start 304.693066 -251.921518)
					(mid 304.707945 -251.957439)
					(end 304.743866 -251.972318)
				)
				(arc
					(start 306.143406 -251.972318)
					(mid 306.179327 -251.957439)
					(end 306.194206 -251.921518)
				)
				(arc
					(start 306.194206 -251.512578)
					(mid 306.179327 -251.476657)
					(end 306.143406 -251.461778)
				)
				(arc
					(start 304.743866 -251.461778)
					(mid 304.707945 -251.476657)
					(end 304.693066 -251.512578)
				)
			)
		)
	)
	(zone
		(layers "In1.Cu" "In2.Cu")
		(hatch none 0.5)
		(connect_pads
			(clearance 0)
		)
		(min_thickness 0.25)
		(keepout
			(tracks not_allowed)
			(vias allowed)
			(pads allowed)
			(copperpour not_allowed)
			(footprints allowed)
		)
		(placement
			(enabled no)
			(sheetname "")
		)
		(fill yes
			(thermal_gap 0.5)
			(thermal_bridge_width 0.5)
			(island_removal_mode 0)
		)
		(polygon
			(pts
				(arc
					(start 158.06293 -296.121328)
					(mid 158.077809 -296.157249)
					(end 158.11373 -296.172128)
				)
				(arc
					(start 159.51327 -296.172128)
					(mid 159.549191 -296.157249)
					(end 159.56407 -296.121328)
				)
				(arc
					(start 159.56407 -295.712388)
					(mid 159.549191 -295.676467)
					(end 159.51327 -295.661588)
				)
				(arc
					(start 158.11373 -295.661588)
					(mid 158.077809 -295.676467)
					(end 158.06293 -295.712388)
				)
			)
		)
	)
	(zone
		(layers "In1.Cu" "In2.Cu")
		(hatch none 0.5)
		(connect_pads
			(clearance 0)
		)
		(min_thickness 0.25)
		(keepout
			(tracks not_allowed)
			(vias allowed)
			(pads allowed)
			(copperpour not_allowed)
			(footprints allowed)
		)
		(placement
			(enabled no)
			(sheetname "")
		)
		(fill yes
			(thermal_gap 0.5)
			(thermal_bridge_width 0.5)
			(island_removal_mode 0)
		)
		(polygon
			(pts
				(arc
					(start 26.577798 -309.721504)
					(mid 26.592677 -309.757425)
					(end 26.628598 -309.772304)
				)
				(arc
					(start 28.028138 -309.772304)
					(mid 28.064059 -309.757425)
					(end 28.078938 -309.721504)
				)
				(arc
					(start 28.078938 -309.312564)
					(mid 28.064059 -309.276643)
					(end 28.028138 -309.261764)
				)
				(arc
					(start 26.628598 -309.261764)
					(mid 26.592677 -309.276643)
					(end 26.577798 -309.312564)
				)
			)
		)
	)
	(zone
		(layers "In1.Cu" "In2.Cu")
		(hatch none 0.5)
		(connect_pads
			(clearance 0)
		)
		(min_thickness 0.25)
		(keepout
			(tracks not_allowed)
			(vias allowed)
			(pads allowed)
			(copperpour not_allowed)
			(footprints allowed)
		)
		(placement
			(enabled no)
			(sheetname "")
		)
		(fill yes
			(thermal_gap 0.5)
			(thermal_bridge_width 0.5)
			(island_removal_mode 0)
		)
		(polygon
			(pts
				(arc
					(start 41.665398 -262.121396)
					(mid 41.680277 -262.157317)
					(end 41.716198 -262.172196)
				)
				(arc
					(start 43.115738 -262.172196)
					(mid 43.151659 -262.157317)
					(end 43.166538 -262.121396)
				)
				(arc
					(start 43.166538 -261.712456)
					(mid 43.151659 -261.676535)
					(end 43.115738 -261.661656)
				)
				(arc
					(start 41.716198 -261.661656)
					(mid 41.680277 -261.676535)
					(end 41.665398 -261.712456)
				)
			)
		)
	)
	(zone
		(layers "In1.Cu" "In2.Cu")
		(hatch none 0.5)
		(connect_pads
			(clearance 0)
		)
		(min_thickness 0.25)
		(keepout
			(tracks not_allowed)
			(vias allowed)
			(pads allowed)
			(copperpour not_allowed)
			(footprints allowed)
		)
		(placement
			(enabled no)
			(sheetname "")
		)
		(fill yes
			(thermal_gap 0.5)
			(thermal_bridge_width 0.5)
			(island_removal_mode 0)
		)
		(polygon
			(pts
				(arc
					(start 297.149266 -296.971466)
					(mid 297.164145 -297.007387)
					(end 297.200066 -297.022266)
				)
				(arc
					(start 298.599606 -297.022266)
					(mid 298.635527 -297.007387)
					(end 298.650406 -296.971466)
				)
				(arc
					(start 298.650406 -296.562526)
					(mid 298.635527 -296.526605)
					(end 298.599606 -296.511726)
				)
				(arc
					(start 297.200066 -296.511726)
					(mid 297.164145 -296.526605)
					(end 297.149266 -296.562526)
				)
			)
		)
	)
	(zone
		(layers "In1.Cu" "In2.Cu")
		(hatch none 0.5)
		(connect_pads
			(clearance 0)
		)
		(min_thickness 0.25)
		(keepout
			(tracks not_allowed)
			(vias allowed)
			(pads allowed)
			(copperpour not_allowed)
			(footprints allowed)
		)
		(placement
			(enabled no)
			(sheetname "")
		)
		(fill yes
			(thermal_gap 0.5)
			(thermal_bridge_width 0.5)
			(island_removal_mode 0)
		)
		(polygon
			(pts
				(arc
					(start 195.78193 -219.621354)
					(mid 195.796809 -219.657275)
					(end 195.83273 -219.672154)
				)
				(arc
					(start 197.23227 -219.672154)
					(mid 197.268191 -219.657275)
					(end 197.28307 -219.621354)
				)
				(arc
					(start 197.28307 -219.212414)
					(mid 197.268191 -219.176493)
					(end 197.23227 -219.161614)
				)
				(arc
					(start 195.83273 -219.161614)
					(mid 195.796809 -219.176493)
					(end 195.78193 -219.212414)
				)
			)
		)
	)
	(zone
		(layers "In1.Cu" "In2.Cu")
		(hatch none 0.5)
		(connect_pads
			(clearance 0)
		)
		(min_thickness 0.25)
		(keepout
			(tracks not_allowed)
			(vias allowed)
			(pads allowed)
			(copperpour not_allowed)
			(footprints allowed)
		)
		(placement
			(enabled no)
			(sheetname "")
		)
		(fill yes
			(thermal_gap 0.5)
			(thermal_bridge_width 0.5)
			(island_removal_mode 0)
		)
		(polygon
			(pts
				(arc
					(start 52.65293 -269.771368)
					(mid 52.667809 -269.807289)
					(end 52.70373 -269.822168)
				)
				(arc
					(start 54.10327 -269.822168)
					(mid 54.139191 -269.807289)
					(end 54.15407 -269.771368)
				)
				(arc
					(start 54.15407 -269.362428)
					(mid 54.139191 -269.326507)
					(end 54.10327 -269.311628)
				)
				(arc
					(start 52.70373 -269.311628)
					(mid 52.667809 -269.326507)
					(end 52.65293 -269.362428)
				)
			)
		)
	)
	(zone
		(layers "In1.Cu" "In2.Cu")
		(hatch none 0.5)
		(connect_pads
			(clearance 0)
		)
		(min_thickness 0.25)
		(keepout
			(tracks not_allowed)
			(vias allowed)
			(pads allowed)
			(copperpour not_allowed)
			(footprints allowed)
		)
		(placement
			(enabled no)
			(sheetname "")
		)
		(fill yes
			(thermal_gap 0.5)
			(thermal_bridge_width 0.5)
			(island_removal_mode 0)
		)
		(polygon
			(pts
				(arc
					(start 169.706798 -218.77147)
					(mid 169.721677 -218.807391)
					(end 169.757598 -218.82227)
				)
				(arc
					(start 171.157138 -218.82227)
					(mid 171.193059 -218.807391)
					(end 171.207938 -218.77147)
				)
				(arc
					(start 171.207938 -218.36253)
					(mid 171.193059 -218.326609)
					(end 171.157138 -218.31173)
				)
				(arc
					(start 169.757598 -218.31173)
					(mid 169.721677 -218.326609)
					(end 169.706798 -218.36253)
				)
			)
		)
	)
	(zone
		(layers "In1.Cu" "In2.Cu")
		(hatch none 0.5)
		(connect_pads
			(clearance 0)
		)
		(min_thickness 0.25)
		(keepout
			(tracks not_allowed)
			(vias allowed)
			(pads allowed)
			(copperpour not_allowed)
			(footprints allowed)
		)
		(placement
			(enabled no)
			(sheetname "")
		)
		(fill yes
			(thermal_gap 0.5)
			(thermal_bridge_width 0.5)
			(island_removal_mode 0)
		)
		(polygon
			(pts
				(arc
					(start 266.974066 -262.121396)
					(mid 266.988945 -262.157317)
					(end 267.024866 -262.172196)
				)
				(arc
					(start 268.424406 -262.172196)
					(mid 268.460327 -262.157317)
					(end 268.475206 -262.121396)
				)
				(arc
					(start 268.475206 -261.712456)
					(mid 268.460327 -261.676535)
					(end 268.424406 -261.661656)
				)
				(arc
					(start 267.024866 -261.661656)
					(mid 266.988945 -261.676535)
					(end 266.974066 -261.712456)
				)
			)
		)
	)
	(zone
		(layers "In1.Cu" "In2.Cu")
		(hatch none 0.5)
		(connect_pads
			(clearance 0)
		)
		(min_thickness 0.25)
		(keepout
			(tracks not_allowed)
			(vias allowed)
			(pads allowed)
			(copperpour not_allowed)
			(footprints allowed)
		)
		(placement
			(enabled no)
			(sheetname "")
		)
		(fill yes
			(thermal_gap 0.5)
			(thermal_bridge_width 0.5)
			(island_removal_mode 0)
		)
		(polygon
			(pts
				(arc
					(start 37.56533 -207.721454)
					(mid 37.580209 -207.757375)
					(end 37.61613 -207.772254)
				)
				(arc
					(start 39.01567 -207.772254)
					(mid 39.051591 -207.757375)
					(end 39.06647 -207.721454)
				)
				(arc
					(start 39.06647 -207.312514)
					(mid 39.051591 -207.276593)
					(end 39.01567 -207.261714)
				)
				(arc
					(start 37.61613 -207.261714)
					(mid 37.580209 -207.276593)
					(end 37.56533 -207.312514)
				)
			)
		)
	)
	(zone
		(layers "In1.Cu" "In2.Cu")
		(hatch none 0.5)
		(connect_pads
			(clearance 0)
		)
		(min_thickness 0.25)
		(keepout
			(tracks not_allowed)
			(vias allowed)
			(pads allowed)
			(copperpour not_allowed)
			(footprints allowed)
		)
		(placement
			(enabled no)
			(sheetname "")
		)
		(fill yes
			(thermal_gap 0.5)
			(thermal_bridge_width 0.5)
			(island_removal_mode 0)
		)
		(polygon
			(pts
				(arc
					(start 436.178198 -218.77147)
					(mid 436.193077 -218.807391)
					(end 436.228998 -218.82227)
				)
				(arc
					(start 437.628538 -218.82227)
					(mid 437.664459 -218.807391)
					(end 437.679338 -218.77147)
				)
				(arc
					(start 437.679338 -218.36253)
					(mid 437.664459 -218.326609)
					(end 437.628538 -218.31173)
				)
				(arc
					(start 436.228998 -218.31173)
					(mid 436.193077 -218.326609)
					(end 436.178198 -218.36253)
				)
			)
		)
	)
	(zone
		(layers "In1.Cu" "In2.Cu")
		(hatch none 0.5)
		(connect_pads
			(clearance 0)
		)
		(min_thickness 0.25)
		(keepout
			(tracks not_allowed)
			(vias allowed)
			(pads allowed)
			(copperpour not_allowed)
			(footprints allowed)
		)
		(placement
			(enabled no)
			(sheetname "")
		)
		(fill yes
			(thermal_gap 0.5)
			(thermal_bridge_width 0.5)
			(island_removal_mode 0)
		)
		(polygon
			(pts
				(arc
					(start 56.752998 -267.221462)
					(mid 56.767877 -267.257383)
					(end 56.803798 -267.272262)
				)
				(arc
					(start 58.203338 -267.272262)
					(mid 58.239259 -267.257383)
					(end 58.254138 -267.221462)
				)
				(arc
					(start 58.254138 -266.812522)
					(mid 58.239259 -266.776601)
					(end 58.203338 -266.761722)
				)
				(arc
					(start 56.803798 -266.761722)
					(mid 56.767877 -266.776601)
					(end 56.752998 -266.812522)
				)
			)
		)
	)
	(zone
		(layers "In1.Cu" "In2.Cu")
		(hatch none 0.5)
		(connect_pads
			(clearance 0)
		)
		(min_thickness 0.25)
		(keepout
			(tracks not_allowed)
			(vias allowed)
			(pads allowed)
			(copperpour not_allowed)
			(footprints allowed)
		)
		(placement
			(enabled no)
			(sheetname "")
		)
		(fill yes
			(thermal_gap 0.5)
			(thermal_bridge_width 0.5)
			(island_removal_mode 0)
		)
		(polygon
			(pts
				(arc
					(start 11.490198 -295.271444)
					(mid 11.505077 -295.307365)
					(end 11.540998 -295.322244)
				)
				(arc
					(start 12.940538 -295.322244)
					(mid 12.976459 -295.307365)
					(end 12.991338 -295.271444)
				)
				(arc
					(start 12.991338 -294.862504)
					(mid 12.976459 -294.826583)
					(end 12.940538 -294.811704)
				)
				(arc
					(start 11.540998 -294.811704)
					(mid 11.505077 -294.826583)
					(end 11.490198 -294.862504)
				)
			)
		)
	)
	(zone
		(layers "In1.Cu" "In2.Cu")
		(hatch none 0.5)
		(connect_pads
			(clearance 0)
		)
		(min_thickness 0.25)
		(keepout
			(tracks not_allowed)
			(vias allowed)
			(pads allowed)
			(copperpour not_allowed)
			(footprints allowed)
		)
		(placement
			(enabled no)
			(sheetname "")
		)
		(fill yes
			(thermal_gap 0.5)
			(thermal_bridge_width 0.5)
			(island_removal_mode 0)
		)
		(polygon
			(pts
				(arc
					(start 52.65293 -301.221394)
					(mid 52.667809 -301.257315)
					(end 52.70373 -301.272194)
				)
				(arc
					(start 54.10327 -301.272194)
					(mid 54.139191 -301.257315)
					(end 54.15407 -301.221394)
				)
				(arc
					(start 54.15407 -300.812454)
					(mid 54.139191 -300.776533)
					(end 54.10327 -300.761654)
				)
				(arc
					(start 52.70373 -300.761654)
					(mid 52.667809 -300.776533)
					(end 52.65293 -300.812454)
				)
			)
		)
	)
	(zone
		(layers "In1.Cu" "In2.Cu")
		(hatch none 0.5)
		(connect_pads
			(clearance 0)
		)
		(min_thickness 0.25)
		(keepout
			(tracks not_allowed)
			(vias allowed)
			(pads allowed)
			(copperpour not_allowed)
			(footprints allowed)
		)
		(placement
			(enabled no)
			(sheetname "")
		)
		(fill yes
			(thermal_gap 0.5)
			(thermal_bridge_width 0.5)
			(island_removal_mode 0)
		)
		(polygon
			(pts
				(arc
					(start 270.417798 -245.971314)
					(mid 270.432677 -246.007235)
					(end 270.468598 -246.022114)
				)
				(arc
					(start 271.868138 -246.022114)
					(mid 271.904059 -246.007235)
					(end 271.918938 -245.971314)
				)
				(arc
					(start 271.918938 -245.562374)
					(mid 271.904059 -245.526453)
					(end 271.868138 -245.511574)
				)
				(arc
					(start 270.468598 -245.511574)
					(mid 270.432677 -245.526453)
					(end 270.417798 -245.562374)
				)
			)
		)
	)
	(zone
		(layers "In1.Cu" "In2.Cu")
		(hatch none 0.5)
		(connect_pads
			(clearance 0)
		)
		(min_thickness 0.25)
		(keepout
			(tracks not_allowed)
			(vias allowed)
			(pads allowed)
			(copperpour not_allowed)
			(footprints allowed)
		)
		(placement
			(enabled no)
			(sheetname "")
		)
		(fill yes
			(thermal_gap 0.5)
			(thermal_bridge_width 0.5)
			(island_removal_mode 0)
		)
		(polygon
			(pts
				(arc
					(start 19.033998 -298.671488)
					(mid 19.048877 -298.707409)
					(end 19.084798 -298.722288)
				)
				(arc
					(start 20.484338 -298.722288)
					(mid 20.520259 -298.707409)
					(end 20.535138 -298.671488)
				)
				(arc
					(start 20.535138 -298.262548)
					(mid 20.520259 -298.226627)
					(end 20.484338 -298.211748)
				)
				(arc
					(start 19.084798 -298.211748)
					(mid 19.048877 -298.226627)
					(end 19.033998 -298.262548)
				)
			)
		)
	)
	(zone
		(layers "In1.Cu" "In2.Cu")
		(hatch none 0.5)
		(connect_pads
			(clearance 0)
		)
		(min_thickness 0.25)
		(keepout
			(tracks not_allowed)
			(vias allowed)
			(pads allowed)
			(copperpour not_allowed)
			(footprints allowed)
		)
		(placement
			(enabled no)
			(sheetname "")
		)
		(fill yes
			(thermal_gap 0.5)
			(thermal_bridge_width 0.5)
			(island_removal_mode 0)
		)
		(polygon
			(pts
				(arc
					(start 203.32573 -228.971348)
					(mid 203.340609 -229.007269)
					(end 203.37653 -229.022148)
				)
				(arc
					(start 204.77607 -229.022148)
					(mid 204.811991 -229.007269)
					(end 204.82687 -228.971348)
				)
				(arc
					(start 204.82687 -228.562408)
					(mid 204.811991 -228.526487)
					(end 204.77607 -228.511608)
				)
				(arc
					(start 203.37653 -228.511608)
					(mid 203.340609 -228.526487)
					(end 203.32573 -228.562408)
				)
			)
		)
	)
	(zone
		(layers "In1.Cu" "In2.Cu")
		(hatch none 0.5)
		(connect_pads
			(clearance 0)
		)
		(min_thickness 0.25)
		(keepout
			(tracks not_allowed)
			(vias allowed)
			(pads allowed)
			(copperpour not_allowed)
			(footprints allowed)
		)
		(placement
			(enabled no)
			(sheetname "")
		)
		(fill yes
			(thermal_gap 0.5)
			(thermal_bridge_width 0.5)
			(island_removal_mode 0)
		)
		(polygon
			(pts
				(arc
					(start 432.734466 -222.171514)
					(mid 432.749345 -222.207435)
					(end 432.785266 -222.222314)
				)
				(arc
					(start 434.184806 -222.222314)
					(mid 434.220727 -222.207435)
					(end 434.235606 -222.171514)
				)
				(arc
					(start 434.235606 -221.762574)
					(mid 434.220727 -221.726653)
					(end 434.184806 -221.711774)
				)
				(arc
					(start 432.785266 -221.711774)
					(mid 432.749345 -221.726653)
					(end 432.734466 -221.762574)
				)
			)
		)
	)
	(zone
		(layers "In1.Cu" "In2.Cu")
		(hatch none 0.5)
		(connect_pads
			(clearance 0)
		)
		(min_thickness 0.25)
		(keepout
			(tracks not_allowed)
			(vias allowed)
			(pads allowed)
			(copperpour not_allowed)
			(footprints allowed)
		)
		(placement
			(enabled no)
			(sheetname "")
		)
		(fill yes
			(thermal_gap 0.5)
			(thermal_bridge_width 0.5)
			(island_removal_mode 0)
		)
		(polygon
			(pts
				(arc
					(start 162.162998 -285.92145)
					(mid 162.177877 -285.957371)
					(end 162.213798 -285.97225)
				)
				(arc
					(start 163.613338 -285.97225)
					(mid 163.649259 -285.957371)
					(end 163.664138 -285.92145)
				)
				(arc
					(start 163.664138 -285.51251)
					(mid 163.649259 -285.476589)
					(end 163.613338 -285.46171)
				)
				(arc
					(start 162.213798 -285.46171)
					(mid 162.177877 -285.476589)
					(end 162.162998 -285.51251)
				)
			)
		)
	)
	(zone
		(layers "In1.Cu" "In2.Cu")
		(hatch none 0.5)
		(connect_pads
			(clearance 0)
		)
		(min_thickness 0.25)
		(keepout
			(tracks not_allowed)
			(vias allowed)
			(pads allowed)
			(copperpour not_allowed)
			(footprints allowed)
		)
		(placement
			(enabled no)
			(sheetname "")
		)
		(fill yes
			(thermal_gap 0.5)
			(thermal_bridge_width 0.5)
			(island_removal_mode 0)
		)
		(polygon
			(pts
				(arc
					(start 162.162998 -231.521508)
					(mid 162.177877 -231.557429)
					(end 162.213798 -231.572308)
				)
				(arc
					(start 163.613338 -231.572308)
					(mid 163.649259 -231.557429)
					(end 163.664138 -231.521508)
				)
				(arc
					(start 163.664138 -231.112568)
					(mid 163.649259 -231.076647)
					(end 163.613338 -231.061768)
				)
				(arc
					(start 162.213798 -231.061768)
					(mid 162.177877 -231.076647)
					(end 162.162998 -231.112568)
				)
			)
		)
	)
	(zone
		(layers "In1.Cu" "In2.Cu")
		(hatch none 0.5)
		(connect_pads
			(clearance 0)
		)
		(min_thickness 0.25)
		(keepout
			(tracks not_allowed)
			(vias allowed)
			(pads allowed)
			(copperpour not_allowed)
			(footprints allowed)
		)
		(placement
			(enabled no)
			(sheetname "")
		)
		(fill yes
			(thermal_gap 0.5)
			(thermal_bridge_width 0.5)
			(island_removal_mode 0)
		)
		(polygon
			(pts
				(arc
					(start 293.049198 -294.421306)
					(mid 293.064077 -294.457227)
					(end 293.099998 -294.472106)
				)
				(arc
					(start 294.499538 -294.472106)
					(mid 294.535459 -294.457227)
					(end 294.550338 -294.421306)
				)
				(arc
					(start 294.550338 -294.012366)
					(mid 294.535459 -293.976445)
					(end 294.499538 -293.961566)
				)
				(arc
					(start 293.099998 -293.961566)
					(mid 293.064077 -293.976445)
					(end 293.049198 -294.012366)
				)
			)
		)
	)
	(zone
		(layers "In1.Cu" "In2.Cu")
		(hatch none 0.5)
		(connect_pads
			(clearance 0)
		)
		(min_thickness 0.25)
		(keepout
			(tracks not_allowed)
			(vias allowed)
			(pads allowed)
			(copperpour not_allowed)
			(footprints allowed)
		)
		(placement
			(enabled no)
			(sheetname "")
		)
		(fill yes
			(thermal_gap 0.5)
			(thermal_bridge_width 0.5)
			(island_removal_mode 0)
		)
		(polygon
			(pts
				(arc
					(start 451.265798 -209.421476)
					(mid 451.280677 -209.457397)
					(end 451.316598 -209.472276)
				)
				(arc
					(start 452.716138 -209.472276)
					(mid 452.752059 -209.457397)
					(end 452.766938 -209.421476)
				)
				(arc
					(start 452.766938 -209.012536)
					(mid 452.752059 -208.976615)
					(end 452.716138 -208.961736)
				)
				(arc
					(start 451.316598 -208.961736)
					(mid 451.280677 -208.976615)
					(end 451.265798 -209.012536)
				)
			)
		)
	)
	(zone
		(layers "In1.Cu" "In2.Cu")
		(hatch none 0.5)
		(connect_pads
			(clearance 0)
		)
		(min_thickness 0.25)
		(keepout
			(tracks not_allowed)
			(vias allowed)
			(pads allowed)
			(copperpour not_allowed)
			(footprints allowed)
		)
		(placement
			(enabled no)
			(sheetname "")
		)
		(fill yes
			(thermal_gap 0.5)
			(thermal_bridge_width 0.5)
			(island_removal_mode 0)
		)
		(polygon
			(pts
				(arc
					(start 285.505398 -228.971348)
					(mid 285.520277 -229.007269)
					(end 285.556198 -229.022148)
				)
				(arc
					(start 286.955738 -229.022148)
					(mid 286.991659 -229.007269)
					(end 287.006538 -228.971348)
				)
				(arc
					(start 287.006538 -228.562408)
					(mid 286.991659 -228.526487)
					(end 286.955738 -228.511608)
				)
				(arc
					(start 285.556198 -228.511608)
					(mid 285.520277 -228.526487)
					(end 285.505398 -228.562408)
				)
			)
		)
	)
	(zone
		(layers "In1.Cu" "In2.Cu")
		(hatch none 0.5)
		(connect_pads
			(clearance 0)
		)
		(min_thickness 0.25)
		(keepout
			(tracks not_allowed)
			(vias allowed)
			(pads allowed)
			(copperpour not_allowed)
			(footprints allowed)
		)
		(placement
			(enabled no)
			(sheetname "")
		)
		(fill yes
			(thermal_gap 0.5)
			(thermal_bridge_width 0.5)
			(island_removal_mode 0)
		)
		(polygon
			(pts
				(arc
					(start 410.103066 -276.571456)
					(mid 410.117945 -276.607377)
					(end 410.153866 -276.622256)
				)
				(arc
					(start 411.553406 -276.622256)
					(mid 411.589327 -276.607377)
					(end 411.604206 -276.571456)
				)
				(arc
					(start 411.604206 -276.162516)
					(mid 411.589327 -276.126595)
					(end 411.553406 -276.111716)
				)
				(arc
					(start 410.153866 -276.111716)
					(mid 410.117945 -276.126595)
					(end 410.103066 -276.162516)
				)
			)
		)
	)
	(zone
		(layers "In1.Cu" "In2.Cu")
		(hatch none 0.5)
		(connect_pads
			(clearance 0)
		)
		(min_thickness 0.25)
		(keepout
			(tracks not_allowed)
			(vias allowed)
			(pads allowed)
			(copperpour not_allowed)
			(footprints allowed)
		)
		(placement
			(enabled no)
			(sheetname "")
		)
		(fill yes
			(thermal_gap 0.5)
			(thermal_bridge_width 0.5)
			(island_removal_mode 0)
		)
		(polygon
			(pts
				(arc
					(start 192.338198 -208.571338)
					(mid 192.353077 -208.607259)
					(end 192.388998 -208.622138)
				)
				(arc
					(start 193.788538 -208.622138)
					(mid 193.824459 -208.607259)
					(end 193.839338 -208.571338)
				)
				(arc
					(start 193.839338 -208.162398)
					(mid 193.824459 -208.126477)
					(end 193.788538 -208.111598)
				)
				(arc
					(start 192.388998 -208.111598)
					(mid 192.353077 -208.126477)
					(end 192.338198 -208.162398)
				)
			)
		)
	)
	(zone
		(layers "In1.Cu" "In2.Cu")
		(hatch none 0.5)
		(connect_pads
			(clearance 0)
		)
		(min_thickness 0.25)
		(keepout
			(tracks not_allowed)
			(vias allowed)
			(pads allowed)
			(copperpour not_allowed)
			(footprints allowed)
		)
		(placement
			(enabled no)
			(sheetname "")
		)
		(fill yes
			(thermal_gap 0.5)
			(thermal_bridge_width 0.5)
			(island_removal_mode 0)
		)
		(polygon
			(pts
				(arc
					(start 60.19673 -204.32141)
					(mid 60.211609 -204.357331)
					(end 60.24753 -204.37221)
				)
				(arc
					(start 61.64707 -204.37221)
					(mid 61.682991 -204.357331)
					(end 61.69787 -204.32141)
				)
				(arc
					(start 61.69787 -203.91247)
					(mid 61.682991 -203.876549)
					(end 61.64707 -203.86167)
				)
				(arc
					(start 60.24753 -203.86167)
					(mid 60.211609 -203.876549)
					(end 60.19673 -203.91247)
				)
			)
		)
	)
	(zone
		(layers "In1.Cu" "In2.Cu")
		(hatch none 0.5)
		(connect_pads
			(clearance 0)
		)
		(min_thickness 0.25)
		(keepout
			(tracks not_allowed)
			(vias allowed)
			(pads allowed)
			(copperpour not_allowed)
			(footprints allowed)
		)
		(placement
			(enabled no)
			(sheetname "")
		)
		(fill yes
			(thermal_gap 0.5)
			(thermal_bridge_width 0.5)
			(island_removal_mode 0)
		)
		(polygon
			(pts
				(arc
					(start 421.090598 -286.771334)
					(mid 421.105477 -286.807255)
					(end 421.141398 -286.822134)
				)
				(arc
					(start 422.540938 -286.822134)
					(mid 422.576859 -286.807255)
					(end 422.591738 -286.771334)
				)
				(arc
					(start 422.591738 -286.362394)
					(mid 422.576859 -286.326473)
					(end 422.540938 -286.311594)
				)
				(arc
					(start 421.141398 -286.311594)
					(mid 421.105477 -286.326473)
					(end 421.090598 -286.362394)
				)
			)
		)
	)
	(zone
		(layers "In1.Cu" "In2.Cu")
		(hatch none 0.5)
		(connect_pads
			(clearance 0)
		)
		(min_thickness 0.25)
		(keepout
			(tracks not_allowed)
			(vias allowed)
			(pads allowed)
			(copperpour not_allowed)
			(footprints allowed)
		)
		(placement
			(enabled no)
			(sheetname "")
		)
		(fill yes
			(thermal_gap 0.5)
			(thermal_bridge_width 0.5)
			(island_removal_mode 0)
		)
		(polygon
			(pts
				(arc
					(start 300.592998 -264.671302)
					(mid 300.607877 -264.707223)
					(end 300.643798 -264.722102)
				)
				(arc
					(start 302.043338 -264.722102)
					(mid 302.079259 -264.707223)
					(end 302.094138 -264.671302)
				)
				(arc
					(start 302.094138 -264.262362)
					(mid 302.079259 -264.226441)
					(end 302.043338 -264.211562)
				)
				(arc
					(start 300.643798 -264.211562)
					(mid 300.607877 -264.226441)
					(end 300.592998 -264.262362)
				)
			)
		)
	)
	(zone
		(layers "In1.Cu" "In2.Cu")
		(hatch none 0.5)
		(connect_pads
			(clearance 0)
		)
		(min_thickness 0.25)
		(keepout
			(tracks not_allowed)
			(vias allowed)
			(pads allowed)
			(copperpour not_allowed)
			(footprints allowed)
		)
		(placement
			(enabled no)
			(sheetname "")
		)
		(fill yes
			(thermal_gap 0.5)
			(thermal_bridge_width 0.5)
			(island_removal_mode 0)
		)
		(polygon
			(pts
				(arc
					(start 37.56533 -316.521338)
					(mid 37.580209 -316.557259)
					(end 37.61613 -316.572138)
				)
				(arc
					(start 39.01567 -316.572138)
					(mid 39.051591 -316.557259)
					(end 39.06647 -316.521338)
				)
				(arc
					(start 39.06647 -316.112398)
					(mid 39.051591 -316.076477)
					(end 39.01567 -316.061598)
				)
				(arc
					(start 37.61613 -316.061598)
					(mid 37.580209 -316.076477)
					(end 37.56533 -316.112398)
				)
			)
		)
	)
	(zone
		(layers "In1.Cu" "In2.Cu")
		(hatch none 0.5)
		(connect_pads
			(clearance 0)
		)
		(min_thickness 0.25)
		(keepout
			(tracks not_allowed)
			(vias allowed)
			(pads allowed)
			(copperpour not_allowed)
			(footprints allowed)
		)
		(placement
			(enabled no)
			(sheetname "")
		)
		(fill yes
			(thermal_gap 0.5)
			(thermal_bridge_width 0.5)
			(island_removal_mode 0)
		)
		(polygon
			(pts
				(arc
					(start 34.121598 -203.471526)
					(mid 34.136477 -203.507447)
					(end 34.172398 -203.522326)
				)
				(arc
					(start 35.571938 -203.522326)
					(mid 35.607859 -203.507447)
					(end 35.622738 -203.471526)
				)
				(arc
					(start 35.622738 -203.062586)
					(mid 35.607859 -203.026665)
					(end 35.571938 -203.011786)
				)
				(arc
					(start 34.172398 -203.011786)
					(mid 34.136477 -203.026665)
					(end 34.121598 -203.062586)
				)
			)
		)
	)
	(zone
		(layers "In1.Cu" "In2.Cu")
		(hatch none 0.5)
		(connect_pads
			(clearance 0)
		)
		(min_thickness 0.25)
		(keepout
			(tracks not_allowed)
			(vias allowed)
			(pads allowed)
			(copperpour not_allowed)
			(footprints allowed)
		)
		(placement
			(enabled no)
			(sheetname "")
		)
		(fill yes
			(thermal_gap 0.5)
			(thermal_bridge_width 0.5)
			(island_removal_mode 0)
		)
		(polygon
			(pts
				(arc
					(start 266.974066 -201.771504)
					(mid 266.988945 -201.807425)
					(end 267.024866 -201.822304)
				)
				(arc
					(start 268.424406 -201.822304)
					(mid 268.460327 -201.807425)
					(end 268.475206 -201.771504)
				)
				(arc
					(start 268.475206 -201.362564)
					(mid 268.460327 -201.326643)
					(end 268.424406 -201.311764)
				)
				(arc
					(start 267.024866 -201.311764)
					(mid 266.988945 -201.326643)
					(end 266.974066 -201.362564)
				)
			)
		)
	)
	(zone
		(layers "In1.Cu" "In2.Cu")
		(hatch none 0.5)
		(connect_pads
			(clearance 0)
		)
		(min_thickness 0.25)
		(keepout
			(tracks not_allowed)
			(vias allowed)
			(pads allowed)
			(copperpour not_allowed)
			(footprints allowed)
		)
		(placement
			(enabled no)
			(sheetname "")
		)
		(fill yes
			(thermal_gap 0.5)
			(thermal_bridge_width 0.5)
			(island_removal_mode 0)
		)
		(polygon
			(pts
				(arc
					(start 282.061666 -239.17148)
					(mid 282.076545 -239.207401)
					(end 282.112466 -239.22228)
				)
				(arc
					(start 283.512006 -239.22228)
					(mid 283.547927 -239.207401)
					(end 283.562806 -239.17148)
				)
				(arc
					(start 283.562806 -238.76254)
					(mid 283.547927 -238.726619)
					(end 283.512006 -238.71174)
				)
				(arc
					(start 282.112466 -238.71174)
					(mid 282.076545 -238.726619)
					(end 282.061666 -238.76254)
				)
			)
		)
	)
	(zone
		(layers "In1.Cu" "In2.Cu")
		(hatch none 0.5)
		(connect_pads
			(clearance 0)
		)
		(min_thickness 0.25)
		(keepout
			(tracks not_allowed)
			(vias allowed)
			(pads allowed)
			(copperpour not_allowed)
			(footprints allowed)
		)
		(placement
			(enabled no)
			(sheetname "")
		)
		(fill yes
			(thermal_gap 0.5)
			(thermal_bridge_width 0.5)
			(island_removal_mode 0)
		)
		(polygon
			(pts
				(arc
					(start 259.430266 -302.921416)
					(mid 259.445145 -302.957337)
					(end 259.481066 -302.972216)
				)
				(arc
					(start 260.880606 -302.972216)
					(mid 260.916527 -302.957337)
					(end 260.931406 -302.921416)
				)
				(arc
					(start 260.931406 -302.512476)
					(mid 260.916527 -302.476555)
					(end 260.880606 -302.461676)
				)
				(arc
					(start 259.481066 -302.461676)
					(mid 259.445145 -302.476555)
					(end 259.430266 -302.512476)
				)
			)
		)
	)
	(zone
		(layers "In1.Cu" "In2.Cu")
		(hatch none 0.5)
		(connect_pads
			(clearance 0)
		)
		(min_thickness 0.25)
		(keepout
			(tracks not_allowed)
			(vias allowed)
			(pads allowed)
			(copperpour not_allowed)
			(footprints allowed)
		)
		(placement
			(enabled no)
			(sheetname "")
		)
		(fill yes
			(thermal_gap 0.5)
			(thermal_bridge_width 0.5)
			(island_removal_mode 0)
		)
		(polygon
			(pts
				(arc
					(start 26.577798 -203.471526)
					(mid 26.592677 -203.507447)
					(end 26.628598 -203.522326)
				)
				(arc
					(start 28.028138 -203.522326)
					(mid 28.064059 -203.507447)
					(end 28.078938 -203.471526)
				)
				(arc
					(start 28.078938 -203.062586)
					(mid 28.064059 -203.026665)
					(end 28.028138 -203.011786)
				)
				(arc
					(start 26.628598 -203.011786)
					(mid 26.592677 -203.026665)
					(end 26.577798 -203.062586)
				)
			)
		)
	)
	(zone
		(layers "In1.Cu" "In2.Cu")
		(hatch none 0.5)
		(connect_pads
			(clearance 0)
		)
		(min_thickness 0.25)
		(keepout
			(tracks not_allowed)
			(vias allowed)
			(pads allowed)
			(copperpour not_allowed)
			(footprints allowed)
		)
		(placement
			(enabled no)
			(sheetname "")
		)
		(fill yes
			(thermal_gap 0.5)
			(thermal_bridge_width 0.5)
			(island_removal_mode 0)
		)
		(polygon
			(pts
				(arc
					(start 262.873998 -247.671336)
					(mid 262.888877 -247.707257)
					(end 262.924798 -247.722136)
				)
				(arc
					(start 264.324338 -247.722136)
					(mid 264.360259 -247.707257)
					(end 264.375138 -247.671336)
				)
				(arc
					(start 264.375138 -247.262396)
					(mid 264.360259 -247.226475)
					(end 264.324338 -247.211596)
				)
				(arc
					(start 262.924798 -247.211596)
					(mid 262.888877 -247.226475)
					(end 262.873998 -247.262396)
				)
			)
		)
	)
	(zone
		(layers "In1.Cu" "In2.Cu")
		(hatch none 0.5)
		(connect_pads
			(clearance 0)
		)
		(min_thickness 0.25)
		(keepout
			(tracks not_allowed)
			(vias allowed)
			(pads allowed)
			(copperpour not_allowed)
			(footprints allowed)
		)
		(placement
			(enabled no)
			(sheetname "")
		)
		(fill yes
			(thermal_gap 0.5)
			(thermal_bridge_width 0.5)
			(island_removal_mode 0)
		)
		(polygon
			(pts
				(arc
					(start 11.490198 -313.971432)
					(mid 11.505077 -314.007353)
					(end 11.540998 -314.022232)
				)
				(arc
					(start 12.940538 -314.022232)
					(mid 12.976459 -314.007353)
					(end 12.991338 -313.971432)
				)
				(arc
					(start 12.991338 -313.562492)
					(mid 12.976459 -313.526571)
					(end 12.940538 -313.511692)
				)
				(arc
					(start 11.540998 -313.511692)
					(mid 11.505077 -313.526571)
					(end 11.490198 -313.562492)
				)
			)
		)
	)
	(zone
		(layers "In1.Cu" "In2.Cu")
		(hatch none 0.5)
		(connect_pads
			(clearance 0)
		)
		(min_thickness 0.25)
		(keepout
			(tracks not_allowed)
			(vias allowed)
			(pads allowed)
			(copperpour not_allowed)
			(footprints allowed)
		)
		(placement
			(enabled no)
			(sheetname "")
		)
		(fill yes
			(thermal_gap 0.5)
			(thermal_bridge_width 0.5)
			(island_removal_mode 0)
		)
		(polygon
			(pts
				(arc
					(start 428.634398 -228.121464)
					(mid 428.649277 -228.157385)
					(end 428.685198 -228.172264)
				)
				(arc
					(start 430.084738 -228.172264)
					(mid 430.120659 -228.157385)
					(end 430.135538 -228.121464)
				)
				(arc
					(start 430.135538 -227.712524)
					(mid 430.120659 -227.676603)
					(end 430.084738 -227.661724)
				)
				(arc
					(start 428.685198 -227.661724)
					(mid 428.649277 -227.676603)
					(end 428.634398 -227.712524)
				)
			)
		)
	)
	(zone
		(layers "In1.Cu" "In2.Cu")
		(hatch none 0.5)
		(connect_pads
			(clearance 0)
		)
		(min_thickness 0.25)
		(keepout
			(tracks not_allowed)
			(vias allowed)
			(pads allowed)
			(copperpour not_allowed)
			(footprints allowed)
		)
		(placement
			(enabled no)
			(sheetname "")
		)
		(fill yes
			(thermal_gap 0.5)
			(thermal_bridge_width 0.5)
			(island_removal_mode 0)
		)
		(polygon
			(pts
				(arc
					(start 285.505398 -261.271512)
					(mid 285.520277 -261.307433)
					(end 285.556198 -261.322312)
				)
				(arc
					(start 286.955738 -261.322312)
					(mid 286.991659 -261.307433)
					(end 287.006538 -261.271512)
				)
				(arc
					(start 287.006538 -260.862572)
					(mid 286.991659 -260.826651)
					(end 286.955738 -260.811772)
				)
				(arc
					(start 285.556198 -260.811772)
					(mid 285.520277 -260.826651)
					(end 285.505398 -260.862572)
				)
			)
		)
	)
	(zone
		(layers "In1.Cu" "In2.Cu")
		(hatch none 0.5)
		(connect_pads
			(clearance 0)
		)
		(min_thickness 0.25)
		(keepout
			(tracks not_allowed)
			(vias allowed)
			(pads allowed)
			(copperpour not_allowed)
			(footprints allowed)
		)
		(placement
			(enabled no)
			(sheetname "")
		)
		(fill yes
			(thermal_gap 0.5)
			(thermal_bridge_width 0.5)
			(island_removal_mode 0)
		)
		(polygon
			(pts
				(arc
					(start 297.149266 -246.821452)
					(mid 297.164145 -246.857373)
					(end 297.200066 -246.872252)
				)
				(arc
					(start 298.599606 -246.872252)
					(mid 298.635527 -246.857373)
					(end 298.650406 -246.821452)
				)
				(arc
					(start 298.650406 -246.412512)
					(mid 298.635527 -246.376591)
					(end 298.599606 -246.361712)
				)
				(arc
					(start 297.200066 -246.361712)
					(mid 297.164145 -246.376591)
					(end 297.149266 -246.412512)
				)
			)
		)
	)
	(zone
		(layers "In1.Cu" "In2.Cu")
		(hatch none 0.5)
		(connect_pads
			(clearance 0)
		)
		(min_thickness 0.25)
		(keepout
			(tracks not_allowed)
			(vias allowed)
			(pads allowed)
			(copperpour not_allowed)
			(footprints allowed)
		)
		(placement
			(enabled no)
			(sheetname "")
		)
		(fill yes
			(thermal_gap 0.5)
			(thermal_bridge_width 0.5)
			(island_removal_mode 0)
		)
		(polygon
			(pts
				(arc
					(start 37.56533 -243.421408)
					(mid 37.580209 -243.457329)
					(end 37.61613 -243.472208)
				)
				(arc
					(start 39.01567 -243.472208)
					(mid 39.051591 -243.457329)
					(end 39.06647 -243.421408)
				)
				(arc
					(start 39.06647 -243.012468)
					(mid 39.051591 -242.976547)
					(end 39.01567 -242.961668)
				)
				(arc
					(start 37.61613 -242.961668)
					(mid 37.580209 -242.976547)
					(end 37.56533 -243.012468)
				)
			)
		)
	)
	(zone
		(layers "In1.Cu" "In2.Cu")
		(hatch none 0.5)
		(connect_pads
			(clearance 0)
		)
		(min_thickness 0.25)
		(keepout
			(tracks not_allowed)
			(vias allowed)
			(pads allowed)
			(copperpour not_allowed)
			(footprints allowed)
		)
		(placement
			(enabled no)
			(sheetname "")
		)
		(fill yes
			(thermal_gap 0.5)
			(thermal_bridge_width 0.5)
			(island_removal_mode 0)
		)
		(polygon
			(pts
				(arc
					(start 34.121598 -265.52144)
					(mid 34.136477 -265.557361)
					(end 34.172398 -265.57224)
				)
				(arc
					(start 35.571938 -265.57224)
					(mid 35.607859 -265.557361)
					(end 35.622738 -265.52144)
				)
				(arc
					(start 35.622738 -265.1125)
					(mid 35.607859 -265.076579)
					(end 35.571938 -265.0617)
				)
				(arc
					(start 34.172398 -265.0617)
					(mid 34.136477 -265.076579)
					(end 34.121598 -265.1125)
				)
			)
		)
	)
	(zone
		(layers "In1.Cu" "In2.Cu")
		(hatch none 0.5)
		(connect_pads
			(clearance 0)
		)
		(min_thickness 0.25)
		(keepout
			(tracks not_allowed)
			(vias allowed)
			(pads allowed)
			(copperpour not_allowed)
			(footprints allowed)
		)
		(placement
			(enabled no)
			(sheetname "")
		)
		(fill yes
			(thermal_gap 0.5)
			(thermal_bridge_width 0.5)
			(island_removal_mode 0)
		)
		(polygon
			(pts
				(arc
					(start 282.061666 -276.571456)
					(mid 282.076545 -276.607377)
					(end 282.112466 -276.622256)
				)
				(arc
					(start 283.512006 -276.622256)
					(mid 283.547927 -276.607377)
					(end 283.562806 -276.571456)
				)
				(arc
					(start 283.562806 -276.162516)
					(mid 283.547927 -276.126595)
					(end 283.512006 -276.111716)
				)
				(arc
					(start 282.112466 -276.111716)
					(mid 282.076545 -276.126595)
					(end 282.061666 -276.162516)
				)
			)
		)
	)
	(zone
		(layers "In1.Cu" "In2.Cu")
		(hatch none 0.5)
		(connect_pads
			(clearance 0)
		)
		(min_thickness 0.25)
		(keepout
			(tracks not_allowed)
			(vias allowed)
			(pads allowed)
			(copperpour not_allowed)
			(footprints allowed)
		)
		(placement
			(enabled no)
			(sheetname "")
		)
		(fill yes
			(thermal_gap 0.5)
			(thermal_bridge_width 0.5)
			(island_removal_mode 0)
		)
		(polygon
			(pts
				(arc
					(start 177.250598 -279.9715)
					(mid 177.265477 -280.007421)
					(end 177.301398 -280.0223)
				)
				(arc
					(start 178.700938 -280.0223)
					(mid 178.736859 -280.007421)
					(end 178.751738 -279.9715)
				)
				(arc
					(start 178.751738 -279.56256)
					(mid 178.736859 -279.526639)
					(end 178.700938 -279.51176)
				)
				(arc
					(start 177.301398 -279.51176)
					(mid 177.265477 -279.526639)
					(end 177.250598 -279.56256)
				)
			)
		)
	)
	(zone
		(layers "In1.Cu" "In2.Cu")
		(hatch none 0.5)
		(connect_pads
			(clearance 0)
		)
		(min_thickness 0.25)
		(keepout
			(tracks not_allowed)
			(vias allowed)
			(pads allowed)
			(copperpour not_allowed)
			(footprints allowed)
		)
		(placement
			(enabled no)
			(sheetname "")
		)
		(fill yes
			(thermal_gap 0.5)
			(thermal_bridge_width 0.5)
			(island_removal_mode 0)
		)
		(polygon
			(pts
				(arc
					(start 410.103066 -259.57149)
					(mid 410.117945 -259.607411)
					(end 410.153866 -259.62229)
				)
				(arc
					(start 411.553406 -259.62229)
					(mid 411.589327 -259.607411)
					(end 411.604206 -259.57149)
				)
				(arc
					(start 411.604206 -259.16255)
					(mid 411.589327 -259.126629)
					(end 411.553406 -259.11175)
				)
				(arc
					(start 410.153866 -259.11175)
					(mid 410.117945 -259.126629)
					(end 410.103066 -259.16255)
				)
			)
		)
	)
	(zone
		(layers "In1.Cu" "In2.Cu")
		(hatch none 0.5)
		(connect_pads
			(clearance 0)
		)
		(min_thickness 0.25)
		(keepout
			(tracks not_allowed)
			(vias allowed)
			(pads allowed)
			(copperpour not_allowed)
			(footprints allowed)
		)
		(placement
			(enabled no)
			(sheetname "")
		)
		(fill yes
			(thermal_gap 0.5)
			(thermal_bridge_width 0.5)
			(island_removal_mode 0)
		)
		(polygon
			(pts
				(arc
					(start 192.338198 -315.671454)
					(mid 192.353077 -315.707375)
					(end 192.388998 -315.722254)
				)
				(arc
					(start 193.788538 -315.722254)
					(mid 193.824459 -315.707375)
					(end 193.839338 -315.671454)
				)
				(arc
					(start 193.839338 -315.262514)
					(mid 193.824459 -315.226593)
					(end 193.788538 -315.211714)
				)
				(arc
					(start 192.388998 -315.211714)
					(mid 192.353077 -315.226593)
					(end 192.338198 -315.262514)
				)
			)
		)
	)
	(zone
		(layers "In1.Cu" "In2.Cu")
		(hatch none 0.5)
		(connect_pads
			(clearance 0)
		)
		(min_thickness 0.25)
		(keepout
			(tracks not_allowed)
			(vias allowed)
			(pads allowed)
			(copperpour not_allowed)
			(footprints allowed)
		)
		(placement
			(enabled no)
			(sheetname "")
		)
		(fill yes
			(thermal_gap 0.5)
			(thermal_bridge_width 0.5)
			(island_removal_mode 0)
		)
		(polygon
			(pts
				(arc
					(start 169.706798 -200.071482)
					(mid 169.721677 -200.107403)
					(end 169.757598 -200.122282)
				)
				(arc
					(start 171.157138 -200.122282)
					(mid 171.193059 -200.107403)
					(end 171.207938 -200.071482)
				)
				(arc
					(start 171.207938 -199.662542)
					(mid 171.193059 -199.626621)
					(end 171.157138 -199.611742)
				)
				(arc
					(start 169.757598 -199.611742)
					(mid 169.721677 -199.626621)
					(end 169.706798 -199.662542)
				)
			)
		)
	)
	(zone
		(layers "In1.Cu" "In2.Cu")
		(hatch none 0.5)
		(connect_pads
			(clearance 0)
		)
		(min_thickness 0.25)
		(keepout
			(tracks not_allowed)
			(vias allowed)
			(pads allowed)
			(copperpour not_allowed)
			(footprints allowed)
		)
		(placement
			(enabled no)
			(sheetname "")
		)
		(fill yes
			(thermal_gap 0.5)
			(thermal_bridge_width 0.5)
			(island_removal_mode 0)
		)
		(polygon
			(pts
				(arc
					(start 421.090598 -308.871366)
					(mid 421.105477 -308.907287)
					(end 421.141398 -308.922166)
				)
				(arc
					(start 422.540938 -308.922166)
					(mid 422.576859 -308.907287)
					(end 422.591738 -308.871366)
				)
				(arc
					(start 422.591738 -308.462426)
					(mid 422.576859 -308.426505)
					(end 422.540938 -308.411626)
				)
				(arc
					(start 421.141398 -308.411626)
					(mid 421.105477 -308.426505)
					(end 421.090598 -308.462426)
				)
			)
		)
	)
	(zone
		(layers "In1.Cu" "In2.Cu")
		(hatch none 0.5)
		(connect_pads
			(clearance 0)
		)
		(min_thickness 0.25)
		(keepout
			(tracks not_allowed)
			(vias allowed)
			(pads allowed)
			(copperpour not_allowed)
			(footprints allowed)
		)
		(placement
			(enabled no)
			(sheetname "")
		)
		(fill yes
			(thermal_gap 0.5)
			(thermal_bridge_width 0.5)
			(island_removal_mode 0)
		)
		(polygon
			(pts
				(arc
					(start 262.873998 -273.171412)
					(mid 262.888877 -273.207333)
					(end 262.924798 -273.222212)
				)
				(arc
					(start 264.324338 -273.222212)
					(mid 264.360259 -273.207333)
					(end 264.375138 -273.171412)
				)
				(arc
					(start 264.375138 -272.762472)
					(mid 264.360259 -272.726551)
					(end 264.324338 -272.711672)
				)
				(arc
					(start 262.924798 -272.711672)
					(mid 262.888877 -272.726551)
					(end 262.873998 -272.762472)
				)
			)
		)
	)
	(zone
		(layers "In1.Cu" "In2.Cu")
		(hatch none 0.5)
		(connect_pads
			(clearance 0)
		)
		(min_thickness 0.25)
		(keepout
			(tracks not_allowed)
			(vias allowed)
			(pads allowed)
			(copperpour not_allowed)
			(footprints allowed)
		)
		(placement
			(enabled no)
			(sheetname "")
		)
		(fill yes
			(thermal_gap 0.5)
			(thermal_bridge_width 0.5)
			(island_removal_mode 0)
		)
		(polygon
			(pts
				(arc
					(start 462.909666 -248.521474)
					(mid 462.924545 -248.557395)
					(end 462.960466 -248.572274)
				)
				(arc
					(start 464.360006 -248.572274)
					(mid 464.395927 -248.557395)
					(end 464.410806 -248.521474)
				)
				(arc
					(start 464.410806 -248.112534)
					(mid 464.395927 -248.076613)
					(end 464.360006 -248.061734)
				)
				(arc
					(start 462.960466 -248.061734)
					(mid 462.924545 -248.076613)
					(end 462.909666 -248.112534)
				)
			)
		)
	)
	(zone
		(layers "In1.Cu" "In2.Cu")
		(hatch none 0.5)
		(connect_pads
			(clearance 0)
		)
		(min_thickness 0.25)
		(keepout
			(tracks not_allowed)
			(vias allowed)
			(pads allowed)
			(copperpour not_allowed)
			(footprints allowed)
		)
		(placement
			(enabled no)
			(sheetname "")
		)
		(fill yes
			(thermal_gap 0.5)
			(thermal_bridge_width 0.5)
			(island_removal_mode 0)
		)
		(polygon
			(pts
				(arc
					(start 436.178198 -296.121328)
					(mid 436.193077 -296.157249)
					(end 436.228998 -296.172128)
				)
				(arc
					(start 437.628538 -296.172128)
					(mid 437.664459 -296.157249)
					(end 437.679338 -296.121328)
				)
				(arc
					(start 437.679338 -295.712388)
					(mid 437.664459 -295.676467)
					(end 437.628538 -295.661588)
				)
				(arc
					(start 436.228998 -295.661588)
					(mid 436.193077 -295.676467)
					(end 436.178198 -295.712388)
				)
			)
		)
	)
	(zone
		(layers "In1.Cu" "In2.Cu")
		(hatch none 0.5)
		(connect_pads
			(clearance 0)
		)
		(min_thickness 0.25)
		(keepout
			(tracks not_allowed)
			(vias allowed)
			(pads allowed)
			(copperpour not_allowed)
			(footprints allowed)
		)
		(placement
			(enabled no)
			(sheetname "")
		)
		(fill yes
			(thermal_gap 0.5)
			(thermal_bridge_width 0.5)
			(island_removal_mode 0)
		)
		(polygon
			(pts
				(arc
					(start 425.190666 -195.821554)
					(mid 425.205545 -195.857475)
					(end 425.241466 -195.872354)
				)
				(arc
					(start 426.641006 -195.872354)
					(mid 426.676927 -195.857475)
					(end 426.691806 -195.821554)
				)
				(arc
					(start 426.691806 -195.412614)
					(mid 426.676927 -195.376693)
					(end 426.641006 -195.361814)
				)
				(arc
					(start 425.241466 -195.361814)
					(mid 425.205545 -195.376693)
					(end 425.190666 -195.412614)
				)
			)
		)
	)
	(zone
		(layers "In1.Cu" "In2.Cu")
		(hatch none 0.5)
		(connect_pads
			(clearance 0)
		)
		(min_thickness 0.25)
		(keepout
			(tracks not_allowed)
			(vias allowed)
			(pads allowed)
			(copperpour not_allowed)
			(footprints allowed)
		)
		(placement
			(enabled no)
			(sheetname "")
		)
		(fill yes
			(thermal_gap 0.5)
			(thermal_bridge_width 0.5)
			(island_removal_mode 0)
		)
		(polygon
			(pts
				(arc
					(start 274.517866 -199.221344)
					(mid 274.532745 -199.257265)
					(end 274.568666 -199.272144)
				)
				(arc
					(start 275.968206 -199.272144)
					(mid 276.004127 -199.257265)
					(end 276.019006 -199.221344)
				)
				(arc
					(start 276.019006 -198.812404)
					(mid 276.004127 -198.776483)
					(end 275.968206 -198.761604)
				)
				(arc
					(start 274.568666 -198.761604)
					(mid 274.532745 -198.776483)
					(end 274.517866 -198.812404)
				)
			)
		)
	)
	(zone
		(layers "In1.Cu" "In2.Cu")
		(hatch none 0.5)
		(connect_pads
			(clearance 0)
		)
		(min_thickness 0.25)
		(keepout
			(tracks not_allowed)
			(vias allowed)
			(pads allowed)
			(copperpour not_allowed)
			(footprints allowed)
		)
		(placement
			(enabled no)
			(sheetname "")
		)
		(fill yes
			(thermal_gap 0.5)
			(thermal_bridge_width 0.5)
			(island_removal_mode 0)
		)
		(polygon
			(pts
				(arc
					(start 180.69433 -224.72142)
					(mid 180.709209 -224.757341)
					(end 180.74513 -224.77222)
				)
				(arc
					(start 182.14467 -224.77222)
					(mid 182.180591 -224.757341)
					(end 182.19547 -224.72142)
				)
				(arc
					(start 182.19547 -224.31248)
					(mid 182.180591 -224.276559)
					(end 182.14467 -224.26168)
				)
				(arc
					(start 180.74513 -224.26168)
					(mid 180.709209 -224.276559)
					(end 180.69433 -224.31248)
				)
			)
		)
	)
	(zone
		(layers "In1.Cu" "In2.Cu")
		(hatch none 0.5)
		(connect_pads
			(clearance 0)
		)
		(min_thickness 0.25)
		(keepout
			(tracks not_allowed)
			(vias allowed)
			(pads allowed)
			(copperpour not_allowed)
			(footprints allowed)
		)
		(placement
			(enabled no)
			(sheetname "")
		)
		(fill yes
			(thermal_gap 0.5)
			(thermal_bridge_width 0.5)
			(island_removal_mode 0)
		)
		(polygon
			(pts
				(arc
					(start 30.02153 -294.421306)
					(mid 30.036409 -294.457227)
					(end 30.07233 -294.472106)
				)
				(arc
					(start 31.47187 -294.472106)
					(mid 31.507791 -294.457227)
					(end 31.52267 -294.421306)
				)
				(arc
					(start 31.52267 -294.012366)
					(mid 31.507791 -293.976445)
					(end 31.47187 -293.961566)
				)
				(arc
					(start 30.07233 -293.961566)
					(mid 30.036409 -293.976445)
					(end 30.02153 -294.012366)
				)
			)
		)
	)
	(zone
		(layers "In1.Cu" "In2.Cu")
		(hatch none 0.5)
		(connect_pads
			(clearance 0)
		)
		(min_thickness 0.25)
		(keepout
			(tracks not_allowed)
			(vias allowed)
			(pads allowed)
			(copperpour not_allowed)
			(footprints allowed)
		)
		(placement
			(enabled no)
			(sheetname "")
		)
		(fill yes
			(thermal_gap 0.5)
			(thermal_bridge_width 0.5)
			(island_removal_mode 0)
		)
		(polygon
			(pts
				(arc
					(start 443.721998 -223.021398)
					(mid 443.736877 -223.057319)
					(end 443.772798 -223.072198)
				)
				(arc
					(start 445.172338 -223.072198)
					(mid 445.208259 -223.057319)
					(end 445.223138 -223.021398)
				)
				(arc
					(start 445.223138 -222.612458)
					(mid 445.208259 -222.576537)
					(end 445.172338 -222.561658)
				)
				(arc
					(start 443.772798 -222.561658)
					(mid 443.736877 -222.576537)
					(end 443.721998 -222.612458)
				)
			)
		)
	)
	(zone
		(layers "In1.Cu" "In2.Cu")
		(hatch none 0.5)
		(connect_pads
			(clearance 0)
		)
		(min_thickness 0.25)
		(keepout
			(tracks not_allowed)
			(vias allowed)
			(pads allowed)
			(copperpour not_allowed)
			(footprints allowed)
		)
		(placement
			(enabled no)
			(sheetname "")
		)
		(fill yes
			(thermal_gap 0.5)
			(thermal_bridge_width 0.5)
			(island_removal_mode 0)
		)
		(polygon
			(pts
				(arc
					(start 60.19673 -268.071346)
					(mid 60.211609 -268.107267)
					(end 60.24753 -268.122146)
				)
				(arc
					(start 61.64707 -268.122146)
					(mid 61.682991 -268.107267)
					(end 61.69787 -268.071346)
				)
				(arc
					(start 61.69787 -267.662406)
					(mid 61.682991 -267.626485)
					(end 61.64707 -267.611606)
				)
				(arc
					(start 60.24753 -267.611606)
					(mid 60.211609 -267.626485)
					(end 60.19673 -267.662406)
				)
			)
		)
	)
	(zone
		(layers "In1.Cu" "In2.Cu")
		(hatch none 0.5)
		(connect_pads
			(clearance 0)
		)
		(min_thickness 0.25)
		(keepout
			(tracks not_allowed)
			(vias allowed)
			(pads allowed)
			(copperpour not_allowed)
			(footprints allowed)
		)
		(placement
			(enabled no)
			(sheetname "")
		)
		(fill yes
			(thermal_gap 0.5)
			(thermal_bridge_width 0.5)
			(island_removal_mode 0)
		)
		(polygon
			(pts
				(arc
					(start 169.706798 -201.771504)
					(mid 169.721677 -201.807425)
					(end 169.757598 -201.822304)
				)
				(arc
					(start 171.157138 -201.822304)
					(mid 171.193059 -201.807425)
					(end 171.207938 -201.771504)
				)
				(arc
					(start 171.207938 -201.362564)
					(mid 171.193059 -201.326643)
					(end 171.157138 -201.311764)
				)
				(arc
					(start 169.757598 -201.311764)
					(mid 169.721677 -201.326643)
					(end 169.706798 -201.362564)
				)
			)
		)
	)
	(zone
		(layers "In1.Cu" "In2.Cu")
		(hatch none 0.5)
		(connect_pads
			(clearance 0)
		)
		(min_thickness 0.25)
		(keepout
			(tracks not_allowed)
			(vias allowed)
			(pads allowed)
			(copperpour not_allowed)
			(footprints allowed)
		)
		(placement
			(enabled no)
			(sheetname "")
		)
		(fill yes
			(thermal_gap 0.5)
			(thermal_bridge_width 0.5)
			(island_removal_mode 0)
		)
		(polygon
			(pts
				(arc
					(start 195.78193 -243.421408)
					(mid 195.796809 -243.457329)
					(end 195.83273 -243.472208)
				)
				(arc
					(start 197.23227 -243.472208)
					(mid 197.268191 -243.457329)
					(end 197.28307 -243.421408)
				)
				(arc
					(start 197.28307 -243.012468)
					(mid 197.268191 -242.976547)
					(end 197.23227 -242.961668)
				)
				(arc
					(start 195.83273 -242.961668)
					(mid 195.796809 -242.976547)
					(end 195.78193 -243.012468)
				)
			)
		)
	)
	(zone
		(layers "In1.Cu" "In2.Cu")
		(hatch none 0.5)
		(connect_pads
			(clearance 0)
		)
		(min_thickness 0.25)
		(keepout
			(tracks not_allowed)
			(vias allowed)
			(pads allowed)
			(copperpour not_allowed)
			(footprints allowed)
		)
		(placement
			(enabled no)
			(sheetname "")
		)
		(fill yes
			(thermal_gap 0.5)
			(thermal_bridge_width 0.5)
			(island_removal_mode 0)
		)
		(polygon
			(pts
				(arc
					(start 255.330198 -314.821316)
					(mid 255.345077 -314.857237)
					(end 255.380998 -314.872116)
				)
				(arc
					(start 256.780538 -314.872116)
					(mid 256.816459 -314.857237)
					(end 256.831338 -314.821316)
				)
				(arc
					(start 256.831338 -314.412376)
					(mid 256.816459 -314.376455)
					(end 256.780538 -314.361576)
				)
				(arc
					(start 255.380998 -314.361576)
					(mid 255.345077 -314.376455)
					(end 255.330198 -314.412376)
				)
			)
		)
	)
	(zone
		(layers "In1.Cu" "In2.Cu")
		(hatch none 0.5)
		(connect_pads
			(clearance 0)
		)
		(min_thickness 0.25)
		(keepout
			(tracks not_allowed)
			(vias allowed)
			(pads allowed)
			(copperpour not_allowed)
			(footprints allowed)
		)
		(placement
			(enabled no)
			(sheetname "")
		)
		(fill yes
			(thermal_gap 0.5)
			(thermal_bridge_width 0.5)
			(island_removal_mode 0)
		)
		(polygon
			(pts
				(arc
					(start 41.665398 -284.221428)
					(mid 41.680277 -284.257349)
					(end 41.716198 -284.272228)
				)
				(arc
					(start 43.115738 -284.272228)
					(mid 43.151659 -284.257349)
					(end 43.166538 -284.221428)
				)
				(arc
					(start 43.166538 -283.812488)
					(mid 43.151659 -283.776567)
					(end 43.115738 -283.761688)
				)
				(arc
					(start 41.716198 -283.761688)
					(mid 41.680277 -283.776567)
					(end 41.665398 -283.812488)
				)
			)
		)
	)
	(zone
		(layers "In1.Cu" "In2.Cu")
		(hatch none 0.5)
		(connect_pads
			(clearance 0)
		)
		(min_thickness 0.25)
		(keepout
			(tracks not_allowed)
			(vias allowed)
			(pads allowed)
			(copperpour not_allowed)
			(footprints allowed)
		)
		(placement
			(enabled no)
			(sheetname "")
		)
		(fill yes
			(thermal_gap 0.5)
			(thermal_bridge_width 0.5)
			(island_removal_mode 0)
		)
		(polygon
			(pts
				(arc
					(start 14.93393 -206.021432)
					(mid 14.948809 -206.057353)
					(end 14.98473 -206.072232)
				)
				(arc
					(start 16.38427 -206.072232)
					(mid 16.420191 -206.057353)
					(end 16.43507 -206.021432)
				)
				(arc
					(start 16.43507 -205.612492)
					(mid 16.420191 -205.576571)
					(end 16.38427 -205.561692)
				)
				(arc
					(start 14.98473 -205.561692)
					(mid 14.948809 -205.576571)
					(end 14.93393 -205.612492)
				)
			)
		)
	)
	(zone
		(layers "In1.Cu" "In2.Cu")
		(hatch none 0.5)
		(connect_pads
			(clearance 0)
		)
		(min_thickness 0.25)
		(keepout
			(tracks not_allowed)
			(vias allowed)
			(pads allowed)
			(copperpour not_allowed)
			(footprints allowed)
		)
		(placement
			(enabled no)
			(sheetname "")
		)
		(fill yes
			(thermal_gap 0.5)
			(thermal_bridge_width 0.5)
			(island_removal_mode 0)
		)
		(polygon
			(pts
				(arc
					(start 255.330198 -277.42134)
					(mid 255.345077 -277.457261)
					(end 255.380998 -277.47214)
				)
				(arc
					(start 256.780538 -277.47214)
					(mid 256.816459 -277.457261)
					(end 256.831338 -277.42134)
				)
				(arc
					(start 256.831338 -277.0124)
					(mid 256.816459 -276.976479)
					(end 256.780538 -276.9616)
				)
				(arc
					(start 255.380998 -276.9616)
					(mid 255.345077 -276.976479)
					(end 255.330198 -277.0124)
				)
			)
		)
	)
	(zone
		(layers "In1.Cu" "In2.Cu")
		(hatch none 0.5)
		(connect_pads
			(clearance 0)
		)
		(min_thickness 0.25)
		(keepout
			(tracks not_allowed)
			(vias allowed)
			(pads allowed)
			(copperpour not_allowed)
			(footprints allowed)
		)
		(placement
			(enabled no)
			(sheetname "")
		)
		(fill yes
			(thermal_gap 0.5)
			(thermal_bridge_width 0.5)
			(island_removal_mode 0)
		)
		(polygon
			(pts
				(arc
					(start 436.178198 -228.971348)
					(mid 436.193077 -229.007269)
					(end 436.228998 -229.022148)
				)
				(arc
					(start 437.628538 -229.022148)
					(mid 437.664459 -229.007269)
					(end 437.679338 -228.971348)
				)
				(arc
					(start 437.679338 -228.562408)
					(mid 437.664459 -228.526487)
					(end 437.628538 -228.511608)
				)
				(arc
					(start 436.228998 -228.511608)
					(mid 436.193077 -228.526487)
					(end 436.178198 -228.562408)
				)
			)
		)
	)
	(zone
		(layers "In1.Cu" "In2.Cu")
		(hatch none 0.5)
		(connect_pads
			(clearance 0)
		)
		(min_thickness 0.25)
		(keepout
			(tracks not_allowed)
			(vias allowed)
			(pads allowed)
			(copperpour not_allowed)
			(footprints allowed)
		)
		(placement
			(enabled no)
			(sheetname "")
		)
		(fill yes
			(thermal_gap 0.5)
			(thermal_bridge_width 0.5)
			(island_removal_mode 0)
		)
		(polygon
			(pts
				(arc
					(start 413.546798 -271.47139)
					(mid 413.561677 -271.507311)
					(end 413.597598 -271.52219)
				)
				(arc
					(start 414.997138 -271.52219)
					(mid 415.033059 -271.507311)
					(end 415.047938 -271.47139)
				)
				(arc
					(start 415.047938 -271.06245)
					(mid 415.033059 -271.026529)
					(end 414.997138 -271.01165)
				)
				(arc
					(start 413.597598 -271.01165)
					(mid 413.561677 -271.026529)
					(end 413.546798 -271.06245)
				)
			)
		)
	)
	(zone
		(layers "In1.Cu" "In2.Cu")
		(hatch none 0.5)
		(connect_pads
			(clearance 0)
		)
		(min_thickness 0.25)
		(keepout
			(tracks not_allowed)
			(vias allowed)
			(pads allowed)
			(copperpour not_allowed)
			(footprints allowed)
		)
		(placement
			(enabled no)
			(sheetname "")
		)
		(fill yes
			(thermal_gap 0.5)
			(thermal_bridge_width 0.5)
			(island_removal_mode 0)
		)
		(polygon
			(pts
				(arc
					(start 49.209198 -262.121396)
					(mid 49.224077 -262.157317)
					(end 49.259998 -262.172196)
				)
				(arc
					(start 50.659538 -262.172196)
					(mid 50.695459 -262.157317)
					(end 50.710338 -262.121396)
				)
				(arc
					(start 50.710338 -261.712456)
					(mid 50.695459 -261.676535)
					(end 50.659538 -261.661656)
				)
				(arc
					(start 49.259998 -261.661656)
					(mid 49.224077 -261.676535)
					(end 49.209198 -261.712456)
				)
			)
		)
	)
	(zone
		(layers "In1.Cu" "In2.Cu")
		(hatch none 0.5)
		(connect_pads
			(clearance 0)
		)
		(min_thickness 0.25)
		(keepout
			(tracks not_allowed)
			(vias allowed)
			(pads allowed)
			(copperpour not_allowed)
			(footprints allowed)
		)
		(placement
			(enabled no)
			(sheetname "")
		)
		(fill yes
			(thermal_gap 0.5)
			(thermal_bridge_width 0.5)
			(island_removal_mode 0)
		)
		(polygon
			(pts
				(arc
					(start 277.961598 -316.521338)
					(mid 277.976477 -316.557259)
					(end 278.012398 -316.572138)
				)
				(arc
					(start 279.411938 -316.572138)
					(mid 279.447859 -316.557259)
					(end 279.462738 -316.521338)
				)
				(arc
					(start 279.462738 -316.112398)
					(mid 279.447859 -316.076477)
					(end 279.411938 -316.061598)
				)
				(arc
					(start 278.012398 -316.061598)
					(mid 277.976477 -316.076477)
					(end 277.961598 -316.112398)
				)
			)
		)
	)
	(zone
		(layers "In1.Cu" "In2.Cu")
		(hatch none 0.5)
		(connect_pads
			(clearance 0)
		)
		(min_thickness 0.25)
		(keepout
			(tracks not_allowed)
			(vias allowed)
			(pads allowed)
			(copperpour not_allowed)
			(footprints allowed)
		)
		(placement
			(enabled no)
			(sheetname "")
		)
		(fill yes
			(thermal_gap 0.5)
			(thermal_bridge_width 0.5)
			(island_removal_mode 0)
		)
		(polygon
			(pts
				(arc
					(start 447.822066 -309.721504)
					(mid 447.836945 -309.757425)
					(end 447.872866 -309.772304)
				)
				(arc
					(start 449.272406 -309.772304)
					(mid 449.308327 -309.757425)
					(end 449.323206 -309.721504)
				)
				(arc
					(start 449.323206 -309.312564)
					(mid 449.308327 -309.276643)
					(end 449.272406 -309.261764)
				)
				(arc
					(start 447.872866 -309.261764)
					(mid 447.836945 -309.276643)
					(end 447.822066 -309.312564)
				)
			)
		)
	)
	(zone
		(layers "In1.Cu" "In2.Cu")
		(hatch none 0.5)
		(connect_pads
			(clearance 0)
		)
		(min_thickness 0.25)
		(keepout
			(tracks not_allowed)
			(vias allowed)
			(pads allowed)
			(copperpour not_allowed)
			(footprints allowed)
		)
		(placement
			(enabled no)
			(sheetname "")
		)
		(fill yes
			(thermal_gap 0.5)
			(thermal_bridge_width 0.5)
			(island_removal_mode 0)
		)
		(polygon
			(pts
				(arc
					(start 180.69433 -206.021432)
					(mid 180.709209 -206.057353)
					(end 180.74513 -206.072232)
				)
				(arc
					(start 182.14467 -206.072232)
					(mid 182.180591 -206.057353)
					(end 182.19547 -206.021432)
				)
				(arc
					(start 182.19547 -205.612492)
					(mid 182.180591 -205.576571)
					(end 182.14467 -205.561692)
				)
				(arc
					(start 180.74513 -205.561692)
					(mid 180.709209 -205.576571)
					(end 180.69433 -205.612492)
				)
			)
		)
	)
	(zone
		(layers "In1.Cu" "In2.Cu")
		(hatch none 0.5)
		(connect_pads
			(clearance 0)
		)
		(min_thickness 0.25)
		(keepout
			(tracks not_allowed)
			(vias allowed)
			(pads allowed)
			(copperpour not_allowed)
			(footprints allowed)
		)
		(placement
			(enabled no)
			(sheetname "")
		)
		(fill yes
			(thermal_gap 0.5)
			(thermal_bridge_width 0.5)
			(island_removal_mode 0)
		)
		(polygon
			(pts
				(arc
					(start 270.417798 -228.121464)
					(mid 270.432677 -228.157385)
					(end 270.468598 -228.172264)
				)
				(arc
					(start 271.868138 -228.172264)
					(mid 271.904059 -228.157385)
					(end 271.918938 -228.121464)
				)
				(arc
					(start 271.918938 -227.712524)
					(mid 271.904059 -227.676603)
					(end 271.868138 -227.661724)
				)
				(arc
					(start 270.468598 -227.661724)
					(mid 270.432677 -227.676603)
					(end 270.417798 -227.712524)
				)
			)
		)
	)
	(zone
		(layers "In1.Cu" "In2.Cu")
		(hatch none 0.5)
		(connect_pads
			(clearance 0)
		)
		(min_thickness 0.25)
		(keepout
			(tracks not_allowed)
			(vias allowed)
			(pads allowed)
			(copperpour not_allowed)
			(footprints allowed)
		)
		(placement
			(enabled no)
			(sheetname "")
		)
		(fill yes
			(thermal_gap 0.5)
			(thermal_bridge_width 0.5)
			(island_removal_mode 0)
		)
		(polygon
			(pts
				(arc
					(start 22.47773 -219.621354)
					(mid 22.492609 -219.657275)
					(end 22.52853 -219.672154)
				)
				(arc
					(start 23.92807 -219.672154)
					(mid 23.963991 -219.657275)
					(end 23.97887 -219.621354)
				)
				(arc
					(start 23.97887 -219.212414)
					(mid 23.963991 -219.176493)
					(end 23.92807 -219.161614)
				)
				(arc
					(start 22.52853 -219.161614)
					(mid 22.492609 -219.176493)
					(end 22.47773 -219.212414)
				)
			)
		)
	)
	(zone
		(layers "In1.Cu" "In2.Cu")
		(hatch none 0.5)
		(connect_pads
			(clearance 0)
		)
		(min_thickness 0.25)
		(keepout
			(tracks not_allowed)
			(vias allowed)
			(pads allowed)
			(copperpour not_allowed)
			(footprints allowed)
		)
		(placement
			(enabled no)
			(sheetname "")
		)
		(fill yes
			(thermal_gap 0.5)
			(thermal_bridge_width 0.5)
			(island_removal_mode 0)
		)
		(polygon
			(pts
				(arc
					(start 406.002998 -237.471458)
					(mid 406.017877 -237.507379)
					(end 406.053798 -237.522258)
				)
				(arc
					(start 407.453338 -237.522258)
					(mid 407.489259 -237.507379)
					(end 407.504138 -237.471458)
				)
				(arc
					(start 407.504138 -237.062518)
					(mid 407.489259 -237.026597)
					(end 407.453338 -237.011718)
				)
				(arc
					(start 406.053798 -237.011718)
					(mid 406.017877 -237.026597)
					(end 406.002998 -237.062518)
				)
			)
		)
	)
	(zone
		(layers "In1.Cu" "In2.Cu")
		(hatch none 0.5)
		(connect_pads
			(clearance 0)
		)
		(min_thickness 0.25)
		(keepout
			(tracks not_allowed)
			(vias allowed)
			(pads allowed)
			(copperpour not_allowed)
			(footprints allowed)
		)
		(placement
			(enabled no)
			(sheetname "")
		)
		(fill yes
			(thermal_gap 0.5)
			(thermal_bridge_width 0.5)
			(island_removal_mode 0)
		)
		(polygon
			(pts
				(arc
					(start 443.721998 -310.571388)
					(mid 443.736877 -310.607309)
					(end 443.772798 -310.622188)
				)
				(arc
					(start 445.172338 -310.622188)
					(mid 445.208259 -310.607309)
					(end 445.223138 -310.571388)
				)
				(arc
					(start 445.223138 -310.162448)
					(mid 445.208259 -310.126527)
					(end 445.172338 -310.111648)
				)
				(arc
					(start 443.772798 -310.111648)
					(mid 443.736877 -310.126527)
					(end 443.721998 -310.162448)
				)
			)
		)
	)
	(zone
		(layers "In1.Cu" "In2.Cu")
		(hatch none 0.5)
		(connect_pads
			(clearance 0)
		)
		(min_thickness 0.25)
		(keepout
			(tracks not_allowed)
			(vias allowed)
			(pads allowed)
			(copperpour not_allowed)
			(footprints allowed)
		)
		(placement
			(enabled no)
			(sheetname "")
		)
		(fill yes
			(thermal_gap 0.5)
			(thermal_bridge_width 0.5)
			(island_removal_mode 0)
		)
		(polygon
			(pts
				(arc
					(start 60.19673 -218.77147)
					(mid 60.211609 -218.807391)
					(end 60.24753 -218.82227)
				)
				(arc
					(start 61.64707 -218.82227)
					(mid 61.682991 -218.807391)
					(end 61.69787 -218.77147)
				)
				(arc
					(start 61.69787 -218.36253)
					(mid 61.682991 -218.326609)
					(end 61.64707 -218.31173)
				)
				(arc
					(start 60.24753 -218.31173)
					(mid 60.211609 -218.326609)
					(end 60.19673 -218.36253)
				)
			)
		)
	)
	(zone
		(layers "In1.Cu" "In2.Cu")
		(hatch none 0.5)
		(connect_pads
			(clearance 0)
		)
		(min_thickness 0.25)
		(keepout
			(tracks not_allowed)
			(vias allowed)
			(pads allowed)
			(copperpour not_allowed)
			(footprints allowed)
		)
		(placement
			(enabled no)
			(sheetname "")
		)
		(fill yes
			(thermal_gap 0.5)
			(thermal_bridge_width 0.5)
			(island_removal_mode 0)
		)
		(polygon
			(pts
				(arc
					(start 165.60673 -305.471322)
					(mid 165.621609 -305.507243)
					(end 165.65753 -305.522122)
				)
				(arc
					(start 167.05707 -305.522122)
					(mid 167.092991 -305.507243)
					(end 167.10787 -305.471322)
				)
				(arc
					(start 167.10787 -305.062382)
					(mid 167.092991 -305.026461)
					(end 167.05707 -305.011582)
				)
				(arc
					(start 165.65753 -305.011582)
					(mid 165.621609 -305.026461)
					(end 165.60673 -305.062382)
				)
			)
		)
	)
	(zone
		(layers "In1.Cu" "In2.Cu")
		(hatch none 0.5)
		(connect_pads
			(clearance 0)
		)
		(min_thickness 0.25)
		(keepout
			(tracks not_allowed)
			(vias allowed)
			(pads allowed)
			(copperpour not_allowed)
			(footprints allowed)
		)
		(placement
			(enabled no)
			(sheetname "")
		)
		(fill yes
			(thermal_gap 0.5)
			(thermal_bridge_width 0.5)
			(island_removal_mode 0)
		)
		(polygon
			(pts
				(arc
					(start 417.646866 -205.171548)
					(mid 417.661745 -205.207469)
					(end 417.697666 -205.222348)
				)
				(arc
					(start 419.097206 -205.222348)
					(mid 419.133127 -205.207469)
					(end 419.148006 -205.171548)
				)
				(arc
					(start 419.148006 -204.762608)
					(mid 419.133127 -204.726687)
					(end 419.097206 -204.711808)
				)
				(arc
					(start 417.697666 -204.711808)
					(mid 417.661745 -204.726687)
					(end 417.646866 -204.762608)
				)
			)
		)
	)
	(zone
		(layers "In1.Cu" "In2.Cu")
		(hatch none 0.5)
		(connect_pads
			(clearance 0)
		)
		(min_thickness 0.25)
		(keepout
			(tracks not_allowed)
			(vias allowed)
			(pads allowed)
			(copperpour not_allowed)
			(footprints allowed)
		)
		(placement
			(enabled no)
			(sheetname "")
		)
		(fill yes
			(thermal_gap 0.5)
			(thermal_bridge_width 0.5)
			(island_removal_mode 0)
		)
		(polygon
			(pts
				(arc
					(start 458.809598 -266.371324)
					(mid 458.824477 -266.407245)
					(end 458.860398 -266.422124)
				)
				(arc
					(start 460.259938 -266.422124)
					(mid 460.295859 -266.407245)
					(end 460.310738 -266.371324)
				)
				(arc
					(start 460.310738 -265.962384)
					(mid 460.295859 -265.926463)
					(end 460.259938 -265.911584)
				)
				(arc
					(start 458.860398 -265.911584)
					(mid 458.824477 -265.926463)
					(end 458.809598 -265.962384)
				)
			)
		)
	)
	(zone
		(layers "In1.Cu" "In2.Cu")
		(hatch none 0.5)
		(connect_pads
			(clearance 0)
		)
		(min_thickness 0.25)
		(keepout
			(tracks not_allowed)
			(vias allowed)
			(pads allowed)
			(copperpour not_allowed)
			(footprints allowed)
		)
		(placement
			(enabled no)
			(sheetname "")
		)
		(fill yes
			(thermal_gap 0.5)
			(thermal_bridge_width 0.5)
			(island_removal_mode 0)
		)
		(polygon
			(pts
				(arc
					(start 406.002998 -230.67137)
					(mid 406.017877 -230.707291)
					(end 406.053798 -230.72217)
				)
				(arc
					(start 407.453338 -230.72217)
					(mid 407.489259 -230.707291)
					(end 407.504138 -230.67137)
				)
				(arc
					(start 407.504138 -230.26243)
					(mid 407.489259 -230.226509)
					(end 407.453338 -230.21163)
				)
				(arc
					(start 406.053798 -230.21163)
					(mid 406.017877 -230.226509)
					(end 406.002998 -230.26243)
				)
			)
		)
	)
	(zone
		(layers "In1.Cu" "In2.Cu")
		(hatch none 0.5)
		(connect_pads
			(clearance 0)
		)
		(min_thickness 0.25)
		(keepout
			(tracks not_allowed)
			(vias allowed)
			(pads allowed)
			(copperpour not_allowed)
			(footprints allowed)
		)
		(placement
			(enabled no)
			(sheetname "")
		)
		(fill yes
			(thermal_gap 0.5)
			(thermal_bridge_width 0.5)
			(island_removal_mode 0)
		)
		(polygon
			(pts
				(arc
					(start 282.061666 -308.021482)
					(mid 282.076545 -308.057403)
					(end 282.112466 -308.072282)
				)
				(arc
					(start 283.512006 -308.072282)
					(mid 283.547927 -308.057403)
					(end 283.562806 -308.021482)
				)
				(arc
					(start 283.562806 -307.612542)
					(mid 283.547927 -307.576621)
					(end 283.512006 -307.561742)
				)
				(arc
					(start 282.112466 -307.561742)
					(mid 282.076545 -307.576621)
					(end 282.061666 -307.612542)
				)
			)
		)
	)
	(zone
		(layers "In1.Cu" "In2.Cu")
		(hatch none 0.5)
		(connect_pads
			(clearance 0)
		)
		(min_thickness 0.25)
		(keepout
			(tracks not_allowed)
			(vias allowed)
			(pads allowed)
			(copperpour not_allowed)
			(footprints allowed)
		)
		(placement
			(enabled no)
			(sheetname "")
		)
		(fill yes
			(thermal_gap 0.5)
			(thermal_bridge_width 0.5)
			(island_removal_mode 0)
		)
		(polygon
			(pts
				(arc
					(start 210.86953 -234.071414)
					(mid 210.884409 -234.107335)
					(end 210.92033 -234.122214)
				)
				(arc
					(start 212.31987 -234.122214)
					(mid 212.355791 -234.107335)
					(end 212.37067 -234.071414)
				)
				(arc
					(start 212.37067 -233.662474)
					(mid 212.355791 -233.626553)
					(end 212.31987 -233.611674)
				)
				(arc
					(start 210.92033 -233.611674)
					(mid 210.884409 -233.626553)
					(end 210.86953 -233.662474)
				)
			)
		)
	)
	(zone
		(layers "In1.Cu" "In2.Cu")
		(hatch none 0.5)
		(connect_pads
			(clearance 0)
		)
		(min_thickness 0.25)
		(keepout
			(tracks not_allowed)
			(vias allowed)
			(pads allowed)
			(copperpour not_allowed)
			(footprints allowed)
		)
		(placement
			(enabled no)
			(sheetname "")
		)
		(fill yes
			(thermal_gap 0.5)
			(thermal_bridge_width 0.5)
			(island_removal_mode 0)
		)
		(polygon
			(pts
				(arc
					(start 60.19673 -290.171378)
					(mid 60.211609 -290.207299)
					(end 60.24753 -290.222178)
				)
				(arc
					(start 61.64707 -290.222178)
					(mid 61.682991 -290.207299)
					(end 61.69787 -290.171378)
				)
				(arc
					(start 61.69787 -289.762438)
					(mid 61.682991 -289.726517)
					(end 61.64707 -289.711638)
				)
				(arc
					(start 60.24753 -289.711638)
					(mid 60.211609 -289.726517)
					(end 60.19673 -289.762438)
				)
			)
		)
	)
	(zone
		(layers "In1.Cu" "In2.Cu")
		(hatch none 0.5)
		(connect_pads
			(clearance 0)
		)
		(min_thickness 0.25)
		(keepout
			(tracks not_allowed)
			(vias allowed)
			(pads allowed)
			(copperpour not_allowed)
			(footprints allowed)
		)
		(placement
			(enabled no)
			(sheetname "")
		)
		(fill yes
			(thermal_gap 0.5)
			(thermal_bridge_width 0.5)
			(island_removal_mode 0)
		)
		(polygon
			(pts
				(arc
					(start 289.605466 -302.921416)
					(mid 289.620345 -302.957337)
					(end 289.656266 -302.972216)
				)
				(arc
					(start 291.055806 -302.972216)
					(mid 291.091727 -302.957337)
					(end 291.106606 -302.921416)
				)
				(arc
					(start 291.106606 -302.512476)
					(mid 291.091727 -302.476555)
					(end 291.055806 -302.461676)
				)
				(arc
					(start 289.656266 -302.461676)
					(mid 289.620345 -302.476555)
					(end 289.605466 -302.512476)
				)
			)
		)
	)
	(zone
		(layers "In1.Cu" "In2.Cu")
		(hatch none 0.5)
		(connect_pads
			(clearance 0)
		)
		(min_thickness 0.25)
		(keepout
			(tracks not_allowed)
			(vias allowed)
			(pads allowed)
			(copperpour not_allowed)
			(footprints allowed)
		)
		(placement
			(enabled no)
			(sheetname "")
		)
		(fill yes
			(thermal_gap 0.5)
			(thermal_bridge_width 0.5)
			(island_removal_mode 0)
		)
		(polygon
			(pts
				(arc
					(start 30.02153 -266.371324)
					(mid 30.036409 -266.407245)
					(end 30.07233 -266.422124)
				)
				(arc
					(start 31.47187 -266.422124)
					(mid 31.507791 -266.407245)
					(end 31.52267 -266.371324)
				)
				(arc
					(start 31.52267 -265.962384)
					(mid 31.507791 -265.926463)
					(end 31.47187 -265.911584)
				)
				(arc
					(start 30.07233 -265.911584)
					(mid 30.036409 -265.926463)
					(end 30.02153 -265.962384)
				)
			)
		)
	)
	(zone
		(layers "In1.Cu" "In2.Cu")
		(hatch none 0.5)
		(connect_pads
			(clearance 0)
		)
		(min_thickness 0.25)
		(keepout
			(tracks not_allowed)
			(vias allowed)
			(pads allowed)
			(copperpour not_allowed)
			(footprints allowed)
		)
		(placement
			(enabled no)
			(sheetname "")
		)
		(fill yes
			(thermal_gap 0.5)
			(thermal_bridge_width 0.5)
			(island_removal_mode 0)
		)
		(polygon
			(pts
				(arc
					(start 49.209198 -245.12143)
					(mid 49.224077 -245.157351)
					(end 49.259998 -245.17223)
				)
				(arc
					(start 50.659538 -245.17223)
					(mid 50.695459 -245.157351)
					(end 50.710338 -245.12143)
				)
				(arc
					(start 50.710338 -244.71249)
					(mid 50.695459 -244.676569)
					(end 50.659538 -244.66169)
				)
				(arc
					(start 49.259998 -244.66169)
					(mid 49.224077 -244.676569)
					(end 49.209198 -244.71249)
				)
			)
		)
	)
	(zone
		(layers "In1.Cu" "In2.Cu")
		(hatch none 0.5)
		(connect_pads
			(clearance 0)
		)
		(min_thickness 0.25)
		(keepout
			(tracks not_allowed)
			(vias allowed)
			(pads allowed)
			(copperpour not_allowed)
			(footprints allowed)
		)
		(placement
			(enabled no)
			(sheetname "")
		)
		(fill yes
			(thermal_gap 0.5)
			(thermal_bridge_width 0.5)
			(island_removal_mode 0)
		)
		(polygon
			(pts
				(arc
					(start 30.02153 -280.821384)
					(mid 30.036409 -280.857305)
					(end 30.07233 -280.872184)
				)
				(arc
					(start 31.47187 -280.872184)
					(mid 31.507791 -280.857305)
					(end 31.52267 -280.821384)
				)
				(arc
					(start 31.52267 -280.412444)
					(mid 31.507791 -280.376523)
					(end 31.47187 -280.361644)
				)
				(arc
					(start 30.07233 -280.361644)
					(mid 30.036409 -280.376523)
					(end 30.02153 -280.412444)
				)
			)
		)
	)
	(zone
		(layers "In1.Cu" "In2.Cu")
		(hatch none 0.5)
		(connect_pads
			(clearance 0)
		)
		(min_thickness 0.25)
		(keepout
			(tracks not_allowed)
			(vias allowed)
			(pads allowed)
			(copperpour not_allowed)
			(footprints allowed)
		)
		(placement
			(enabled no)
			(sheetname "")
		)
		(fill yes
			(thermal_gap 0.5)
			(thermal_bridge_width 0.5)
			(island_removal_mode 0)
		)
		(polygon
			(pts
				(arc
					(start 188.23813 -312.27141)
					(mid 188.253009 -312.307331)
					(end 188.28893 -312.32221)
				)
				(arc
					(start 189.68847 -312.32221)
					(mid 189.724391 -312.307331)
					(end 189.73927 -312.27141)
				)
				(arc
					(start 189.73927 -311.86247)
					(mid 189.724391 -311.826549)
					(end 189.68847 -311.81167)
				)
				(arc
					(start 188.28893 -311.81167)
					(mid 188.253009 -311.826549)
					(end 188.23813 -311.86247)
				)
			)
		)
	)
	(zone
		(layers "In1.Cu" "In2.Cu")
		(hatch none 0.5)
		(connect_pads
			(clearance 0)
		)
		(min_thickness 0.25)
		(keepout
			(tracks not_allowed)
			(vias allowed)
			(pads allowed)
			(copperpour not_allowed)
			(footprints allowed)
		)
		(placement
			(enabled no)
			(sheetname "")
		)
		(fill yes
			(thermal_gap 0.5)
			(thermal_bridge_width 0.5)
			(island_removal_mode 0)
		)
		(polygon
			(pts
				(arc
					(start 282.061666 -225.571304)
					(mid 282.076545 -225.607225)
					(end 282.112466 -225.622104)
				)
				(arc
					(start 283.512006 -225.622104)
					(mid 283.547927 -225.607225)
					(end 283.562806 -225.571304)
				)
				(arc
					(start 283.562806 -225.162364)
					(mid 283.547927 -225.126443)
					(end 283.512006 -225.111564)
				)
				(arc
					(start 282.112466 -225.111564)
					(mid 282.076545 -225.126443)
					(end 282.061666 -225.162364)
				)
			)
		)
	)
	(zone
		(layers "In1.Cu" "In2.Cu")
		(hatch none 0.5)
		(connect_pads
			(clearance 0)
		)
		(min_thickness 0.25)
		(keepout
			(tracks not_allowed)
			(vias allowed)
			(pads allowed)
			(copperpour not_allowed)
			(footprints allowed)
		)
		(placement
			(enabled no)
			(sheetname "")
		)
		(fill yes
			(thermal_gap 0.5)
			(thermal_bridge_width 0.5)
			(island_removal_mode 0)
		)
		(polygon
			(pts
				(arc
					(start 285.505398 -196.671438)
					(mid 285.520277 -196.707359)
					(end 285.556198 -196.722238)
				)
				(arc
					(start 286.955738 -196.722238)
					(mid 286.991659 -196.707359)
					(end 287.006538 -196.671438)
				)
				(arc
					(start 287.006538 -196.262498)
					(mid 286.991659 -196.226577)
					(end 286.955738 -196.211698)
				)
				(arc
					(start 285.556198 -196.211698)
					(mid 285.520277 -196.226577)
					(end 285.505398 -196.262498)
				)
			)
		)
	)
	(zone
		(layers "In1.Cu" "In2.Cu")
		(hatch none 0.5)
		(connect_pads
			(clearance 0)
		)
		(min_thickness 0.25)
		(keepout
			(tracks not_allowed)
			(vias allowed)
			(pads allowed)
			(copperpour not_allowed)
			(footprints allowed)
		)
		(placement
			(enabled no)
			(sheetname "")
		)
		(fill yes
			(thermal_gap 0.5)
			(thermal_bridge_width 0.5)
			(island_removal_mode 0)
		)
		(polygon
			(pts
				(arc
					(start 304.693066 -200.071482)
					(mid 304.707945 -200.107403)
					(end 304.743866 -200.122282)
				)
				(arc
					(start 306.143406 -200.122282)
					(mid 306.179327 -200.107403)
					(end 306.194206 -200.071482)
				)
				(arc
					(start 306.194206 -199.662542)
					(mid 306.179327 -199.626621)
					(end 306.143406 -199.611742)
				)
				(arc
					(start 304.743866 -199.611742)
					(mid 304.707945 -199.626621)
					(end 304.693066 -199.662542)
				)
			)
		)
	)
	(zone
		(layers "In1.Cu" "In2.Cu")
		(hatch none 0.5)
		(connect_pads
			(clearance 0)
		)
		(min_thickness 0.25)
		(keepout
			(tracks not_allowed)
			(vias allowed)
			(pads allowed)
			(copperpour not_allowed)
			(footprints allowed)
		)
		(placement
			(enabled no)
			(sheetname "")
		)
		(fill yes
			(thermal_gap 0.5)
			(thermal_bridge_width 0.5)
			(island_removal_mode 0)
		)
		(polygon
			(pts
				(arc
					(start 37.56533 -235.771436)
					(mid 37.580209 -235.807357)
					(end 37.61613 -235.822236)
				)
				(arc
					(start 39.01567 -235.822236)
					(mid 39.051591 -235.807357)
					(end 39.06647 -235.771436)
				)
				(arc
					(start 39.06647 -235.362496)
					(mid 39.051591 -235.326575)
					(end 39.01567 -235.311696)
				)
				(arc
					(start 37.61613 -235.311696)
					(mid 37.580209 -235.326575)
					(end 37.56533 -235.362496)
				)
			)
		)
	)
	(zone
		(layers "In1.Cu" "In2.Cu")
		(hatch none 0.5)
		(connect_pads
			(clearance 0)
		)
		(min_thickness 0.25)
		(keepout
			(tracks not_allowed)
			(vias allowed)
			(pads allowed)
			(copperpour not_allowed)
			(footprints allowed)
		)
		(placement
			(enabled no)
			(sheetname "")
		)
		(fill yes
			(thermal_gap 0.5)
			(thermal_bridge_width 0.5)
			(island_removal_mode 0)
		)
		(polygon
			(pts
				(arc
					(start 37.56533 -269.771368)
					(mid 37.580209 -269.807289)
					(end 37.61613 -269.822168)
				)
				(arc
					(start 39.01567 -269.822168)
					(mid 39.051591 -269.807289)
					(end 39.06647 -269.771368)
				)
				(arc
					(start 39.06647 -269.362428)
					(mid 39.051591 -269.326507)
					(end 39.01567 -269.311628)
				)
				(arc
					(start 37.61613 -269.311628)
					(mid 37.580209 -269.326507)
					(end 37.56533 -269.362428)
				)
			)
		)
	)
	(zone
		(layers "In1.Cu" "In2.Cu")
		(hatch none 0.5)
		(connect_pads
			(clearance 0)
		)
		(min_thickness 0.25)
		(keepout
			(tracks not_allowed)
			(vias allowed)
			(pads allowed)
			(copperpour not_allowed)
			(footprints allowed)
		)
		(placement
			(enabled no)
			(sheetname "")
		)
		(fill yes
			(thermal_gap 0.5)
			(thermal_bridge_width 0.5)
			(island_removal_mode 0)
		)
		(polygon
			(pts
				(arc
					(start 56.752998 -293.571422)
					(mid 56.767877 -293.607343)
					(end 56.803798 -293.622222)
				)
				(arc
					(start 58.203338 -293.622222)
					(mid 58.239259 -293.607343)
					(end 58.254138 -293.571422)
				)
				(arc
					(start 58.254138 -293.162482)
					(mid 58.239259 -293.126561)
					(end 58.203338 -293.111682)
				)
				(arc
					(start 56.803798 -293.111682)
					(mid 56.767877 -293.126561)
					(end 56.752998 -293.162482)
				)
			)
		)
	)
	(zone
		(layers "In1.Cu" "In2.Cu")
		(hatch none 0.5)
		(connect_pads
			(clearance 0)
		)
		(min_thickness 0.25)
		(keepout
			(tracks not_allowed)
			(vias allowed)
			(pads allowed)
			(copperpour not_allowed)
			(footprints allowed)
		)
		(placement
			(enabled no)
			(sheetname "")
		)
		(fill yes
			(thermal_gap 0.5)
			(thermal_bridge_width 0.5)
			(island_removal_mode 0)
		)
		(polygon
			(pts
				(arc
					(start 436.178198 -234.071414)
					(mid 436.193077 -234.107335)
					(end 436.228998 -234.122214)
				)
				(arc
					(start 437.628538 -234.122214)
					(mid 437.664459 -234.107335)
					(end 437.679338 -234.071414)
				)
				(arc
					(start 437.679338 -233.662474)
					(mid 437.664459 -233.626553)
					(end 437.628538 -233.611674)
				)
				(arc
					(start 436.228998 -233.611674)
					(mid 436.193077 -233.626553)
					(end 436.178198 -233.662474)
				)
			)
		)
	)
	(zone
		(layers "In1.Cu" "In2.Cu")
		(hatch none 0.5)
		(connect_pads
			(clearance 0)
		)
		(min_thickness 0.25)
		(keepout
			(tracks not_allowed)
			(vias allowed)
			(pads allowed)
			(copperpour not_allowed)
			(footprints allowed)
		)
		(placement
			(enabled no)
			(sheetname "")
		)
		(fill yes
			(thermal_gap 0.5)
			(thermal_bridge_width 0.5)
			(island_removal_mode 0)
		)
		(polygon
			(pts
				(arc
					(start 312.236866 -274.02155)
					(mid 312.251745 -274.057471)
					(end 312.287666 -274.07235)
				)
				(arc
					(start 313.687206 -274.07235)
					(mid 313.723127 -274.057471)
					(end 313.738006 -274.02155)
				)
				(arc
					(start 313.738006 -273.61261)
					(mid 313.723127 -273.576689)
					(end 313.687206 -273.56181)
				)
				(arc
					(start 312.287666 -273.56181)
					(mid 312.251745 -273.576689)
					(end 312.236866 -273.61261)
				)
			)
		)
	)
	(zone
		(layers "In1.Cu" "In2.Cu")
		(hatch none 0.5)
		(connect_pads
			(clearance 0)
		)
		(min_thickness 0.25)
		(keepout
			(tracks not_allowed)
			(vias allowed)
			(pads allowed)
			(copperpour not_allowed)
			(footprints allowed)
		)
		(placement
			(enabled no)
			(sheetname "")
		)
		(fill yes
			(thermal_gap 0.5)
			(thermal_bridge_width 0.5)
			(island_removal_mode 0)
		)
		(polygon
			(pts
				(arc
					(start 165.60673 -290.171378)
					(mid 165.621609 -290.207299)
					(end 165.65753 -290.222178)
				)
				(arc
					(start 167.05707 -290.222178)
					(mid 167.092991 -290.207299)
					(end 167.10787 -290.171378)
				)
				(arc
					(start 167.10787 -289.762438)
					(mid 167.092991 -289.726517)
					(end 167.05707 -289.711638)
				)
				(arc
					(start 165.65753 -289.711638)
					(mid 165.621609 -289.726517)
					(end 165.60673 -289.762438)
				)
			)
		)
	)
	(zone
		(layers "In1.Cu" "In2.Cu")
		(hatch none 0.5)
		(connect_pads
			(clearance 0)
		)
		(min_thickness 0.25)
		(keepout
			(tracks not_allowed)
			(vias allowed)
			(pads allowed)
			(copperpour not_allowed)
			(footprints allowed)
		)
		(placement
			(enabled no)
			(sheetname "")
		)
		(fill yes
			(thermal_gap 0.5)
			(thermal_bridge_width 0.5)
			(island_removal_mode 0)
		)
		(polygon
			(pts
				(arc
					(start 255.330198 -316.521338)
					(mid 255.345077 -316.557259)
					(end 255.380998 -316.572138)
				)
				(arc
					(start 256.780538 -316.572138)
					(mid 256.816459 -316.557259)
					(end 256.831338 -316.521338)
				)
				(arc
					(start 256.831338 -316.112398)
					(mid 256.816459 -316.076477)
					(end 256.780538 -316.061598)
				)
				(arc
					(start 255.380998 -316.061598)
					(mid 255.345077 -316.076477)
					(end 255.330198 -316.112398)
				)
			)
		)
	)
	(zone
		(layers "In1.Cu" "In2.Cu")
		(hatch none 0.5)
		(connect_pads
			(clearance 0)
		)
		(min_thickness 0.25)
		(keepout
			(tracks not_allowed)
			(vias allowed)
			(pads allowed)
			(copperpour not_allowed)
			(footprints allowed)
		)
		(placement
			(enabled no)
			(sheetname "")
		)
		(fill yes
			(thermal_gap 0.5)
			(thermal_bridge_width 0.5)
			(island_removal_mode 0)
		)
		(polygon
			(pts
				(arc
					(start 60.19673 -213.671404)
					(mid 60.211609 -213.707325)
					(end 60.24753 -213.722204)
				)
				(arc
					(start 61.64707 -213.722204)
					(mid 61.682991 -213.707325)
					(end 61.69787 -213.671404)
				)
				(arc
					(start 61.69787 -213.262464)
					(mid 61.682991 -213.226543)
					(end 61.64707 -213.211664)
				)
				(arc
					(start 60.24753 -213.211664)
					(mid 60.211609 -213.226543)
					(end 60.19673 -213.262464)
				)
			)
		)
	)
	(zone
		(layers "In1.Cu" "In2.Cu")
		(hatch none 0.5)
		(connect_pads
			(clearance 0)
		)
		(min_thickness 0.25)
		(keepout
			(tracks not_allowed)
			(vias allowed)
			(pads allowed)
			(copperpour not_allowed)
			(footprints allowed)
		)
		(placement
			(enabled no)
			(sheetname "")
		)
		(fill yes
			(thermal_gap 0.5)
			(thermal_bridge_width 0.5)
			(island_removal_mode 0)
		)
		(polygon
			(pts
				(arc
					(start 458.809598 -218.77147)
					(mid 458.824477 -218.807391)
					(end 458.860398 -218.82227)
				)
				(arc
					(start 460.259938 -218.82227)
					(mid 460.295859 -218.807391)
					(end 460.310738 -218.77147)
				)
				(arc
					(start 460.310738 -218.36253)
					(mid 460.295859 -218.326609)
					(end 460.259938 -218.31173)
				)
				(arc
					(start 458.860398 -218.31173)
					(mid 458.824477 -218.326609)
					(end 458.809598 -218.36253)
				)
			)
		)
	)
	(zone
		(layers "In1.Cu" "In2.Cu")
		(hatch none 0.5)
		(connect_pads
			(clearance 0)
		)
		(min_thickness 0.25)
		(keepout
			(tracks not_allowed)
			(vias allowed)
			(pads allowed)
			(copperpour not_allowed)
			(footprints allowed)
		)
		(placement
			(enabled no)
			(sheetname "")
		)
		(fill yes
			(thermal_gap 0.5)
			(thermal_bridge_width 0.5)
			(island_removal_mode 0)
		)
		(polygon
			(pts
				(arc
					(start 60.19673 -221.321376)
					(mid 60.211609 -221.357297)
					(end 60.24753 -221.372176)
				)
				(arc
					(start 61.64707 -221.372176)
					(mid 61.682991 -221.357297)
					(end 61.69787 -221.321376)
				)
				(arc
					(start 61.69787 -220.912436)
					(mid 61.682991 -220.876515)
					(end 61.64707 -220.861636)
				)
				(arc
					(start 60.24753 -220.861636)
					(mid 60.211609 -220.876515)
					(end 60.19673 -220.912436)
				)
			)
		)
	)
	(zone
		(layers "In1.Cu" "In2.Cu")
		(hatch none 0.5)
		(connect_pads
			(clearance 0)
		)
		(min_thickness 0.25)
		(keepout
			(tracks not_allowed)
			(vias allowed)
			(pads allowed)
			(copperpour not_allowed)
			(footprints allowed)
		)
		(placement
			(enabled no)
			(sheetname "")
		)
		(fill yes
			(thermal_gap 0.5)
			(thermal_bridge_width 0.5)
			(island_removal_mode 0)
		)
		(polygon
			(pts
				(arc
					(start 262.873998 -237.471458)
					(mid 262.888877 -237.507379)
					(end 262.924798 -237.522258)
				)
				(arc
					(start 264.324338 -237.522258)
					(mid 264.360259 -237.507379)
					(end 264.375138 -237.471458)
				)
				(arc
					(start 264.375138 -237.062518)
					(mid 264.360259 -237.026597)
					(end 264.324338 -237.011718)
				)
				(arc
					(start 262.924798 -237.011718)
					(mid 262.888877 -237.026597)
					(end 262.873998 -237.062518)
				)
			)
		)
	)
	(zone
		(layers "In1.Cu" "In2.Cu")
		(hatch none 0.5)
		(connect_pads
			(clearance 0)
		)
		(min_thickness 0.25)
		(keepout
			(tracks not_allowed)
			(vias allowed)
			(pads allowed)
			(copperpour not_allowed)
			(footprints allowed)
		)
		(placement
			(enabled no)
			(sheetname "")
		)
		(fill yes
			(thermal_gap 0.5)
			(thermal_bridge_width 0.5)
			(island_removal_mode 0)
		)
		(polygon
			(pts
				(arc
					(start 37.56533 -209.421476)
					(mid 37.580209 -209.457397)
					(end 37.61613 -209.472276)
				)
				(arc
					(start 39.01567 -209.472276)
					(mid 39.051591 -209.457397)
					(end 39.06647 -209.421476)
				)
				(arc
					(start 39.06647 -209.012536)
					(mid 39.051591 -208.976615)
					(end 39.01567 -208.961736)
				)
				(arc
					(start 37.61613 -208.961736)
					(mid 37.580209 -208.976615)
					(end 37.56533 -209.012536)
				)
			)
		)
	)
	(zone
		(layers "In1.Cu" "In2.Cu")
		(hatch none 0.5)
		(connect_pads
			(clearance 0)
		)
		(min_thickness 0.25)
		(keepout
			(tracks not_allowed)
			(vias allowed)
			(pads allowed)
			(copperpour not_allowed)
			(footprints allowed)
		)
		(placement
			(enabled no)
			(sheetname "")
		)
		(fill yes
			(thermal_gap 0.5)
			(thermal_bridge_width 0.5)
			(island_removal_mode 0)
		)
		(polygon
			(pts
				(arc
					(start 458.809598 -313.121294)
					(mid 458.824477 -313.157215)
					(end 458.860398 -313.172094)
				)
				(arc
					(start 460.259938 -313.172094)
					(mid 460.295859 -313.157215)
					(end 460.310738 -313.121294)
				)
				(arc
					(start 460.310738 -312.712354)
					(mid 460.295859 -312.676433)
					(end 460.259938 -312.661554)
				)
				(arc
					(start 458.860398 -312.661554)
					(mid 458.824477 -312.676433)
					(end 458.809598 -312.712354)
				)
			)
		)
	)
	(zone
		(layers "In1.Cu" "In2.Cu")
		(hatch none 0.5)
		(connect_pads
			(clearance 0)
		)
		(min_thickness 0.25)
		(keepout
			(tracks not_allowed)
			(vias allowed)
			(pads allowed)
			(copperpour not_allowed)
			(footprints allowed)
		)
		(placement
			(enabled no)
			(sheetname "")
		)
		(fill yes
			(thermal_gap 0.5)
			(thermal_bridge_width 0.5)
			(island_removal_mode 0)
		)
		(polygon
			(pts
				(arc
					(start 45.10913 -198.37146)
					(mid 45.124009 -198.407381)
					(end 45.15993 -198.42226)
				)
				(arc
					(start 46.55947 -198.42226)
					(mid 46.595391 -198.407381)
					(end 46.61027 -198.37146)
				)
				(arc
					(start 46.61027 -197.96252)
					(mid 46.595391 -197.926599)
					(end 46.55947 -197.91172)
				)
				(arc
					(start 45.15993 -197.91172)
					(mid 45.124009 -197.926599)
					(end 45.10913 -197.96252)
				)
			)
		)
	)
	(zone
		(layers "In1.Cu" "In2.Cu")
		(hatch none 0.5)
		(connect_pads
			(clearance 0)
		)
		(min_thickness 0.25)
		(keepout
			(tracks not_allowed)
			(vias allowed)
			(pads allowed)
			(copperpour not_allowed)
			(footprints allowed)
		)
		(placement
			(enabled no)
			(sheetname "")
		)
		(fill yes
			(thermal_gap 0.5)
			(thermal_bridge_width 0.5)
			(island_removal_mode 0)
		)
		(polygon
			(pts
				(arc
					(start 214.969598 -283.371544)
					(mid 214.984477 -283.407465)
					(end 215.020398 -283.422344)
				)
				(arc
					(start 216.419938 -283.422344)
					(mid 216.455859 -283.407465)
					(end 216.470738 -283.371544)
				)
				(arc
					(start 216.470738 -282.962604)
					(mid 216.455859 -282.926683)
					(end 216.419938 -282.911804)
				)
				(arc
					(start 215.020398 -282.911804)
					(mid 214.984477 -282.926683)
					(end 214.969598 -282.962604)
				)
			)
		)
	)
	(zone
		(layers "In1.Cu" "In2.Cu")
		(hatch none 0.5)
		(connect_pads
			(clearance 0)
		)
		(min_thickness 0.25)
		(keepout
			(tracks not_allowed)
			(vias allowed)
			(pads allowed)
			(copperpour not_allowed)
			(footprints allowed)
		)
		(placement
			(enabled no)
			(sheetname "")
		)
		(fill yes
			(thermal_gap 0.5)
			(thermal_bridge_width 0.5)
			(island_removal_mode 0)
		)
		(polygon
			(pts
				(arc
					(start 458.809598 -245.971314)
					(mid 458.824477 -246.007235)
					(end 458.860398 -246.022114)
				)
				(arc
					(start 460.259938 -246.022114)
					(mid 460.295859 -246.007235)
					(end 460.310738 -245.971314)
				)
				(arc
					(start 460.310738 -245.562374)
					(mid 460.295859 -245.526453)
					(end 460.259938 -245.511574)
				)
				(arc
					(start 458.860398 -245.511574)
					(mid 458.824477 -245.526453)
					(end 458.809598 -245.562374)
				)
			)
		)
	)
	(zone
		(layers "In1.Cu" "In2.Cu")
		(hatch none 0.5)
		(connect_pads
			(clearance 0)
		)
		(min_thickness 0.25)
		(keepout
			(tracks not_allowed)
			(vias allowed)
			(pads allowed)
			(copperpour not_allowed)
			(footprints allowed)
		)
		(placement
			(enabled no)
			(sheetname "")
		)
		(fill yes
			(thermal_gap 0.5)
			(thermal_bridge_width 0.5)
			(island_removal_mode 0)
		)
		(polygon
			(pts
				(arc
					(start 440.278266 -240.871502)
					(mid 440.293145 -240.907423)
					(end 440.329066 -240.922302)
				)
				(arc
					(start 441.728606 -240.922302)
					(mid 441.764527 -240.907423)
					(end 441.779406 -240.871502)
				)
				(arc
					(start 441.779406 -240.462562)
					(mid 441.764527 -240.426641)
					(end 441.728606 -240.411762)
				)
				(arc
					(start 440.329066 -240.411762)
					(mid 440.293145 -240.426641)
					(end 440.278266 -240.462562)
				)
			)
		)
	)
	(zone
		(layers "In1.Cu" "In2.Cu")
		(hatch none 0.5)
		(connect_pads
			(clearance 0)
		)
		(min_thickness 0.25)
		(keepout
			(tracks not_allowed)
			(vias allowed)
			(pads allowed)
			(copperpour not_allowed)
			(footprints allowed)
		)
		(placement
			(enabled no)
			(sheetname "")
		)
		(fill yes
			(thermal_gap 0.5)
			(thermal_bridge_width 0.5)
			(island_removal_mode 0)
		)
		(polygon
			(pts
				(arc
					(start 158.06293 -241.721386)
					(mid 158.077809 -241.757307)
					(end 158.11373 -241.772186)
				)
				(arc
					(start 159.51327 -241.772186)
					(mid 159.549191 -241.757307)
					(end 159.56407 -241.721386)
				)
				(arc
					(start 159.56407 -241.312446)
					(mid 159.549191 -241.276525)
					(end 159.51327 -241.261646)
				)
				(arc
					(start 158.11373 -241.261646)
					(mid 158.077809 -241.276525)
					(end 158.06293 -241.312446)
				)
			)
		)
	)
	(zone
		(layers "In1.Cu" "In2.Cu")
		(hatch none 0.5)
		(connect_pads
			(clearance 0)
		)
		(min_thickness 0.25)
		(keepout
			(tracks not_allowed)
			(vias allowed)
			(pads allowed)
			(copperpour not_allowed)
			(footprints allowed)
		)
		(placement
			(enabled no)
			(sheetname "")
		)
		(fill yes
			(thermal_gap 0.5)
			(thermal_bridge_width 0.5)
			(island_removal_mode 0)
		)
		(polygon
			(pts
				(arc
					(start 413.546798 -266.371324)
					(mid 413.561677 -266.407245)
					(end 413.597598 -266.422124)
				)
				(arc
					(start 414.997138 -266.422124)
					(mid 415.033059 -266.407245)
					(end 415.047938 -266.371324)
				)
				(arc
					(start 415.047938 -265.962384)
					(mid 415.033059 -265.926463)
					(end 414.997138 -265.911584)
				)
				(arc
					(start 413.597598 -265.911584)
					(mid 413.561677 -265.926463)
					(end 413.546798 -265.962384)
				)
			)
		)
	)
	(zone
		(layers "In1.Cu" "In2.Cu")
		(hatch none 0.5)
		(connect_pads
			(clearance 0)
		)
		(min_thickness 0.25)
		(keepout
			(tracks not_allowed)
			(vias allowed)
			(pads allowed)
			(copperpour not_allowed)
			(footprints allowed)
		)
		(placement
			(enabled no)
			(sheetname "")
		)
		(fill yes
			(thermal_gap 0.5)
			(thermal_bridge_width 0.5)
			(island_removal_mode 0)
		)
		(polygon
			(pts
				(arc
					(start 60.19673 -284.221428)
					(mid 60.211609 -284.257349)
					(end 60.24753 -284.272228)
				)
				(arc
					(start 61.64707 -284.272228)
					(mid 61.682991 -284.257349)
					(end 61.69787 -284.221428)
				)
				(arc
					(start 61.69787 -283.812488)
					(mid 61.682991 -283.776567)
					(end 61.64707 -283.761688)
				)
				(arc
					(start 60.24753 -283.761688)
					(mid 60.211609 -283.776567)
					(end 60.19673 -283.812488)
				)
			)
		)
	)
	(zone
		(layers "In1.Cu" "In2.Cu")
		(hatch none 0.5)
		(connect_pads
			(clearance 0)
		)
		(min_thickness 0.25)
		(keepout
			(tracks not_allowed)
			(vias allowed)
			(pads allowed)
			(copperpour not_allowed)
			(footprints allowed)
		)
		(placement
			(enabled no)
			(sheetname "")
		)
		(fill yes
			(thermal_gap 0.5)
			(thermal_bridge_width 0.5)
			(island_removal_mode 0)
		)
		(polygon
			(pts
				(arc
					(start 165.60673 -211.971382)
					(mid 165.621609 -212.007303)
					(end 165.65753 -212.022182)
				)
				(arc
					(start 167.05707 -212.022182)
					(mid 167.092991 -212.007303)
					(end 167.10787 -211.971382)
				)
				(arc
					(start 167.10787 -211.562442)
					(mid 167.092991 -211.526521)
					(end 167.05707 -211.511642)
				)
				(arc
					(start 165.65753 -211.511642)
					(mid 165.621609 -211.526521)
					(end 165.60673 -211.562442)
				)
			)
		)
	)
	(zone
		(layers "In1.Cu" "In2.Cu")
		(hatch none 0.5)
		(connect_pads
			(clearance 0)
		)
		(min_thickness 0.25)
		(keepout
			(tracks not_allowed)
			(vias allowed)
			(pads allowed)
			(copperpour not_allowed)
			(footprints allowed)
		)
		(placement
			(enabled no)
			(sheetname "")
		)
		(fill yes
			(thermal_gap 0.5)
			(thermal_bridge_width 0.5)
			(island_removal_mode 0)
		)
		(polygon
			(pts
				(arc
					(start 207.425798 -201.771504)
					(mid 207.440677 -201.807425)
					(end 207.476598 -201.822304)
				)
				(arc
					(start 208.876138 -201.822304)
					(mid 208.912059 -201.807425)
					(end 208.926938 -201.771504)
				)
				(arc
					(start 208.926938 -201.362564)
					(mid 208.912059 -201.326643)
					(end 208.876138 -201.311764)
				)
				(arc
					(start 207.476598 -201.311764)
					(mid 207.440677 -201.326643)
					(end 207.425798 -201.362564)
				)
			)
		)
	)
	(zone
		(layers "In1.Cu" "In2.Cu")
		(hatch none 0.5)
		(connect_pads
			(clearance 0)
		)
		(min_thickness 0.25)
		(keepout
			(tracks not_allowed)
			(vias allowed)
			(pads allowed)
			(copperpour not_allowed)
			(footprints allowed)
		)
		(placement
			(enabled no)
			(sheetname "")
		)
		(fill yes
			(thermal_gap 0.5)
			(thermal_bridge_width 0.5)
			(island_removal_mode 0)
		)
		(polygon
			(pts
				(arc
					(start 277.961598 -206.021432)
					(mid 277.976477 -206.057353)
					(end 278.012398 -206.072232)
				)
				(arc
					(start 279.411938 -206.072232)
					(mid 279.447859 -206.057353)
					(end 279.462738 -206.021432)
				)
				(arc
					(start 279.462738 -205.612492)
					(mid 279.447859 -205.576571)
					(end 279.411938 -205.561692)
				)
				(arc
					(start 278.012398 -205.561692)
					(mid 277.976477 -205.576571)
					(end 277.961598 -205.612492)
				)
			)
		)
	)
	(zone
		(layers "In1.Cu" "In2.Cu")
		(hatch none 0.5)
		(connect_pads
			(clearance 0)
		)
		(min_thickness 0.25)
		(keepout
			(tracks not_allowed)
			(vias allowed)
			(pads allowed)
			(copperpour not_allowed)
			(footprints allowed)
		)
		(placement
			(enabled no)
			(sheetname "")
		)
		(fill yes
			(thermal_gap 0.5)
			(thermal_bridge_width 0.5)
			(island_removal_mode 0)
		)
		(polygon
			(pts
				(arc
					(start 282.061666 -214.521542)
					(mid 282.076545 -214.557463)
					(end 282.112466 -214.572342)
				)
				(arc
					(start 283.512006 -214.572342)
					(mid 283.547927 -214.557463)
					(end 283.562806 -214.521542)
				)
				(arc
					(start 283.562806 -214.112602)
					(mid 283.547927 -214.076681)
					(end 283.512006 -214.061802)
				)
				(arc
					(start 282.112466 -214.061802)
					(mid 282.076545 -214.076681)
					(end 282.061666 -214.112602)
				)
			)
		)
	)
	(zone
		(layers "In1.Cu" "In2.Cu")
		(hatch none 0.5)
		(connect_pads
			(clearance 0)
		)
		(min_thickness 0.25)
		(keepout
			(tracks not_allowed)
			(vias allowed)
			(pads allowed)
			(copperpour not_allowed)
			(footprints allowed)
		)
		(placement
			(enabled no)
			(sheetname "")
		)
		(fill yes
			(thermal_gap 0.5)
			(thermal_bridge_width 0.5)
			(island_removal_mode 0)
		)
		(polygon
			(pts
				(arc
					(start 64.296798 -216.22131)
					(mid 64.311677 -216.257231)
					(end 64.347598 -216.27211)
				)
				(arc
					(start 65.747138 -216.27211)
					(mid 65.783059 -216.257231)
					(end 65.797938 -216.22131)
				)
				(arc
					(start 65.797938 -215.81237)
					(mid 65.783059 -215.776449)
					(end 65.747138 -215.76157)
				)
				(arc
					(start 64.347598 -215.76157)
					(mid 64.311677 -215.776449)
					(end 64.296798 -215.81237)
				)
			)
		)
	)
	(zone
		(layers "In1.Cu" "In2.Cu")
		(hatch none 0.5)
		(connect_pads
			(clearance 0)
		)
		(min_thickness 0.25)
		(keepout
			(tracks not_allowed)
			(vias allowed)
			(pads allowed)
			(copperpour not_allowed)
			(footprints allowed)
		)
		(placement
			(enabled no)
			(sheetname "")
		)
		(fill yes
			(thermal_gap 0.5)
			(thermal_bridge_width 0.5)
			(island_removal_mode 0)
		)
		(polygon
			(pts
				(arc
					(start 177.250598 -214.521542)
					(mid 177.265477 -214.557463)
					(end 177.301398 -214.572342)
				)
				(arc
					(start 178.700938 -214.572342)
					(mid 178.736859 -214.557463)
					(end 178.751738 -214.521542)
				)
				(arc
					(start 178.751738 -214.112602)
					(mid 178.736859 -214.076681)
					(end 178.700938 -214.061802)
				)
				(arc
					(start 177.301398 -214.061802)
					(mid 177.265477 -214.076681)
					(end 177.250598 -214.112602)
				)
			)
		)
	)
	(zone
		(layers "In1.Cu" "In2.Cu")
		(hatch none 0.5)
		(connect_pads
			(clearance 0)
		)
		(min_thickness 0.25)
		(keepout
			(tracks not_allowed)
			(vias allowed)
			(pads allowed)
			(copperpour not_allowed)
			(footprints allowed)
		)
		(placement
			(enabled no)
			(sheetname "")
		)
		(fill yes
			(thermal_gap 0.5)
			(thermal_bridge_width 0.5)
			(island_removal_mode 0)
		)
		(polygon
			(pts
				(arc
					(start 289.605466 -308.021482)
					(mid 289.620345 -308.057403)
					(end 289.656266 -308.072282)
				)
				(arc
					(start 291.055806 -308.072282)
					(mid 291.091727 -308.057403)
					(end 291.106606 -308.021482)
				)
				(arc
					(start 291.106606 -307.612542)
					(mid 291.091727 -307.576621)
					(end 291.055806 -307.561742)
				)
				(arc
					(start 289.656266 -307.561742)
					(mid 289.620345 -307.576621)
					(end 289.605466 -307.612542)
				)
			)
		)
	)
	(zone
		(layers "In1.Cu" "In2.Cu")
		(hatch none 0.5)
		(connect_pads
			(clearance 0)
		)
		(min_thickness 0.25)
		(keepout
			(tracks not_allowed)
			(vias allowed)
			(pads allowed)
			(copperpour not_allowed)
			(footprints allowed)
		)
		(placement
			(enabled no)
			(sheetname "")
		)
		(fill yes
			(thermal_gap 0.5)
			(thermal_bridge_width 0.5)
			(island_removal_mode 0)
		)
		(polygon
			(pts
				(arc
					(start 255.330198 -200.921366)
					(mid 255.345077 -200.957287)
					(end 255.380998 -200.972166)
				)
				(arc
					(start 256.780538 -200.972166)
					(mid 256.816459 -200.957287)
					(end 256.831338 -200.921366)
				)
				(arc
					(start 256.831338 -200.512426)
					(mid 256.816459 -200.476505)
					(end 256.780538 -200.461626)
				)
				(arc
					(start 255.380998 -200.461626)
					(mid 255.345077 -200.476505)
					(end 255.330198 -200.512426)
				)
			)
		)
	)
	(zone
		(layers "In1.Cu" "In2.Cu")
		(hatch none 0.5)
		(connect_pads
			(clearance 0)
		)
		(min_thickness 0.25)
		(keepout
			(tracks not_allowed)
			(vias allowed)
			(pads allowed)
			(copperpour not_allowed)
			(footprints allowed)
		)
		(placement
			(enabled no)
			(sheetname "")
		)
		(fill yes
			(thermal_gap 0.5)
			(thermal_bridge_width 0.5)
			(island_removal_mode 0)
		)
		(polygon
			(pts
				(arc
					(start 26.577798 -278.271478)
					(mid 26.592677 -278.307399)
					(end 26.628598 -278.322278)
				)
				(arc
					(start 28.028138 -278.322278)
					(mid 28.064059 -278.307399)
					(end 28.078938 -278.271478)
				)
				(arc
					(start 28.078938 -277.862538)
					(mid 28.064059 -277.826617)
					(end 28.028138 -277.811738)
				)
				(arc
					(start 26.628598 -277.811738)
					(mid 26.592677 -277.826617)
					(end 26.577798 -277.862538)
				)
			)
		)
	)
	(zone
		(layers "In1.Cu" "In2.Cu")
		(hatch none 0.5)
		(connect_pads
			(clearance 0)
		)
		(min_thickness 0.25)
		(keepout
			(tracks not_allowed)
			(vias allowed)
			(pads allowed)
			(copperpour not_allowed)
			(footprints allowed)
		)
		(placement
			(enabled no)
			(sheetname "")
		)
		(fill yes
			(thermal_gap 0.5)
			(thermal_bridge_width 0.5)
			(island_removal_mode 0)
		)
		(polygon
			(pts
				(arc
					(start 447.822066 -228.121464)
					(mid 447.836945 -228.157385)
					(end 447.872866 -228.172264)
				)
				(arc
					(start 449.272406 -228.172264)
					(mid 449.308327 -228.157385)
					(end 449.323206 -228.121464)
				)
				(arc
					(start 449.323206 -227.712524)
					(mid 449.308327 -227.676603)
					(end 449.272406 -227.661724)
				)
				(arc
					(start 447.872866 -227.661724)
					(mid 447.836945 -227.676603)
					(end 447.822066 -227.712524)
				)
			)
		)
	)
	(zone
		(layers "In1.Cu" "In2.Cu")
		(hatch none 0.5)
		(connect_pads
			(clearance 0)
		)
		(min_thickness 0.25)
		(keepout
			(tracks not_allowed)
			(vias allowed)
			(pads allowed)
			(copperpour not_allowed)
			(footprints allowed)
		)
		(placement
			(enabled no)
			(sheetname "")
		)
		(fill yes
			(thermal_gap 0.5)
			(thermal_bridge_width 0.5)
			(island_removal_mode 0)
		)
		(polygon
			(pts
				(arc
					(start 289.605466 -220.471492)
					(mid 289.620345 -220.507413)
					(end 289.656266 -220.522292)
				)
				(arc
					(start 291.055806 -220.522292)
					(mid 291.091727 -220.507413)
					(end 291.106606 -220.471492)
				)
				(arc
					(start 291.106606 -220.062552)
					(mid 291.091727 -220.026631)
					(end 291.055806 -220.011752)
				)
				(arc
					(start 289.656266 -220.011752)
					(mid 289.620345 -220.026631)
					(end 289.605466 -220.062552)
				)
			)
		)
	)
	(zone
		(layers "In1.Cu" "In2.Cu")
		(hatch none 0.5)
		(connect_pads
			(clearance 0)
		)
		(min_thickness 0.25)
		(keepout
			(tracks not_allowed)
			(vias allowed)
			(pads allowed)
			(copperpour not_allowed)
			(footprints allowed)
		)
		(placement
			(enabled no)
			(sheetname "")
		)
		(fill yes
			(thermal_gap 0.5)
			(thermal_bridge_width 0.5)
			(island_removal_mode 0)
		)
		(polygon
			(pts
				(arc
					(start 195.78193 -202.621388)
					(mid 195.796809 -202.657309)
					(end 195.83273 -202.672188)
				)
				(arc
					(start 197.23227 -202.672188)
					(mid 197.268191 -202.657309)
					(end 197.28307 -202.621388)
				)
				(arc
					(start 197.28307 -202.212448)
					(mid 197.268191 -202.176527)
					(end 197.23227 -202.161648)
				)
				(arc
					(start 195.83273 -202.161648)
					(mid 195.796809 -202.176527)
					(end 195.78193 -202.212448)
				)
			)
		)
	)
	(zone
		(layers "In1.Cu" "In2.Cu")
		(hatch none 0.5)
		(connect_pads
			(clearance 0)
		)
		(min_thickness 0.25)
		(keepout
			(tracks not_allowed)
			(vias allowed)
			(pads allowed)
			(copperpour not_allowed)
			(footprints allowed)
		)
		(placement
			(enabled no)
			(sheetname "")
		)
		(fill yes
			(thermal_gap 0.5)
			(thermal_bridge_width 0.5)
			(island_removal_mode 0)
		)
		(polygon
			(pts
				(arc
					(start 188.23813 -207.721454)
					(mid 188.253009 -207.757375)
					(end 188.28893 -207.772254)
				)
				(arc
					(start 189.68847 -207.772254)
					(mid 189.724391 -207.757375)
					(end 189.73927 -207.721454)
				)
				(arc
					(start 189.73927 -207.312514)
					(mid 189.724391 -207.276593)
					(end 189.68847 -207.261714)
				)
				(arc
					(start 188.28893 -207.261714)
					(mid 188.253009 -207.276593)
					(end 188.23813 -207.312514)
				)
			)
		)
	)
	(zone
		(layers "In1.Cu" "In2.Cu")
		(hatch none 0.5)
		(connect_pads
			(clearance 0)
		)
		(min_thickness 0.25)
		(keepout
			(tracks not_allowed)
			(vias allowed)
			(pads allowed)
			(copperpour not_allowed)
			(footprints allowed)
		)
		(placement
			(enabled no)
			(sheetname "")
		)
		(fill yes
			(thermal_gap 0.5)
			(thermal_bridge_width 0.5)
			(island_removal_mode 0)
		)
		(polygon
			(pts
				(arc
					(start 447.822066 -274.871434)
					(mid 447.836945 -274.907355)
					(end 447.872866 -274.922234)
				)
				(arc
					(start 449.272406 -274.922234)
					(mid 449.308327 -274.907355)
					(end 449.323206 -274.871434)
				)
				(arc
					(start 449.323206 -274.462494)
					(mid 449.308327 -274.426573)
					(end 449.272406 -274.411694)
				)
				(arc
					(start 447.872866 -274.411694)
					(mid 447.836945 -274.426573)
					(end 447.822066 -274.462494)
				)
			)
		)
	)
	(zone
		(layers "In1.Cu" "In2.Cu")
		(hatch none 0.5)
		(connect_pads
			(clearance 0)
		)
		(min_thickness 0.25)
		(keepout
			(tracks not_allowed)
			(vias allowed)
			(pads allowed)
			(copperpour not_allowed)
			(footprints allowed)
		)
		(placement
			(enabled no)
			(sheetname "")
		)
		(fill yes
			(thermal_gap 0.5)
			(thermal_bridge_width 0.5)
			(island_removal_mode 0)
		)
		(polygon
			(pts
				(arc
					(start 425.190666 -214.521542)
					(mid 425.205545 -214.557463)
					(end 425.241466 -214.572342)
				)
				(arc
					(start 426.641006 -214.572342)
					(mid 426.676927 -214.557463)
					(end 426.691806 -214.521542)
				)
				(arc
					(start 426.691806 -214.112602)
					(mid 426.676927 -214.076681)
					(end 426.641006 -214.061802)
				)
				(arc
					(start 425.241466 -214.061802)
					(mid 425.205545 -214.076681)
					(end 425.190666 -214.112602)
				)
			)
		)
	)
	(zone
		(layers "In1.Cu" "In2.Cu")
		(hatch none 0.5)
		(connect_pads
			(clearance 0)
		)
		(min_thickness 0.25)
		(keepout
			(tracks not_allowed)
			(vias allowed)
			(pads allowed)
			(copperpour not_allowed)
			(footprints allowed)
		)
		(placement
			(enabled no)
			(sheetname "")
		)
		(fill yes
			(thermal_gap 0.5)
			(thermal_bridge_width 0.5)
			(island_removal_mode 0)
		)
		(polygon
			(pts
				(arc
					(start 421.090598 -299.521372)
					(mid 421.105477 -299.557293)
					(end 421.141398 -299.572172)
				)
				(arc
					(start 422.540938 -299.572172)
					(mid 422.576859 -299.557293)
					(end 422.591738 -299.521372)
				)
				(arc
					(start 422.591738 -299.112432)
					(mid 422.576859 -299.076511)
					(end 422.540938 -299.061632)
				)
				(arc
					(start 421.141398 -299.061632)
					(mid 421.105477 -299.076511)
					(end 421.090598 -299.112432)
				)
			)
		)
	)
	(zone
		(layers "In1.Cu" "In2.Cu")
		(hatch none 0.5)
		(connect_pads
			(clearance 0)
		)
		(min_thickness 0.25)
		(keepout
			(tracks not_allowed)
			(vias allowed)
			(pads allowed)
			(copperpour not_allowed)
			(footprints allowed)
		)
		(placement
			(enabled no)
			(sheetname "")
		)
		(fill yes
			(thermal_gap 0.5)
			(thermal_bridge_width 0.5)
			(island_removal_mode 0)
		)
		(polygon
			(pts
				(arc
					(start 285.505398 -310.571388)
					(mid 285.520277 -310.607309)
					(end 285.556198 -310.622188)
				)
				(arc
					(start 286.955738 -310.622188)
					(mid 286.991659 -310.607309)
					(end 287.006538 -310.571388)
				)
				(arc
					(start 287.006538 -310.162448)
					(mid 286.991659 -310.126527)
					(end 286.955738 -310.111648)
				)
				(arc
					(start 285.556198 -310.111648)
					(mid 285.520277 -310.126527)
					(end 285.505398 -310.162448)
				)
			)
		)
	)
	(zone
		(layers "In1.Cu" "In2.Cu")
		(hatch none 0.5)
		(connect_pads
			(clearance 0)
		)
		(min_thickness 0.25)
		(keepout
			(tracks not_allowed)
			(vias allowed)
			(pads allowed)
			(copperpour not_allowed)
			(footprints allowed)
		)
		(placement
			(enabled no)
			(sheetname "")
		)
		(fill yes
			(thermal_gap 0.5)
			(thermal_bridge_width 0.5)
			(island_removal_mode 0)
		)
		(polygon
			(pts
				(arc
					(start 285.505398 -280.821384)
					(mid 285.520277 -280.857305)
					(end 285.556198 -280.872184)
				)
				(arc
					(start 286.955738 -280.872184)
					(mid 286.991659 -280.857305)
					(end 287.006538 -280.821384)
				)
				(arc
					(start 287.006538 -280.412444)
					(mid 286.991659 -280.376523)
					(end 286.955738 -280.361644)
				)
				(arc
					(start 285.556198 -280.361644)
					(mid 285.520277 -280.376523)
					(end 285.505398 -280.412444)
				)
			)
		)
	)
	(zone
		(layers "In1.Cu" "In2.Cu")
		(hatch none 0.5)
		(connect_pads
			(clearance 0)
		)
		(min_thickness 0.25)
		(keepout
			(tracks not_allowed)
			(vias allowed)
			(pads allowed)
			(copperpour not_allowed)
			(footprints allowed)
		)
		(placement
			(enabled no)
			(sheetname "")
		)
		(fill yes
			(thermal_gap 0.5)
			(thermal_bridge_width 0.5)
			(island_removal_mode 0)
		)
		(polygon
			(pts
				(arc
					(start 413.546798 -302.921416)
					(mid 413.561677 -302.957337)
					(end 413.597598 -302.972216)
				)
				(arc
					(start 414.997138 -302.972216)
					(mid 415.033059 -302.957337)
					(end 415.047938 -302.921416)
				)
				(arc
					(start 415.047938 -302.512476)
					(mid 415.033059 -302.476555)
					(end 414.997138 -302.461676)
				)
				(arc
					(start 413.597598 -302.461676)
					(mid 413.561677 -302.476555)
					(end 413.546798 -302.512476)
				)
			)
		)
	)
	(zone
		(layers "In1.Cu" "In2.Cu")
		(hatch none 0.5)
		(connect_pads
			(clearance 0)
		)
		(min_thickness 0.25)
		(keepout
			(tracks not_allowed)
			(vias allowed)
			(pads allowed)
			(copperpour not_allowed)
			(footprints allowed)
		)
		(placement
			(enabled no)
			(sheetname "")
		)
		(fill yes
			(thermal_gap 0.5)
			(thermal_bridge_width 0.5)
			(island_removal_mode 0)
		)
		(polygon
			(pts
				(arc
					(start 7.39013 -299.521372)
					(mid 7.405009 -299.557293)
					(end 7.44093 -299.572172)
				)
				(arc
					(start 8.84047 -299.572172)
					(mid 8.876391 -299.557293)
					(end 8.89127 -299.521372)
				)
				(arc
					(start 8.89127 -299.112432)
					(mid 8.876391 -299.076511)
					(end 8.84047 -299.061632)
				)
				(arc
					(start 7.44093 -299.061632)
					(mid 7.405009 -299.076511)
					(end 7.39013 -299.112432)
				)
			)
		)
	)
	(zone
		(layers "In1.Cu" "In2.Cu")
		(hatch none 0.5)
		(connect_pads
			(clearance 0)
		)
		(min_thickness 0.25)
		(keepout
			(tracks not_allowed)
			(vias allowed)
			(pads allowed)
			(copperpour not_allowed)
			(footprints allowed)
		)
		(placement
			(enabled no)
			(sheetname "")
		)
		(fill yes
			(thermal_gap 0.5)
			(thermal_bridge_width 0.5)
			(island_removal_mode 0)
		)
		(polygon
			(pts
				(arc
					(start 425.190666 -212.82152)
					(mid 425.205545 -212.857441)
					(end 425.241466 -212.87232)
				)
				(arc
					(start 426.641006 -212.87232)
					(mid 426.676927 -212.857441)
					(end 426.691806 -212.82152)
				)
				(arc
					(start 426.691806 -212.41258)
					(mid 426.676927 -212.376659)
					(end 426.641006 -212.36178)
				)
				(arc
					(start 425.241466 -212.36178)
					(mid 425.205545 -212.376659)
					(end 425.190666 -212.41258)
				)
			)
		)
	)
	(zone
		(layers "In1.Cu" "In2.Cu")
		(hatch none 0.5)
		(connect_pads
			(clearance 0)
		)
		(min_thickness 0.25)
		(keepout
			(tracks not_allowed)
			(vias allowed)
			(pads allowed)
			(copperpour not_allowed)
			(footprints allowed)
		)
		(placement
			(enabled no)
			(sheetname "")
		)
		(fill yes
			(thermal_gap 0.5)
			(thermal_bridge_width 0.5)
			(island_removal_mode 0)
		)
		(polygon
			(pts
				(arc
					(start 214.969598 -263.821418)
					(mid 214.984477 -263.857339)
					(end 215.020398 -263.872218)
				)
				(arc
					(start 216.419938 -263.872218)
					(mid 216.455859 -263.857339)
					(end 216.470738 -263.821418)
				)
				(arc
					(start 216.470738 -263.412478)
					(mid 216.455859 -263.376557)
					(end 216.419938 -263.361678)
				)
				(arc
					(start 215.020398 -263.361678)
					(mid 214.984477 -263.376557)
					(end 214.969598 -263.412478)
				)
			)
		)
	)
	(zone
		(layers "In1.Cu" "In2.Cu")
		(hatch none 0.5)
		(connect_pads
			(clearance 0)
		)
		(min_thickness 0.25)
		(keepout
			(tracks not_allowed)
			(vias allowed)
			(pads allowed)
			(copperpour not_allowed)
			(footprints allowed)
		)
		(placement
			(enabled no)
			(sheetname "")
		)
		(fill yes
			(thermal_gap 0.5)
			(thermal_bridge_width 0.5)
			(island_removal_mode 0)
		)
		(polygon
			(pts
				(arc
					(start 177.250598 -201.771504)
					(mid 177.265477 -201.807425)
					(end 177.301398 -201.822304)
				)
				(arc
					(start 178.700938 -201.822304)
					(mid 178.736859 -201.807425)
					(end 178.751738 -201.771504)
				)
				(arc
					(start 178.751738 -201.362564)
					(mid 178.736859 -201.326643)
					(end 178.700938 -201.311764)
				)
				(arc
					(start 177.301398 -201.311764)
					(mid 177.265477 -201.326643)
					(end 177.250598 -201.362564)
				)
			)
		)
	)
	(zone
		(layers "In1.Cu" "In2.Cu")
		(hatch none 0.5)
		(connect_pads
			(clearance 0)
		)
		(min_thickness 0.25)
		(keepout
			(tracks not_allowed)
			(vias allowed)
			(pads allowed)
			(copperpour not_allowed)
			(footprints allowed)
		)
		(placement
			(enabled no)
			(sheetname "")
		)
		(fill yes
			(thermal_gap 0.5)
			(thermal_bridge_width 0.5)
			(island_removal_mode 0)
		)
		(polygon
			(pts
				(arc
					(start 41.665398 -236.62132)
					(mid 41.680277 -236.657241)
					(end 41.716198 -236.67212)
				)
				(arc
					(start 43.115738 -236.67212)
					(mid 43.151659 -236.657241)
					(end 43.166538 -236.62132)
				)
				(arc
					(start 43.166538 -236.21238)
					(mid 43.151659 -236.176459)
					(end 43.115738 -236.16158)
				)
				(arc
					(start 41.716198 -236.16158)
					(mid 41.680277 -236.176459)
					(end 41.665398 -236.21238)
				)
			)
		)
	)
	(zone
		(layers "In1.Cu" "In2.Cu")
		(hatch none 0.5)
		(connect_pads
			(clearance 0)
		)
		(min_thickness 0.25)
		(keepout
			(tracks not_allowed)
			(vias allowed)
			(pads allowed)
			(copperpour not_allowed)
			(footprints allowed)
		)
		(placement
			(enabled no)
			(sheetname "")
		)
		(fill yes
			(thermal_gap 0.5)
			(thermal_bridge_width 0.5)
			(island_removal_mode 0)
		)
		(polygon
			(pts
				(arc
					(start 428.634398 -245.971314)
					(mid 428.649277 -246.007235)
					(end 428.685198 -246.022114)
				)
				(arc
					(start 430.084738 -246.022114)
					(mid 430.120659 -246.007235)
					(end 430.135538 -245.971314)
				)
				(arc
					(start 430.135538 -245.562374)
					(mid 430.120659 -245.526453)
					(end 430.084738 -245.511574)
				)
				(arc
					(start 428.685198 -245.511574)
					(mid 428.649277 -245.526453)
					(end 428.634398 -245.562374)
				)
			)
		)
	)
	(zone
		(layers "In1.Cu" "In2.Cu")
		(hatch none 0.5)
		(connect_pads
			(clearance 0)
		)
		(min_thickness 0.25)
		(keepout
			(tracks not_allowed)
			(vias allowed)
			(pads allowed)
			(copperpour not_allowed)
			(footprints allowed)
		)
		(placement
			(enabled no)
			(sheetname "")
		)
		(fill yes
			(thermal_gap 0.5)
			(thermal_bridge_width 0.5)
			(island_removal_mode 0)
		)
		(polygon
			(pts
				(arc
					(start 274.517866 -208.571338)
					(mid 274.532745 -208.607259)
					(end 274.568666 -208.622138)
				)
				(arc
					(start 275.968206 -208.622138)
					(mid 276.004127 -208.607259)
					(end 276.019006 -208.571338)
				)
				(arc
					(start 276.019006 -208.162398)
					(mid 276.004127 -208.126477)
					(end 275.968206 -208.111598)
				)
				(arc
					(start 274.568666 -208.111598)
					(mid 274.532745 -208.126477)
					(end 274.517866 -208.162398)
				)
			)
		)
	)
	(zone
		(layers "In1.Cu" "In2.Cu")
		(hatch none 0.5)
		(connect_pads
			(clearance 0)
		)
		(min_thickness 0.25)
		(keepout
			(tracks not_allowed)
			(vias allowed)
			(pads allowed)
			(copperpour not_allowed)
			(footprints allowed)
		)
		(placement
			(enabled no)
			(sheetname "")
		)
		(fill yes
			(thermal_gap 0.5)
			(thermal_bridge_width 0.5)
			(island_removal_mode 0)
		)
		(polygon
			(pts
				(arc
					(start 455.365866 -287.621472)
					(mid 455.380745 -287.657393)
					(end 455.416666 -287.672272)
				)
				(arc
					(start 456.816206 -287.672272)
					(mid 456.852127 -287.657393)
					(end 456.867006 -287.621472)
				)
				(arc
					(start 456.867006 -287.212532)
					(mid 456.852127 -287.176611)
					(end 456.816206 -287.161732)
				)
				(arc
					(start 455.416666 -287.161732)
					(mid 455.380745 -287.176611)
					(end 455.365866 -287.212532)
				)
			)
		)
	)
	(zone
		(layers "In1.Cu" "In2.Cu")
		(hatch none 0.5)
		(connect_pads
			(clearance 0)
		)
		(min_thickness 0.25)
		(keepout
			(tracks not_allowed)
			(vias allowed)
			(pads allowed)
			(copperpour not_allowed)
			(footprints allowed)
		)
		(placement
			(enabled no)
			(sheetname "")
		)
		(fill yes
			(thermal_gap 0.5)
			(thermal_bridge_width 0.5)
			(island_removal_mode 0)
		)
		(polygon
			(pts
				(arc
					(start 274.517866 -306.32146)
					(mid 274.532745 -306.357381)
					(end 274.568666 -306.37226)
				)
				(arc
					(start 275.968206 -306.37226)
					(mid 276.004127 -306.357381)
					(end 276.019006 -306.32146)
				)
				(arc
					(start 276.019006 -305.91252)
					(mid 276.004127 -305.876599)
					(end 275.968206 -305.86172)
				)
				(arc
					(start 274.568666 -305.86172)
					(mid 274.532745 -305.876599)
					(end 274.517866 -305.91252)
				)
			)
		)
	)
	(zone
		(layers "In1.Cu" "In2.Cu")
		(hatch none 0.5)
		(connect_pads
			(clearance 0)
		)
		(min_thickness 0.25)
		(keepout
			(tracks not_allowed)
			(vias allowed)
			(pads allowed)
			(copperpour not_allowed)
			(footprints allowed)
		)
		(placement
			(enabled no)
			(sheetname "")
		)
		(fill yes
			(thermal_gap 0.5)
			(thermal_bridge_width 0.5)
			(island_removal_mode 0)
		)
		(polygon
			(pts
				(arc
					(start 11.490198 -281.671522)
					(mid 11.505077 -281.707443)
					(end 11.540998 -281.722322)
				)
				(arc
					(start 12.940538 -281.722322)
					(mid 12.976459 -281.707443)
					(end 12.991338 -281.671522)
				)
				(arc
					(start 12.991338 -281.262582)
					(mid 12.976459 -281.226661)
					(end 12.940538 -281.211782)
				)
				(arc
					(start 11.540998 -281.211782)
					(mid 11.505077 -281.226661)
					(end 11.490198 -281.262582)
				)
			)
		)
	)
	(zone
		(layers "In1.Cu" "In2.Cu")
		(hatch none 0.5)
		(connect_pads
			(clearance 0)
		)
		(min_thickness 0.25)
		(keepout
			(tracks not_allowed)
			(vias allowed)
			(pads allowed)
			(copperpour not_allowed)
			(footprints allowed)
		)
		(placement
			(enabled no)
			(sheetname "")
		)
		(fill yes
			(thermal_gap 0.5)
			(thermal_bridge_width 0.5)
			(island_removal_mode 0)
		)
		(polygon
			(pts
				(arc
					(start 425.190666 -211.121498)
					(mid 425.205545 -211.157419)
					(end 425.241466 -211.172298)
				)
				(arc
					(start 426.641006 -211.172298)
					(mid 426.676927 -211.157419)
					(end 426.691806 -211.121498)
				)
				(arc
					(start 426.691806 -210.712558)
					(mid 426.676927 -210.676637)
					(end 426.641006 -210.661758)
				)
				(arc
					(start 425.241466 -210.661758)
					(mid 425.205545 -210.676637)
					(end 425.190666 -210.712558)
				)
			)
		)
	)
	(zone
		(layers "In1.Cu" "In2.Cu")
		(hatch none 0.5)
		(connect_pads
			(clearance 0)
		)
		(min_thickness 0.25)
		(keepout
			(tracks not_allowed)
			(vias allowed)
			(pads allowed)
			(copperpour not_allowed)
			(footprints allowed)
		)
		(placement
			(enabled no)
			(sheetname "")
		)
		(fill yes
			(thermal_gap 0.5)
			(thermal_bridge_width 0.5)
			(island_removal_mode 0)
		)
		(polygon
			(pts
				(arc
					(start 406.002998 -228.971348)
					(mid 406.017877 -229.007269)
					(end 406.053798 -229.022148)
				)
				(arc
					(start 407.453338 -229.022148)
					(mid 407.489259 -229.007269)
					(end 407.504138 -228.971348)
				)
				(arc
					(start 407.504138 -228.562408)
					(mid 407.489259 -228.526487)
					(end 407.453338 -228.511608)
				)
				(arc
					(start 406.053798 -228.511608)
					(mid 406.017877 -228.526487)
					(end 406.002998 -228.562408)
				)
			)
		)
	)
	(zone
		(layers "In1.Cu" "In2.Cu")
		(hatch none 0.5)
		(connect_pads
			(clearance 0)
		)
		(min_thickness 0.25)
		(keepout
			(tracks not_allowed)
			(vias allowed)
			(pads allowed)
			(copperpour not_allowed)
			(footprints allowed)
		)
		(placement
			(enabled no)
			(sheetname "")
		)
		(fill yes
			(thermal_gap 0.5)
			(thermal_bridge_width 0.5)
			(island_removal_mode 0)
		)
		(polygon
			(pts
				(arc
					(start 300.592998 -202.621388)
					(mid 300.607877 -202.657309)
					(end 300.643798 -202.672188)
				)
				(arc
					(start 302.043338 -202.672188)
					(mid 302.079259 -202.657309)
					(end 302.094138 -202.621388)
				)
				(arc
					(start 302.094138 -202.212448)
					(mid 302.079259 -202.176527)
					(end 302.043338 -202.161648)
				)
				(arc
					(start 300.643798 -202.161648)
					(mid 300.607877 -202.176527)
					(end 300.592998 -202.212448)
				)
			)
		)
	)
	(zone
		(layers "In1.Cu" "In2.Cu")
		(hatch none 0.5)
		(connect_pads
			(clearance 0)
		)
		(min_thickness 0.25)
		(keepout
			(tracks not_allowed)
			(vias allowed)
			(pads allowed)
			(copperpour not_allowed)
			(footprints allowed)
		)
		(placement
			(enabled no)
			(sheetname "")
		)
		(fill yes
			(thermal_gap 0.5)
			(thermal_bridge_width 0.5)
			(island_removal_mode 0)
		)
		(polygon
			(pts
				(arc
					(start 19.033998 -218.77147)
					(mid 19.048877 -218.807391)
					(end 19.084798 -218.82227)
				)
				(arc
					(start 20.484338 -218.82227)
					(mid 20.520259 -218.807391)
					(end 20.535138 -218.77147)
				)
				(arc
					(start 20.535138 -218.36253)
					(mid 20.520259 -218.326609)
					(end 20.484338 -218.31173)
				)
				(arc
					(start 19.084798 -218.31173)
					(mid 19.048877 -218.326609)
					(end 19.033998 -218.36253)
				)
			)
		)
	)
	(zone
		(layers "In1.Cu" "In2.Cu")
		(hatch none 0.5)
		(connect_pads
			(clearance 0)
		)
		(min_thickness 0.25)
		(keepout
			(tracks not_allowed)
			(vias allowed)
			(pads allowed)
			(copperpour not_allowed)
			(footprints allowed)
		)
		(placement
			(enabled no)
			(sheetname "")
		)
		(fill yes
			(thermal_gap 0.5)
			(thermal_bridge_width 0.5)
			(island_removal_mode 0)
		)
		(polygon
			(pts
				(arc
					(start 285.505398 -207.721454)
					(mid 285.520277 -207.757375)
					(end 285.556198 -207.772254)
				)
				(arc
					(start 286.955738 -207.772254)
					(mid 286.991659 -207.757375)
					(end 287.006538 -207.721454)
				)
				(arc
					(start 287.006538 -207.312514)
					(mid 286.991659 -207.276593)
					(end 286.955738 -207.261714)
				)
				(arc
					(start 285.556198 -207.261714)
					(mid 285.520277 -207.276593)
					(end 285.505398 -207.312514)
				)
			)
		)
	)
	(zone
		(layers "In1.Cu" "In2.Cu")
		(hatch none 0.5)
		(connect_pads
			(clearance 0)
		)
		(min_thickness 0.25)
		(keepout
			(tracks not_allowed)
			(vias allowed)
			(pads allowed)
			(copperpour not_allowed)
			(footprints allowed)
		)
		(placement
			(enabled no)
			(sheetname "")
		)
		(fill yes
			(thermal_gap 0.5)
			(thermal_bridge_width 0.5)
			(island_removal_mode 0)
		)
		(polygon
			(pts
				(arc
					(start 19.033998 -245.12143)
					(mid 19.048877 -245.157351)
					(end 19.084798 -245.17223)
				)
				(arc
					(start 20.484338 -245.17223)
					(mid 20.520259 -245.157351)
					(end 20.535138 -245.12143)
				)
				(arc
					(start 20.535138 -244.71249)
					(mid 20.520259 -244.676569)
					(end 20.484338 -244.66169)
				)
				(arc
					(start 19.084798 -244.66169)
					(mid 19.048877 -244.676569)
					(end 19.033998 -244.71249)
				)
			)
		)
	)
	(zone
		(layers "In1.Cu" "In2.Cu")
		(hatch none 0.5)
		(connect_pads
			(clearance 0)
		)
		(min_thickness 0.25)
		(keepout
			(tracks not_allowed)
			(vias allowed)
			(pads allowed)
			(copperpour not_allowed)
			(footprints allowed)
		)
		(placement
			(enabled no)
			(sheetname "")
		)
		(fill yes
			(thermal_gap 0.5)
			(thermal_bridge_width 0.5)
			(island_removal_mode 0)
		)
		(polygon
			(pts
				(arc
					(start 41.665398 -212.82152)
					(mid 41.680277 -212.857441)
					(end 41.716198 -212.87232)
				)
				(arc
					(start 43.115738 -212.87232)
					(mid 43.151659 -212.857441)
					(end 43.166538 -212.82152)
				)
				(arc
					(start 43.166538 -212.41258)
					(mid 43.151659 -212.376659)
					(end 43.115738 -212.36178)
				)
				(arc
					(start 41.716198 -212.36178)
					(mid 41.680277 -212.376659)
					(end 41.665398 -212.41258)
				)
			)
		)
	)
	(zone
		(layers "In1.Cu" "In2.Cu")
		(hatch none 0.5)
		(connect_pads
			(clearance 0)
		)
		(min_thickness 0.25)
		(keepout
			(tracks not_allowed)
			(vias allowed)
			(pads allowed)
			(copperpour not_allowed)
			(footprints allowed)
		)
		(placement
			(enabled no)
			(sheetname "")
		)
		(fill yes
			(thermal_gap 0.5)
			(thermal_bridge_width 0.5)
			(island_removal_mode 0)
		)
		(polygon
			(pts
				(arc
					(start 440.278266 -237.471458)
					(mid 440.293145 -237.507379)
					(end 440.329066 -237.522258)
				)
				(arc
					(start 441.728606 -237.522258)
					(mid 441.764527 -237.507379)
					(end 441.779406 -237.471458)
				)
				(arc
					(start 441.779406 -237.062518)
					(mid 441.764527 -237.026597)
					(end 441.728606 -237.011718)
				)
				(arc
					(start 440.329066 -237.011718)
					(mid 440.293145 -237.026597)
					(end 440.278266 -237.062518)
				)
			)
		)
	)
	(zone
		(layers "In1.Cu" "In2.Cu")
		(hatch none 0.5)
		(connect_pads
			(clearance 0)
		)
		(min_thickness 0.25)
		(keepout
			(tracks not_allowed)
			(vias allowed)
			(pads allowed)
			(copperpour not_allowed)
			(footprints allowed)
		)
		(placement
			(enabled no)
			(sheetname "")
		)
		(fill yes
			(thermal_gap 0.5)
			(thermal_bridge_width 0.5)
			(island_removal_mode 0)
		)
		(polygon
			(pts
				(arc
					(start 26.577798 -228.121464)
					(mid 26.592677 -228.157385)
					(end 26.628598 -228.172264)
				)
				(arc
					(start 28.028138 -228.172264)
					(mid 28.064059 -228.157385)
					(end 28.078938 -228.121464)
				)
				(arc
					(start 28.078938 -227.712524)
					(mid 28.064059 -227.676603)
					(end 28.028138 -227.661724)
				)
				(arc
					(start 26.628598 -227.661724)
					(mid 26.592677 -227.676603)
					(end 26.577798 -227.712524)
				)
			)
		)
	)
	(zone
		(layers "In1.Cu" "In2.Cu")
		(hatch none 0.5)
		(connect_pads
			(clearance 0)
		)
		(min_thickness 0.25)
		(keepout
			(tracks not_allowed)
			(vias allowed)
			(pads allowed)
			(copperpour not_allowed)
			(footprints allowed)
		)
		(placement
			(enabled no)
			(sheetname "")
		)
		(fill yes
			(thermal_gap 0.5)
			(thermal_bridge_width 0.5)
			(island_removal_mode 0)
		)
		(polygon
			(pts
				(arc
					(start 410.103066 -295.271444)
					(mid 410.117945 -295.307365)
					(end 410.153866 -295.322244)
				)
				(arc
					(start 411.553406 -295.322244)
					(mid 411.589327 -295.307365)
					(end 411.604206 -295.271444)
				)
				(arc
					(start 411.604206 -294.862504)
					(mid 411.589327 -294.826583)
					(end 411.553406 -294.811704)
				)
				(arc
					(start 410.153866 -294.811704)
					(mid 410.117945 -294.826583)
					(end 410.103066 -294.862504)
				)
			)
		)
	)
	(zone
		(layers "In1.Cu" "In2.Cu")
		(hatch none 0.5)
		(connect_pads
			(clearance 0)
		)
		(min_thickness 0.25)
		(keepout
			(tracks not_allowed)
			(vias allowed)
			(pads allowed)
			(copperpour not_allowed)
			(footprints allowed)
		)
		(placement
			(enabled no)
			(sheetname "")
		)
		(fill yes
			(thermal_gap 0.5)
			(thermal_bridge_width 0.5)
			(island_removal_mode 0)
		)
		(polygon
			(pts
				(arc
					(start 425.190666 -200.071482)
					(mid 425.205545 -200.107403)
					(end 425.241466 -200.122282)
				)
				(arc
					(start 426.641006 -200.122282)
					(mid 426.676927 -200.107403)
					(end 426.691806 -200.071482)
				)
				(arc
					(start 426.691806 -199.662542)
					(mid 426.676927 -199.626621)
					(end 426.641006 -199.611742)
				)
				(arc
					(start 425.241466 -199.611742)
					(mid 425.205545 -199.626621)
					(end 425.190666 -199.662542)
				)
			)
		)
	)
	(zone
		(layers "In1.Cu" "In2.Cu")
		(hatch none 0.5)
		(connect_pads
			(clearance 0)
		)
		(min_thickness 0.25)
		(keepout
			(tracks not_allowed)
			(vias allowed)
			(pads allowed)
			(copperpour not_allowed)
			(footprints allowed)
		)
		(placement
			(enabled no)
			(sheetname "")
		)
		(fill yes
			(thermal_gap 0.5)
			(thermal_bridge_width 0.5)
			(island_removal_mode 0)
		)
		(polygon
			(pts
				(arc
					(start 14.93393 -308.871366)
					(mid 14.948809 -308.907287)
					(end 14.98473 -308.922166)
				)
				(arc
					(start 16.38427 -308.922166)
					(mid 16.420191 -308.907287)
					(end 16.43507 -308.871366)
				)
				(arc
					(start 16.43507 -308.462426)
					(mid 16.420191 -308.426505)
					(end 16.38427 -308.411626)
				)
				(arc
					(start 14.98473 -308.411626)
					(mid 14.948809 -308.426505)
					(end 14.93393 -308.462426)
				)
			)
		)
	)
	(zone
		(layers "In1.Cu" "In2.Cu")
		(hatch none 0.5)
		(connect_pads
			(clearance 0)
		)
		(min_thickness 0.25)
		(keepout
			(tracks not_allowed)
			(vias allowed)
			(pads allowed)
			(copperpour not_allowed)
			(footprints allowed)
		)
		(placement
			(enabled no)
			(sheetname "")
		)
		(fill yes
			(thermal_gap 0.5)
			(thermal_bridge_width 0.5)
			(island_removal_mode 0)
		)
		(polygon
			(pts
				(arc
					(start 22.47773 -301.221394)
					(mid 22.492609 -301.257315)
					(end 22.52853 -301.272194)
				)
				(arc
					(start 23.92807 -301.272194)
					(mid 23.963991 -301.257315)
					(end 23.97887 -301.221394)
				)
				(arc
					(start 23.97887 -300.812454)
					(mid 23.963991 -300.776533)
					(end 23.92807 -300.761654)
				)
				(arc
					(start 22.52853 -300.761654)
					(mid 22.492609 -300.776533)
					(end 22.47773 -300.812454)
				)
			)
		)
	)
	(zone
		(layers "In1.Cu" "In2.Cu")
		(hatch none 0.5)
		(connect_pads
			(clearance 0)
		)
		(min_thickness 0.25)
		(keepout
			(tracks not_allowed)
			(vias allowed)
			(pads allowed)
			(copperpour not_allowed)
			(footprints allowed)
		)
		(placement
			(enabled no)
			(sheetname "")
		)
		(fill yes
			(thermal_gap 0.5)
			(thermal_bridge_width 0.5)
			(island_removal_mode 0)
		)
		(polygon
			(pts
				(arc
					(start 203.32573 -226.421442)
					(mid 203.340609 -226.457363)
					(end 203.37653 -226.472242)
				)
				(arc
					(start 204.77607 -226.472242)
					(mid 204.811991 -226.457363)
					(end 204.82687 -226.421442)
				)
				(arc
					(start 204.82687 -226.012502)
					(mid 204.811991 -225.976581)
					(end 204.77607 -225.961702)
				)
				(arc
					(start 203.37653 -225.961702)
					(mid 203.340609 -225.976581)
					(end 203.32573 -226.012502)
				)
			)
		)
	)
	(zone
		(layers "In1.Cu" "In2.Cu")
		(hatch none 0.5)
		(connect_pads
			(clearance 0)
		)
		(min_thickness 0.25)
		(keepout
			(tracks not_allowed)
			(vias allowed)
			(pads allowed)
			(copperpour not_allowed)
			(footprints allowed)
		)
		(placement
			(enabled no)
			(sheetname "")
		)
		(fill yes
			(thermal_gap 0.5)
			(thermal_bridge_width 0.5)
			(island_removal_mode 0)
		)
		(polygon
			(pts
				(arc
					(start 30.02153 -232.371392)
					(mid 30.036409 -232.407313)
					(end 30.07233 -232.422192)
				)
				(arc
					(start 31.47187 -232.422192)
					(mid 31.507791 -232.407313)
					(end 31.52267 -232.371392)
				)
				(arc
					(start 31.52267 -231.962452)
					(mid 31.507791 -231.926531)
					(end 31.47187 -231.911652)
				)
				(arc
					(start 30.07233 -231.911652)
					(mid 30.036409 -231.926531)
					(end 30.02153 -231.962452)
				)
			)
		)
	)
	(zone
		(layers "In1.Cu" "In2.Cu")
		(hatch none 0.5)
		(connect_pads
			(clearance 0)
		)
		(min_thickness 0.25)
		(keepout
			(tracks not_allowed)
			(vias allowed)
			(pads allowed)
			(copperpour not_allowed)
			(footprints allowed)
		)
		(placement
			(enabled no)
			(sheetname "")
		)
		(fill yes
			(thermal_gap 0.5)
			(thermal_bridge_width 0.5)
			(island_removal_mode 0)
		)
		(polygon
			(pts
				(arc
					(start 262.873998 -238.321342)
					(mid 262.888877 -238.357263)
					(end 262.924798 -238.372142)
				)
				(arc
					(start 264.324338 -238.372142)
					(mid 264.360259 -238.357263)
					(end 264.375138 -238.321342)
				)
				(arc
					(start 264.375138 -237.912402)
					(mid 264.360259 -237.876481)
					(end 264.324338 -237.861602)
				)
				(arc
					(start 262.924798 -237.861602)
					(mid 262.888877 -237.876481)
					(end 262.873998 -237.912402)
				)
			)
		)
	)
	(zone
		(layers "In1.Cu" "In2.Cu")
		(hatch none 0.5)
		(connect_pads
			(clearance 0)
		)
		(min_thickness 0.25)
		(keepout
			(tracks not_allowed)
			(vias allowed)
			(pads allowed)
			(copperpour not_allowed)
			(footprints allowed)
		)
		(placement
			(enabled no)
			(sheetname "")
		)
		(fill yes
			(thermal_gap 0.5)
			(thermal_bridge_width 0.5)
			(island_removal_mode 0)
		)
		(polygon
			(pts
				(arc
					(start 274.517866 -200.071482)
					(mid 274.532745 -200.107403)
					(end 274.568666 -200.122282)
				)
				(arc
					(start 275.968206 -200.122282)
					(mid 276.004127 -200.107403)
					(end 276.019006 -200.071482)
				)
				(arc
					(start 276.019006 -199.662542)
					(mid 276.004127 -199.626621)
					(end 275.968206 -199.611742)
				)
				(arc
					(start 274.568666 -199.611742)
					(mid 274.532745 -199.626621)
					(end 274.517866 -199.662542)
				)
			)
		)
	)
	(zone
		(layers "In1.Cu" "In2.Cu")
		(hatch none 0.5)
		(connect_pads
			(clearance 0)
		)
		(min_thickness 0.25)
		(keepout
			(tracks not_allowed)
			(vias allowed)
			(pads allowed)
			(copperpour not_allowed)
			(footprints allowed)
		)
		(placement
			(enabled no)
			(sheetname "")
		)
		(fill yes
			(thermal_gap 0.5)
			(thermal_bridge_width 0.5)
			(island_removal_mode 0)
		)
		(polygon
			(pts
				(arc
					(start 199.881998 -251.921518)
					(mid 199.896877 -251.957439)
					(end 199.932798 -251.972318)
				)
				(arc
					(start 201.332338 -251.972318)
					(mid 201.368259 -251.957439)
					(end 201.383138 -251.921518)
				)
				(arc
					(start 201.383138 -251.512578)
					(mid 201.368259 -251.476657)
					(end 201.332338 -251.461778)
				)
				(arc
					(start 199.932798 -251.461778)
					(mid 199.896877 -251.476657)
					(end 199.881998 -251.512578)
				)
			)
		)
	)
	(zone
		(layers "In1.Cu" "In2.Cu")
		(hatch none 0.5)
		(connect_pads
			(clearance 0)
		)
		(min_thickness 0.25)
		(keepout
			(tracks not_allowed)
			(vias allowed)
			(pads allowed)
			(copperpour not_allowed)
			(footprints allowed)
		)
		(placement
			(enabled no)
			(sheetname "")
		)
		(fill yes
			(thermal_gap 0.5)
			(thermal_bridge_width 0.5)
			(island_removal_mode 0)
		)
		(polygon
			(pts
				(arc
					(start 165.60673 -243.421408)
					(mid 165.621609 -243.457329)
					(end 165.65753 -243.472208)
				)
				(arc
					(start 167.05707 -243.472208)
					(mid 167.092991 -243.457329)
					(end 167.10787 -243.421408)
				)
				(arc
					(start 167.10787 -243.012468)
					(mid 167.092991 -242.976547)
					(end 167.05707 -242.961668)
				)
				(arc
					(start 165.65753 -242.961668)
					(mid 165.621609 -242.976547)
					(end 165.60673 -243.012468)
				)
			)
		)
	)
	(zone
		(layers "In1.Cu" "In2.Cu")
		(hatch none 0.5)
		(connect_pads
			(clearance 0)
		)
		(min_thickness 0.25)
		(keepout
			(tracks not_allowed)
			(vias allowed)
			(pads allowed)
			(copperpour not_allowed)
			(footprints allowed)
		)
		(placement
			(enabled no)
			(sheetname "")
		)
		(fill yes
			(thermal_gap 0.5)
			(thermal_bridge_width 0.5)
			(island_removal_mode 0)
		)
		(polygon
			(pts
				(arc
					(start 184.794398 -228.121464)
					(mid 184.809277 -228.157385)
					(end 184.845198 -228.172264)
				)
				(arc
					(start 186.244738 -228.172264)
					(mid 186.280659 -228.157385)
					(end 186.295538 -228.121464)
				)
				(arc
					(start 186.295538 -227.712524)
					(mid 186.280659 -227.676603)
					(end 186.244738 -227.661724)
				)
				(arc
					(start 184.845198 -227.661724)
					(mid 184.809277 -227.676603)
					(end 184.794398 -227.712524)
				)
			)
		)
	)
	(zone
		(layers "In1.Cu" "In2.Cu")
		(hatch none 0.5)
		(connect_pads
			(clearance 0)
		)
		(min_thickness 0.25)
		(keepout
			(tracks not_allowed)
			(vias allowed)
			(pads allowed)
			(copperpour not_allowed)
			(footprints allowed)
		)
		(placement
			(enabled no)
			(sheetname "")
		)
		(fill yes
			(thermal_gap 0.5)
			(thermal_bridge_width 0.5)
			(island_removal_mode 0)
		)
		(polygon
			(pts
				(arc
					(start 56.752998 -245.12143)
					(mid 56.767877 -245.157351)
					(end 56.803798 -245.17223)
				)
				(arc
					(start 58.203338 -245.17223)
					(mid 58.239259 -245.157351)
					(end 58.254138 -245.12143)
				)
				(arc
					(start 58.254138 -244.71249)
					(mid 58.239259 -244.676569)
					(end 58.203338 -244.66169)
				)
				(arc
					(start 56.803798 -244.66169)
					(mid 56.767877 -244.676569)
					(end 56.752998 -244.71249)
				)
			)
		)
	)
	(zone
		(layers "In1.Cu" "In2.Cu")
		(hatch none 0.5)
		(connect_pads
			(clearance 0)
		)
		(min_thickness 0.25)
		(keepout
			(tracks not_allowed)
			(vias allowed)
			(pads allowed)
			(copperpour not_allowed)
			(footprints allowed)
		)
		(placement
			(enabled no)
			(sheetname "")
		)
		(fill yes
			(thermal_gap 0.5)
			(thermal_bridge_width 0.5)
			(island_removal_mode 0)
		)
		(polygon
			(pts
				(arc
					(start 300.592998 -249.371358)
					(mid 300.607877 -249.407279)
					(end 300.643798 -249.422158)
				)
				(arc
					(start 302.043338 -249.422158)
					(mid 302.079259 -249.407279)
					(end 302.094138 -249.371358)
				)
				(arc
					(start 302.094138 -248.962418)
					(mid 302.079259 -248.926497)
					(end 302.043338 -248.911618)
				)
				(arc
					(start 300.643798 -248.911618)
					(mid 300.607877 -248.926497)
					(end 300.592998 -248.962418)
				)
			)
		)
	)
	(zone
		(layers "In1.Cu" "In2.Cu")
		(hatch none 0.5)
		(connect_pads
			(clearance 0)
		)
		(min_thickness 0.25)
		(keepout
			(tracks not_allowed)
			(vias allowed)
			(pads allowed)
			(copperpour not_allowed)
			(footprints allowed)
		)
		(placement
			(enabled no)
			(sheetname "")
		)
		(fill yes
			(thermal_gap 0.5)
			(thermal_bridge_width 0.5)
			(island_removal_mode 0)
		)
		(polygon
			(pts
				(arc
					(start 455.365866 -240.871502)
					(mid 455.380745 -240.907423)
					(end 455.416666 -240.922302)
				)
				(arc
					(start 456.816206 -240.922302)
					(mid 456.852127 -240.907423)
					(end 456.867006 -240.871502)
				)
				(arc
					(start 456.867006 -240.462562)
					(mid 456.852127 -240.426641)
					(end 456.816206 -240.411762)
				)
				(arc
					(start 455.416666 -240.411762)
					(mid 455.380745 -240.426641)
					(end 455.365866 -240.462562)
				)
			)
		)
	)
	(zone
		(layers "In1.Cu" "In2.Cu")
		(hatch none 0.5)
		(connect_pads
			(clearance 0)
		)
		(min_thickness 0.25)
		(keepout
			(tracks not_allowed)
			(vias allowed)
			(pads allowed)
			(copperpour not_allowed)
			(footprints allowed)
		)
		(placement
			(enabled no)
			(sheetname "")
		)
		(fill yes
			(thermal_gap 0.5)
			(thermal_bridge_width 0.5)
			(island_removal_mode 0)
		)
		(polygon
			(pts
				(arc
					(start 266.974066 -206.871316)
					(mid 266.988945 -206.907237)
					(end 267.024866 -206.922116)
				)
				(arc
					(start 268.424406 -206.922116)
					(mid 268.460327 -206.907237)
					(end 268.475206 -206.871316)
				)
				(arc
					(start 268.475206 -206.462376)
					(mid 268.460327 -206.426455)
					(end 268.424406 -206.411576)
				)
				(arc
					(start 267.024866 -206.411576)
					(mid 266.988945 -206.426455)
					(end 266.974066 -206.462376)
				)
			)
		)
	)
	(zone
		(layers "In1.Cu" "In2.Cu")
		(hatch none 0.5)
		(connect_pads
			(clearance 0)
		)
		(min_thickness 0.25)
		(keepout
			(tracks not_allowed)
			(vias allowed)
			(pads allowed)
			(copperpour not_allowed)
			(footprints allowed)
		)
		(placement
			(enabled no)
			(sheetname "")
		)
		(fill yes
			(thermal_gap 0.5)
			(thermal_bridge_width 0.5)
			(island_removal_mode 0)
		)
		(polygon
			(pts
				(arc
					(start 455.365866 -225.571304)
					(mid 455.380745 -225.607225)
					(end 455.416666 -225.622104)
				)
				(arc
					(start 456.816206 -225.622104)
					(mid 456.852127 -225.607225)
					(end 456.867006 -225.571304)
				)
				(arc
					(start 456.867006 -225.162364)
					(mid 456.852127 -225.126443)
					(end 456.816206 -225.111564)
				)
				(arc
					(start 455.416666 -225.111564)
					(mid 455.380745 -225.126443)
					(end 455.365866 -225.162364)
				)
			)
		)
	)
	(zone
		(layers "In1.Cu" "In2.Cu")
		(hatch none 0.5)
		(connect_pads
			(clearance 0)
		)
		(min_thickness 0.25)
		(keepout
			(tracks not_allowed)
			(vias allowed)
			(pads allowed)
			(copperpour not_allowed)
			(footprints allowed)
		)
		(placement
			(enabled no)
			(sheetname "")
		)
		(fill yes
			(thermal_gap 0.5)
			(thermal_bridge_width 0.5)
			(island_removal_mode 0)
		)
		(polygon
			(pts
				(arc
					(start 421.090598 -243.421408)
					(mid 421.105477 -243.457329)
					(end 421.141398 -243.472208)
				)
				(arc
					(start 422.540938 -243.472208)
					(mid 422.576859 -243.457329)
					(end 422.591738 -243.421408)
				)
				(arc
					(start 422.591738 -243.012468)
					(mid 422.576859 -242.976547)
					(end 422.540938 -242.961668)
				)
				(arc
					(start 421.141398 -242.961668)
					(mid 421.105477 -242.976547)
					(end 421.090598 -243.012468)
				)
			)
		)
	)
	(zone
		(layers "In1.Cu" "In2.Cu")
		(hatch none 0.5)
		(connect_pads
			(clearance 0)
		)
		(min_thickness 0.25)
		(keepout
			(tracks not_allowed)
			(vias allowed)
			(pads allowed)
			(copperpour not_allowed)
			(footprints allowed)
		)
		(placement
			(enabled no)
			(sheetname "")
		)
		(fill yes
			(thermal_gap 0.5)
			(thermal_bridge_width 0.5)
			(island_removal_mode 0)
		)
		(polygon
			(pts
				(arc
					(start 188.23813 -204.32141)
					(mid 188.253009 -204.357331)
					(end 188.28893 -204.37221)
				)
				(arc
					(start 189.68847 -204.37221)
					(mid 189.724391 -204.357331)
					(end 189.73927 -204.32141)
				)
				(arc
					(start 189.73927 -203.91247)
					(mid 189.724391 -203.876549)
					(end 189.68847 -203.86167)
				)
				(arc
					(start 188.28893 -203.86167)
					(mid 188.253009 -203.876549)
					(end 188.23813 -203.91247)
				)
			)
		)
	)
	(zone
		(layers "In1.Cu" "In2.Cu")
		(hatch none 0.5)
		(connect_pads
			(clearance 0)
		)
		(min_thickness 0.25)
		(keepout
			(tracks not_allowed)
			(vias allowed)
			(pads allowed)
			(copperpour not_allowed)
			(footprints allowed)
		)
		(placement
			(enabled no)
			(sheetname "")
		)
		(fill yes
			(thermal_gap 0.5)
			(thermal_bridge_width 0.5)
			(island_removal_mode 0)
		)
		(polygon
			(pts
				(arc
					(start 158.06293 -202.621388)
					(mid 158.077809 -202.657309)
					(end 158.11373 -202.672188)
				)
				(arc
					(start 159.51327 -202.672188)
					(mid 159.549191 -202.657309)
					(end 159.56407 -202.621388)
				)
				(arc
					(start 159.56407 -202.212448)
					(mid 159.549191 -202.176527)
					(end 159.51327 -202.161648)
				)
				(arc
					(start 158.11373 -202.161648)
					(mid 158.077809 -202.176527)
					(end 158.06293 -202.212448)
				)
			)
		)
	)
	(zone
		(layers "In1.Cu" "In2.Cu")
		(hatch none 0.5)
		(connect_pads
			(clearance 0)
		)
		(min_thickness 0.25)
		(keepout
			(tracks not_allowed)
			(vias allowed)
			(pads allowed)
			(copperpour not_allowed)
			(footprints allowed)
		)
		(placement
			(enabled no)
			(sheetname "")
		)
		(fill yes
			(thermal_gap 0.5)
			(thermal_bridge_width 0.5)
			(island_removal_mode 0)
		)
		(polygon
			(pts
				(arc
					(start 169.706798 -216.22131)
					(mid 169.721677 -216.257231)
					(end 169.757598 -216.27211)
				)
				(arc
					(start 171.157138 -216.27211)
					(mid 171.193059 -216.257231)
					(end 171.207938 -216.22131)
				)
				(arc
					(start 171.207938 -215.81237)
					(mid 171.193059 -215.776449)
					(end 171.157138 -215.76157)
				)
				(arc
					(start 169.757598 -215.76157)
					(mid 169.721677 -215.776449)
					(end 169.706798 -215.81237)
				)
			)
		)
	)
	(zone
		(layers "In1.Cu" "In2.Cu")
		(hatch none 0.5)
		(connect_pads
			(clearance 0)
		)
		(min_thickness 0.25)
		(keepout
			(tracks not_allowed)
			(vias allowed)
			(pads allowed)
			(copperpour not_allowed)
			(footprints allowed)
		)
		(placement
			(enabled no)
			(sheetname "")
		)
		(fill yes
			(thermal_gap 0.5)
			(thermal_bridge_width 0.5)
			(island_removal_mode 0)
		)
		(polygon
			(pts
				(arc
					(start 300.592998 -262.971534)
					(mid 300.607877 -263.007455)
					(end 300.643798 -263.022334)
				)
				(arc
					(start 302.043338 -263.022334)
					(mid 302.079259 -263.007455)
					(end 302.094138 -262.971534)
				)
				(arc
					(start 302.094138 -262.562594)
					(mid 302.079259 -262.526673)
					(end 302.043338 -262.511794)
				)
				(arc
					(start 300.643798 -262.511794)
					(mid 300.607877 -262.526673)
					(end 300.592998 -262.562594)
				)
			)
		)
	)
	(zone
		(layers "In1.Cu" "In2.Cu")
		(hatch none 0.5)
		(connect_pads
			(clearance 0)
		)
		(min_thickness 0.25)
		(keepout
			(tracks not_allowed)
			(vias allowed)
			(pads allowed)
			(copperpour not_allowed)
			(footprints allowed)
		)
		(placement
			(enabled no)
			(sheetname "")
		)
		(fill yes
			(thermal_gap 0.5)
			(thermal_bridge_width 0.5)
			(island_removal_mode 0)
		)
		(polygon
			(pts
				(arc
					(start 277.961598 -293.571422)
					(mid 277.976477 -293.607343)
					(end 278.012398 -293.622222)
				)
				(arc
					(start 279.411938 -293.622222)
					(mid 279.447859 -293.607343)
					(end 279.462738 -293.571422)
				)
				(arc
					(start 279.462738 -293.162482)
					(mid 279.447859 -293.126561)
					(end 279.411938 -293.111682)
				)
				(arc
					(start 278.012398 -293.111682)
					(mid 277.976477 -293.126561)
					(end 277.961598 -293.162482)
				)
			)
		)
	)
	(zone
		(layers "In1.Cu" "In2.Cu")
		(hatch none 0.5)
		(connect_pads
			(clearance 0)
		)
		(min_thickness 0.25)
		(keepout
			(tracks not_allowed)
			(vias allowed)
			(pads allowed)
			(copperpour not_allowed)
			(footprints allowed)
		)
		(placement
			(enabled no)
			(sheetname "")
		)
		(fill yes
			(thermal_gap 0.5)
			(thermal_bridge_width 0.5)
			(island_removal_mode 0)
		)
		(polygon
			(pts
				(arc
					(start 285.505398 -268.071346)
					(mid 285.520277 -268.107267)
					(end 285.556198 -268.122146)
				)
				(arc
					(start 286.955738 -268.122146)
					(mid 286.991659 -268.107267)
					(end 287.006538 -268.071346)
				)
				(arc
					(start 287.006538 -267.662406)
					(mid 286.991659 -267.626485)
					(end 286.955738 -267.611606)
				)
				(arc
					(start 285.556198 -267.611606)
					(mid 285.520277 -267.626485)
					(end 285.505398 -267.662406)
				)
			)
		)
	)
	(zone
		(layers "In1.Cu" "In2.Cu")
		(hatch none 0.5)
		(connect_pads
			(clearance 0)
		)
		(min_thickness 0.25)
		(keepout
			(tracks not_allowed)
			(vias allowed)
			(pads allowed)
			(copperpour not_allowed)
			(footprints allowed)
		)
		(placement
			(enabled no)
			(sheetname "")
		)
		(fill yes
			(thermal_gap 0.5)
			(thermal_bridge_width 0.5)
			(island_removal_mode 0)
		)
		(polygon
			(pts
				(arc
					(start 436.178198 -224.72142)
					(mid 436.193077 -224.757341)
					(end 436.228998 -224.77222)
				)
				(arc
					(start 437.628538 -224.77222)
					(mid 437.664459 -224.757341)
					(end 437.679338 -224.72142)
				)
				(arc
					(start 437.679338 -224.31248)
					(mid 437.664459 -224.276559)
					(end 437.628538 -224.26168)
				)
				(arc
					(start 436.228998 -224.26168)
					(mid 436.193077 -224.276559)
					(end 436.178198 -224.31248)
				)
			)
		)
	)
	(zone
		(layers "In1.Cu" "In2.Cu")
		(hatch none 0.5)
		(connect_pads
			(clearance 0)
		)
		(min_thickness 0.25)
		(keepout
			(tracks not_allowed)
			(vias allowed)
			(pads allowed)
			(copperpour not_allowed)
			(footprints allowed)
		)
		(placement
			(enabled no)
			(sheetname "")
		)
		(fill yes
			(thermal_gap 0.5)
			(thermal_bridge_width 0.5)
			(island_removal_mode 0)
		)
		(polygon
			(pts
				(arc
					(start 443.721998 -316.521338)
					(mid 443.736877 -316.557259)
					(end 443.772798 -316.572138)
				)
				(arc
					(start 445.172338 -316.572138)
					(mid 445.208259 -316.557259)
					(end 445.223138 -316.521338)
				)
				(arc
					(start 445.223138 -316.112398)
					(mid 445.208259 -316.076477)
					(end 445.172338 -316.061598)
				)
				(arc
					(start 443.772798 -316.061598)
					(mid 443.736877 -316.076477)
					(end 443.721998 -316.112398)
				)
			)
		)
	)
	(zone
		(layers "In1.Cu" "In2.Cu")
		(hatch none 0.5)
		(connect_pads
			(clearance 0)
		)
		(min_thickness 0.25)
		(keepout
			(tracks not_allowed)
			(vias allowed)
			(pads allowed)
			(copperpour not_allowed)
			(footprints allowed)
		)
		(placement
			(enabled no)
			(sheetname "")
		)
		(fill yes
			(thermal_gap 0.5)
			(thermal_bridge_width 0.5)
			(island_removal_mode 0)
		)
		(polygon
			(pts
				(arc
					(start 443.721998 -271.47139)
					(mid 443.736877 -271.507311)
					(end 443.772798 -271.52219)
				)
				(arc
					(start 445.172338 -271.52219)
					(mid 445.208259 -271.507311)
					(end 445.223138 -271.47139)
				)
				(arc
					(start 445.223138 -271.06245)
					(mid 445.208259 -271.026529)
					(end 445.172338 -271.01165)
				)
				(arc
					(start 443.772798 -271.01165)
					(mid 443.736877 -271.026529)
					(end 443.721998 -271.06245)
				)
			)
		)
	)
	(zone
		(layers "In1.Cu" "In2.Cu")
		(hatch none 0.5)
		(connect_pads
			(clearance 0)
		)
		(min_thickness 0.25)
		(keepout
			(tracks not_allowed)
			(vias allowed)
			(pads allowed)
			(copperpour not_allowed)
			(footprints allowed)
		)
		(placement
			(enabled no)
			(sheetname "")
		)
		(fill yes
			(thermal_gap 0.5)
			(thermal_bridge_width 0.5)
			(island_removal_mode 0)
		)
		(polygon
			(pts
				(arc
					(start 425.190666 -263.821418)
					(mid 425.205545 -263.857339)
					(end 425.241466 -263.872218)
				)
				(arc
					(start 426.641006 -263.872218)
					(mid 426.676927 -263.857339)
					(end 426.691806 -263.821418)
				)
				(arc
					(start 426.691806 -263.412478)
					(mid 426.676927 -263.376557)
					(end 426.641006 -263.361678)
				)
				(arc
					(start 425.241466 -263.361678)
					(mid 425.205545 -263.376557)
					(end 425.190666 -263.412478)
				)
			)
		)
	)
	(zone
		(layers "In1.Cu" "In2.Cu")
		(hatch none 0.5)
		(connect_pads
			(clearance 0)
		)
		(min_thickness 0.25)
		(keepout
			(tracks not_allowed)
			(vias allowed)
			(pads allowed)
			(copperpour not_allowed)
			(footprints allowed)
		)
		(placement
			(enabled no)
			(sheetname "")
		)
		(fill yes
			(thermal_gap 0.5)
			(thermal_bridge_width 0.5)
			(island_removal_mode 0)
		)
		(polygon
			(pts
				(arc
					(start 195.78193 -294.421306)
					(mid 195.796809 -294.457227)
					(end 195.83273 -294.472106)
				)
				(arc
					(start 197.23227 -294.472106)
					(mid 197.268191 -294.457227)
					(end 197.28307 -294.421306)
				)
				(arc
					(start 197.28307 -294.012366)
					(mid 197.268191 -293.976445)
					(end 197.23227 -293.961566)
				)
				(arc
					(start 195.83273 -293.961566)
					(mid 195.796809 -293.976445)
					(end 195.78193 -294.012366)
				)
			)
		)
	)
	(zone
		(layers "In1.Cu" "In2.Cu")
		(hatch none 0.5)
		(connect_pads
			(clearance 0)
		)
		(min_thickness 0.25)
		(keepout
			(tracks not_allowed)
			(vias allowed)
			(pads allowed)
			(copperpour not_allowed)
			(footprints allowed)
		)
		(placement
			(enabled no)
			(sheetname "")
		)
		(fill yes
			(thermal_gap 0.5)
			(thermal_bridge_width 0.5)
			(island_removal_mode 0)
		)
		(polygon
			(pts
				(arc
					(start 30.02153 -305.471322)
					(mid 30.036409 -305.507243)
					(end 30.07233 -305.522122)
				)
				(arc
					(start 31.47187 -305.522122)
					(mid 31.507791 -305.507243)
					(end 31.52267 -305.471322)
				)
				(arc
					(start 31.52267 -305.062382)
					(mid 31.507791 -305.026461)
					(end 31.47187 -305.011582)
				)
				(arc
					(start 30.07233 -305.011582)
					(mid 30.036409 -305.026461)
					(end 30.02153 -305.062382)
				)
			)
		)
	)
	(zone
		(layers "In1.Cu" "In2.Cu")
		(hatch none 0.5)
		(connect_pads
			(clearance 0)
		)
		(min_thickness 0.25)
		(keepout
			(tracks not_allowed)
			(vias allowed)
			(pads allowed)
			(copperpour not_allowed)
			(footprints allowed)
		)
		(placement
			(enabled no)
			(sheetname "")
		)
		(fill yes
			(thermal_gap 0.5)
			(thermal_bridge_width 0.5)
			(island_removal_mode 0)
		)
		(polygon
			(pts
				(arc
					(start 425.190666 -304.621438)
					(mid 425.205545 -304.657359)
					(end 425.241466 -304.672238)
				)
				(arc
					(start 426.641006 -304.672238)
					(mid 426.676927 -304.657359)
					(end 426.691806 -304.621438)
				)
				(arc
					(start 426.691806 -304.212498)
					(mid 426.676927 -304.176577)
					(end 426.641006 -304.161698)
				)
				(arc
					(start 425.241466 -304.161698)
					(mid 425.205545 -304.176577)
					(end 425.190666 -304.212498)
				)
			)
		)
	)
	(zone
		(layers "In1.Cu" "In2.Cu")
		(hatch none 0.5)
		(connect_pads
			(clearance 0)
		)
		(min_thickness 0.25)
		(keepout
			(tracks not_allowed)
			(vias allowed)
			(pads allowed)
			(copperpour not_allowed)
			(footprints allowed)
		)
		(placement
			(enabled no)
			(sheetname "")
		)
		(fill yes
			(thermal_gap 0.5)
			(thermal_bridge_width 0.5)
			(island_removal_mode 0)
		)
		(polygon
			(pts
				(arc
					(start 428.634398 -198.37146)
					(mid 428.649277 -198.407381)
					(end 428.685198 -198.42226)
				)
				(arc
					(start 430.084738 -198.42226)
					(mid 430.120659 -198.407381)
					(end 430.135538 -198.37146)
				)
				(arc
					(start 430.135538 -197.96252)
					(mid 430.120659 -197.926599)
					(end 430.084738 -197.91172)
				)
				(arc
					(start 428.685198 -197.91172)
					(mid 428.649277 -197.926599)
					(end 428.634398 -197.96252)
				)
			)
		)
	)
	(zone
		(layers "In1.Cu" "In2.Cu")
		(hatch none 0.5)
		(connect_pads
			(clearance 0)
		)
		(min_thickness 0.25)
		(keepout
			(tracks not_allowed)
			(vias allowed)
			(pads allowed)
			(copperpour not_allowed)
			(footprints allowed)
		)
		(placement
			(enabled no)
			(sheetname "")
		)
		(fill yes
			(thermal_gap 0.5)
			(thermal_bridge_width 0.5)
			(island_removal_mode 0)
		)
		(polygon
			(pts
				(arc
					(start 180.69433 -310.571388)
					(mid 180.709209 -310.607309)
					(end 180.74513 -310.622188)
				)
				(arc
					(start 182.14467 -310.622188)
					(mid 182.180591 -310.607309)
					(end 182.19547 -310.571388)
				)
				(arc
					(start 182.19547 -310.162448)
					(mid 182.180591 -310.126527)
					(end 182.14467 -310.111648)
				)
				(arc
					(start 180.74513 -310.111648)
					(mid 180.709209 -310.126527)
					(end 180.69433 -310.162448)
				)
			)
		)
	)
	(zone
		(layers "In1.Cu" "In2.Cu")
		(hatch none 0.5)
		(connect_pads
			(clearance 0)
		)
		(min_thickness 0.25)
		(keepout
			(tracks not_allowed)
			(vias allowed)
			(pads allowed)
			(copperpour not_allowed)
			(footprints allowed)
		)
		(placement
			(enabled no)
			(sheetname "")
		)
		(fill yes
			(thermal_gap 0.5)
			(thermal_bridge_width 0.5)
			(island_removal_mode 0)
		)
		(polygon
			(pts
				(arc
					(start 304.693066 -236.62132)
					(mid 304.707945 -236.657241)
					(end 304.743866 -236.67212)
				)
				(arc
					(start 306.143406 -236.67212)
					(mid 306.179327 -236.657241)
					(end 306.194206 -236.62132)
				)
				(arc
					(start 306.194206 -236.21238)
					(mid 306.179327 -236.176459)
					(end 306.143406 -236.16158)
				)
				(arc
					(start 304.743866 -236.16158)
					(mid 304.707945 -236.176459)
					(end 304.693066 -236.21238)
				)
			)
		)
	)
	(zone
		(layers "In1.Cu" "In2.Cu")
		(hatch none 0.5)
		(connect_pads
			(clearance 0)
		)
		(min_thickness 0.25)
		(keepout
			(tracks not_allowed)
			(vias allowed)
			(pads allowed)
			(copperpour not_allowed)
			(footprints allowed)
		)
		(placement
			(enabled no)
			(sheetname "")
		)
		(fill yes
			(thermal_gap 0.5)
			(thermal_bridge_width 0.5)
			(island_removal_mode 0)
		)
		(polygon
			(pts
				(arc
					(start 37.56533 -293.571422)
					(mid 37.580209 -293.607343)
					(end 37.61613 -293.622222)
				)
				(arc
					(start 39.01567 -293.622222)
					(mid 39.051591 -293.607343)
					(end 39.06647 -293.571422)
				)
				(arc
					(start 39.06647 -293.162482)
					(mid 39.051591 -293.126561)
					(end 39.01567 -293.111682)
				)
				(arc
					(start 37.61613 -293.111682)
					(mid 37.580209 -293.126561)
					(end 37.56533 -293.162482)
				)
			)
		)
	)
	(zone
		(layers "In1.Cu" "In2.Cu")
		(hatch none 0.5)
		(connect_pads
			(clearance 0)
		)
		(min_thickness 0.25)
		(keepout
			(tracks not_allowed)
			(vias allowed)
			(pads allowed)
			(copperpour not_allowed)
			(footprints allowed)
		)
		(placement
			(enabled no)
			(sheetname "")
		)
		(fill yes
			(thermal_gap 0.5)
			(thermal_bridge_width 0.5)
			(island_removal_mode 0)
		)
		(polygon
			(pts
				(arc
					(start 413.546798 -249.371358)
					(mid 413.561677 -249.407279)
					(end 413.597598 -249.422158)
				)
				(arc
					(start 414.997138 -249.422158)
					(mid 415.033059 -249.407279)
					(end 415.047938 -249.371358)
				)
				(arc
					(start 415.047938 -248.962418)
					(mid 415.033059 -248.926497)
					(end 414.997138 -248.911618)
				)
				(arc
					(start 413.597598 -248.911618)
					(mid 413.561677 -248.926497)
					(end 413.546798 -248.962418)
				)
			)
		)
	)
	(zone
		(layers "In1.Cu" "In2.Cu")
		(hatch none 0.5)
		(connect_pads
			(clearance 0)
		)
		(min_thickness 0.25)
		(keepout
			(tracks not_allowed)
			(vias allowed)
			(pads allowed)
			(copperpour not_allowed)
			(footprints allowed)
		)
		(placement
			(enabled no)
			(sheetname "")
		)
		(fill yes
			(thermal_gap 0.5)
			(thermal_bridge_width 0.5)
			(island_removal_mode 0)
		)
		(polygon
			(pts
				(arc
					(start 455.365866 -209.421476)
					(mid 455.380745 -209.457397)
					(end 455.416666 -209.472276)
				)
				(arc
					(start 456.816206 -209.472276)
					(mid 456.852127 -209.457397)
					(end 456.867006 -209.421476)
				)
				(arc
					(start 456.867006 -209.012536)
					(mid 456.852127 -208.976615)
					(end 456.816206 -208.961736)
				)
				(arc
					(start 455.416666 -208.961736)
					(mid 455.380745 -208.976615)
					(end 455.365866 -209.012536)
				)
			)
		)
	)
	(zone
		(layers "In1.Cu" "In2.Cu")
		(hatch none 0.5)
		(connect_pads
			(clearance 0)
		)
		(min_thickness 0.25)
		(keepout
			(tracks not_allowed)
			(vias allowed)
			(pads allowed)
			(copperpour not_allowed)
			(footprints allowed)
		)
		(placement
			(enabled no)
			(sheetname "")
		)
		(fill yes
			(thermal_gap 0.5)
			(thermal_bridge_width 0.5)
			(island_removal_mode 0)
		)
		(polygon
			(pts
				(arc
					(start 180.69433 -215.371426)
					(mid 180.709209 -215.407347)
					(end 180.74513 -215.422226)
				)
				(arc
					(start 182.14467 -215.422226)
					(mid 182.180591 -215.407347)
					(end 182.19547 -215.371426)
				)
				(arc
					(start 182.19547 -214.962486)
					(mid 182.180591 -214.926565)
					(end 182.14467 -214.911686)
				)
				(arc
					(start 180.74513 -214.911686)
					(mid 180.709209 -214.926565)
					(end 180.69433 -214.962486)
				)
			)
		)
	)
	(zone
		(layers "In1.Cu" "In2.Cu")
		(hatch none 0.5)
		(connect_pads
			(clearance 0)
		)
		(min_thickness 0.25)
		(keepout
			(tracks not_allowed)
			(vias allowed)
			(pads allowed)
			(copperpour not_allowed)
			(footprints allowed)
		)
		(placement
			(enabled no)
			(sheetname "")
		)
		(fill yes
			(thermal_gap 0.5)
			(thermal_bridge_width 0.5)
			(island_removal_mode 0)
		)
		(polygon
			(pts
				(arc
					(start 255.330198 -228.121464)
					(mid 255.345077 -228.157385)
					(end 255.380998 -228.172264)
				)
				(arc
					(start 256.780538 -228.172264)
					(mid 256.816459 -228.157385)
					(end 256.831338 -228.121464)
				)
				(arc
					(start 256.831338 -227.712524)
					(mid 256.816459 -227.676603)
					(end 256.780538 -227.661724)
				)
				(arc
					(start 255.380998 -227.661724)
					(mid 255.345077 -227.676603)
					(end 255.330198 -227.712524)
				)
			)
		)
	)
	(zone
		(layers "In1.Cu" "In2.Cu")
		(hatch none 0.5)
		(connect_pads
			(clearance 0)
		)
		(min_thickness 0.25)
		(keepout
			(tracks not_allowed)
			(vias allowed)
			(pads allowed)
			(copperpour not_allowed)
			(footprints allowed)
		)
		(placement
			(enabled no)
			(sheetname "")
		)
		(fill yes
			(thermal_gap 0.5)
			(thermal_bridge_width 0.5)
			(island_removal_mode 0)
		)
		(polygon
			(pts
				(arc
					(start 188.23813 -294.421306)
					(mid 188.253009 -294.457227)
					(end 188.28893 -294.472106)
				)
				(arc
					(start 189.68847 -294.472106)
					(mid 189.724391 -294.457227)
					(end 189.73927 -294.421306)
				)
				(arc
					(start 189.73927 -294.012366)
					(mid 189.724391 -293.976445)
					(end 189.68847 -293.961566)
				)
				(arc
					(start 188.28893 -293.961566)
					(mid 188.253009 -293.976445)
					(end 188.23813 -294.012366)
				)
			)
		)
	)
	(zone
		(layers "In1.Cu" "In2.Cu")
		(hatch none 0.5)
		(connect_pads
			(clearance 0)
		)
		(min_thickness 0.25)
		(keepout
			(tracks not_allowed)
			(vias allowed)
			(pads allowed)
			(copperpour not_allowed)
			(footprints allowed)
		)
		(placement
			(enabled no)
			(sheetname "")
		)
		(fill yes
			(thermal_gap 0.5)
			(thermal_bridge_width 0.5)
			(island_removal_mode 0)
		)
		(polygon
			(pts
				(arc
					(start 7.39013 -249.371358)
					(mid 7.405009 -249.407279)
					(end 7.44093 -249.422158)
				)
				(arc
					(start 8.84047 -249.422158)
					(mid 8.876391 -249.407279)
					(end 8.89127 -249.371358)
				)
				(arc
					(start 8.89127 -248.962418)
					(mid 8.876391 -248.926497)
					(end 8.84047 -248.911618)
				)
				(arc
					(start 7.44093 -248.911618)
					(mid 7.405009 -248.926497)
					(end 7.39013 -248.962418)
				)
			)
		)
	)
	(zone
		(layers "In1.Cu" "In2.Cu")
		(hatch none 0.5)
		(connect_pads
			(clearance 0)
		)
		(min_thickness 0.25)
		(keepout
			(tracks not_allowed)
			(vias allowed)
			(pads allowed)
			(copperpour not_allowed)
			(footprints allowed)
		)
		(placement
			(enabled no)
			(sheetname "")
		)
		(fill yes
			(thermal_gap 0.5)
			(thermal_bridge_width 0.5)
			(island_removal_mode 0)
		)
		(polygon
			(pts
				(arc
					(start 255.330198 -202.621388)
					(mid 255.345077 -202.657309)
					(end 255.380998 -202.672188)
				)
				(arc
					(start 256.780538 -202.672188)
					(mid 256.816459 -202.657309)
					(end 256.831338 -202.621388)
				)
				(arc
					(start 256.831338 -202.212448)
					(mid 256.816459 -202.176527)
					(end 256.780538 -202.161648)
				)
				(arc
					(start 255.380998 -202.161648)
					(mid 255.345077 -202.176527)
					(end 255.330198 -202.212448)
				)
			)
		)
	)
	(zone
		(layers "In1.Cu" "In2.Cu")
		(hatch none 0.5)
		(connect_pads
			(clearance 0)
		)
		(min_thickness 0.25)
		(keepout
			(tracks not_allowed)
			(vias allowed)
			(pads allowed)
			(copperpour not_allowed)
			(footprints allowed)
		)
		(placement
			(enabled no)
			(sheetname "")
		)
		(fill yes
			(thermal_gap 0.5)
			(thermal_bridge_width 0.5)
			(island_removal_mode 0)
		)
		(polygon
			(pts
				(arc
					(start 428.634398 -275.721318)
					(mid 428.649277 -275.757239)
					(end 428.685198 -275.772118)
				)
				(arc
					(start 430.084738 -275.772118)
					(mid 430.120659 -275.757239)
					(end 430.135538 -275.721318)
				)
				(arc
					(start 430.135538 -275.312378)
					(mid 430.120659 -275.276457)
					(end 430.084738 -275.261578)
				)
				(arc
					(start 428.685198 -275.261578)
					(mid 428.649277 -275.276457)
					(end 428.634398 -275.312378)
				)
			)
		)
	)
	(zone
		(layers "In1.Cu" "In2.Cu")
		(hatch none 0.5)
		(connect_pads
			(clearance 0)
		)
		(min_thickness 0.25)
		(keepout
			(tracks not_allowed)
			(vias allowed)
			(pads allowed)
			(copperpour not_allowed)
			(footprints allowed)
		)
		(placement
			(enabled no)
			(sheetname "")
		)
		(fill yes
			(thermal_gap 0.5)
			(thermal_bridge_width 0.5)
			(island_removal_mode 0)
		)
		(polygon
			(pts
				(arc
					(start 49.209198 -250.221496)
					(mid 49.224077 -250.257417)
					(end 49.259998 -250.272296)
				)
				(arc
					(start 50.659538 -250.272296)
					(mid 50.695459 -250.257417)
					(end 50.710338 -250.221496)
				)
				(arc
					(start 50.710338 -249.812556)
					(mid 50.695459 -249.776635)
					(end 50.659538 -249.761756)
				)
				(arc
					(start 49.259998 -249.761756)
					(mid 49.224077 -249.776635)
					(end 49.209198 -249.812556)
				)
			)
		)
	)
	(zone
		(layers "In1.Cu" "In2.Cu")
		(hatch none 0.5)
		(connect_pads
			(clearance 0)
		)
		(min_thickness 0.25)
		(keepout
			(tracks not_allowed)
			(vias allowed)
			(pads allowed)
			(copperpour not_allowed)
			(footprints allowed)
		)
		(placement
			(enabled no)
			(sheetname "")
		)
		(fill yes
			(thermal_gap 0.5)
			(thermal_bridge_width 0.5)
			(island_removal_mode 0)
		)
		(polygon
			(pts
				(arc
					(start 410.103066 -201.771504)
					(mid 410.117945 -201.807425)
					(end 410.153866 -201.822304)
				)
				(arc
					(start 411.553406 -201.822304)
					(mid 411.589327 -201.807425)
					(end 411.604206 -201.771504)
				)
				(arc
					(start 411.604206 -201.362564)
					(mid 411.589327 -201.326643)
					(end 411.553406 -201.311764)
				)
				(arc
					(start 410.153866 -201.311764)
					(mid 410.117945 -201.326643)
					(end 410.103066 -201.362564)
				)
			)
		)
	)
	(zone
		(layers "In1.Cu" "In2.Cu")
		(hatch none 0.5)
		(connect_pads
			(clearance 0)
		)
		(min_thickness 0.25)
		(keepout
			(tracks not_allowed)
			(vias allowed)
			(pads allowed)
			(copperpour not_allowed)
			(footprints allowed)
		)
		(placement
			(enabled no)
			(sheetname "")
		)
		(fill yes
			(thermal_gap 0.5)
			(thermal_bridge_width 0.5)
			(island_removal_mode 0)
		)
		(polygon
			(pts
				(arc
					(start 266.974066 -279.9715)
					(mid 266.988945 -280.007421)
					(end 267.024866 -280.0223)
				)
				(arc
					(start 268.424406 -280.0223)
					(mid 268.460327 -280.007421)
					(end 268.475206 -279.9715)
				)
				(arc
					(start 268.475206 -279.56256)
					(mid 268.460327 -279.526639)
					(end 268.424406 -279.51176)
				)
				(arc
					(start 267.024866 -279.51176)
					(mid 266.988945 -279.526639)
					(end 266.974066 -279.56256)
				)
			)
		)
	)
	(zone
		(layers "In1.Cu" "In2.Cu")
		(hatch none 0.5)
		(connect_pads
			(clearance 0)
		)
		(min_thickness 0.25)
		(keepout
			(tracks not_allowed)
			(vias allowed)
			(pads allowed)
			(copperpour not_allowed)
			(footprints allowed)
		)
		(placement
			(enabled no)
			(sheetname "")
		)
		(fill yes
			(thermal_gap 0.5)
			(thermal_bridge_width 0.5)
			(island_removal_mode 0)
		)
		(polygon
			(pts
				(arc
					(start 158.06293 -314.821316)
					(mid 158.077809 -314.857237)
					(end 158.11373 -314.872116)
				)
				(arc
					(start 159.51327 -314.872116)
					(mid 159.549191 -314.857237)
					(end 159.56407 -314.821316)
				)
				(arc
					(start 159.56407 -314.412376)
					(mid 159.549191 -314.376455)
					(end 159.51327 -314.361576)
				)
				(arc
					(start 158.11373 -314.361576)
					(mid 158.077809 -314.376455)
					(end 158.06293 -314.412376)
				)
			)
		)
	)
	(zone
		(layers "In1.Cu" "In2.Cu")
		(hatch none 0.5)
		(connect_pads
			(clearance 0)
		)
		(min_thickness 0.25)
		(keepout
			(tracks not_allowed)
			(vias allowed)
			(pads allowed)
			(copperpour not_allowed)
			(footprints allowed)
		)
		(placement
			(enabled no)
			(sheetname "")
		)
		(fill yes
			(thermal_gap 0.5)
			(thermal_bridge_width 0.5)
			(island_removal_mode 0)
		)
		(polygon
			(pts
				(arc
					(start 293.049198 -224.72142)
					(mid 293.064077 -224.757341)
					(end 293.099998 -224.77222)
				)
				(arc
					(start 294.499538 -224.77222)
					(mid 294.535459 -224.757341)
					(end 294.550338 -224.72142)
				)
				(arc
					(start 294.550338 -224.31248)
					(mid 294.535459 -224.276559)
					(end 294.499538 -224.26168)
				)
				(arc
					(start 293.099998 -224.26168)
					(mid 293.064077 -224.276559)
					(end 293.049198 -224.31248)
				)
			)
		)
	)
	(zone
		(layers "In1.Cu" "In2.Cu")
		(hatch none 0.5)
		(connect_pads
			(clearance 0)
		)
		(min_thickness 0.25)
		(keepout
			(tracks not_allowed)
			(vias allowed)
			(pads allowed)
			(copperpour not_allowed)
			(footprints allowed)
		)
		(placement
			(enabled no)
			(sheetname "")
		)
		(fill yes
			(thermal_gap 0.5)
			(thermal_bridge_width 0.5)
			(island_removal_mode 0)
		)
		(polygon
			(pts
				(arc
					(start 417.646866 -208.571338)
					(mid 417.661745 -208.607259)
					(end 417.697666 -208.622138)
				)
				(arc
					(start 419.097206 -208.622138)
					(mid 419.133127 -208.607259)
					(end 419.148006 -208.571338)
				)
				(arc
					(start 419.148006 -208.162398)
					(mid 419.133127 -208.126477)
					(end 419.097206 -208.111598)
				)
				(arc
					(start 417.697666 -208.111598)
					(mid 417.661745 -208.126477)
					(end 417.646866 -208.162398)
				)
			)
		)
	)
	(zone
		(layers "In1.Cu" "In2.Cu")
		(hatch none 0.5)
		(connect_pads
			(clearance 0)
		)
		(min_thickness 0.25)
		(keepout
			(tracks not_allowed)
			(vias allowed)
			(pads allowed)
			(copperpour not_allowed)
			(footprints allowed)
		)
		(placement
			(enabled no)
			(sheetname "")
		)
		(fill yes
			(thermal_gap 0.5)
			(thermal_bridge_width 0.5)
			(island_removal_mode 0)
		)
		(polygon
			(pts
				(arc
					(start 60.19673 -207.721454)
					(mid 60.211609 -207.757375)
					(end 60.24753 -207.772254)
				)
				(arc
					(start 61.64707 -207.772254)
					(mid 61.682991 -207.757375)
					(end 61.69787 -207.721454)
				)
				(arc
					(start 61.69787 -207.312514)
					(mid 61.682991 -207.276593)
					(end 61.64707 -207.261714)
				)
				(arc
					(start 60.24753 -207.261714)
					(mid 60.211609 -207.276593)
					(end 60.19673 -207.312514)
				)
			)
		)
	)
	(zone
		(layers "In1.Cu" "In2.Cu")
		(hatch none 0.5)
		(connect_pads
			(clearance 0)
		)
		(min_thickness 0.25)
		(keepout
			(tracks not_allowed)
			(vias allowed)
			(pads allowed)
			(copperpour not_allowed)
			(footprints allowed)
		)
		(placement
			(enabled no)
			(sheetname "")
		)
		(fill yes
			(thermal_gap 0.5)
			(thermal_bridge_width 0.5)
			(island_removal_mode 0)
		)
		(polygon
			(pts
				(arc
					(start 199.881998 -197.521322)
					(mid 199.896877 -197.557243)
					(end 199.932798 -197.572122)
				)
				(arc
					(start 201.332338 -197.572122)
					(mid 201.368259 -197.557243)
					(end 201.383138 -197.521322)
				)
				(arc
					(start 201.383138 -197.112382)
					(mid 201.368259 -197.076461)
					(end 201.332338 -197.061582)
				)
				(arc
					(start 199.932798 -197.061582)
					(mid 199.896877 -197.076461)
					(end 199.881998 -197.112382)
				)
			)
		)
	)
	(zone
		(layers "In1.Cu" "In2.Cu")
		(hatch none 0.5)
		(connect_pads
			(clearance 0)
		)
		(min_thickness 0.25)
		(keepout
			(tracks not_allowed)
			(vias allowed)
			(pads allowed)
			(copperpour not_allowed)
			(footprints allowed)
		)
		(placement
			(enabled no)
			(sheetname "")
		)
		(fill yes
			(thermal_gap 0.5)
			(thermal_bridge_width 0.5)
			(island_removal_mode 0)
		)
		(polygon
			(pts
				(arc
					(start 297.149266 -274.02155)
					(mid 297.164145 -274.057471)
					(end 297.200066 -274.07235)
				)
				(arc
					(start 298.599606 -274.07235)
					(mid 298.635527 -274.057471)
					(end 298.650406 -274.02155)
				)
				(arc
					(start 298.650406 -273.61261)
					(mid 298.635527 -273.576689)
					(end 298.599606 -273.56181)
				)
				(arc
					(start 297.200066 -273.56181)
					(mid 297.164145 -273.576689)
					(end 297.149266 -273.61261)
				)
			)
		)
	)
	(zone
		(layers "In1.Cu" "In2.Cu")
		(hatch none 0.5)
		(connect_pads
			(clearance 0)
		)
		(min_thickness 0.25)
		(keepout
			(tracks not_allowed)
			(vias allowed)
			(pads allowed)
			(copperpour not_allowed)
			(footprints allowed)
		)
		(placement
			(enabled no)
			(sheetname "")
		)
		(fill yes
			(thermal_gap 0.5)
			(thermal_bridge_width 0.5)
			(island_removal_mode 0)
		)
		(polygon
			(pts
				(arc
					(start 297.149266 -291.021516)
					(mid 297.164145 -291.057437)
					(end 297.200066 -291.072316)
				)
				(arc
					(start 298.599606 -291.072316)
					(mid 298.635527 -291.057437)
					(end 298.650406 -291.021516)
				)
				(arc
					(start 298.650406 -290.612576)
					(mid 298.635527 -290.576655)
					(end 298.599606 -290.561776)
				)
				(arc
					(start 297.200066 -290.561776)
					(mid 297.164145 -290.576655)
					(end 297.149266 -290.612576)
				)
			)
		)
	)
	(zone
		(layers "In1.Cu" "In2.Cu")
		(hatch none 0.5)
		(connect_pads
			(clearance 0)
		)
		(min_thickness 0.25)
		(keepout
			(tracks not_allowed)
			(vias allowed)
			(pads allowed)
			(copperpour not_allowed)
			(footprints allowed)
		)
		(placement
			(enabled no)
			(sheetname "")
		)
		(fill yes
			(thermal_gap 0.5)
			(thermal_bridge_width 0.5)
			(island_removal_mode 0)
		)
		(polygon
			(pts
				(arc
					(start 195.78193 -213.671404)
					(mid 195.796809 -213.707325)
					(end 195.83273 -213.722204)
				)
				(arc
					(start 197.23227 -213.722204)
					(mid 197.268191 -213.707325)
					(end 197.28307 -213.671404)
				)
				(arc
					(start 197.28307 -213.262464)
					(mid 197.268191 -213.226543)
					(end 197.23227 -213.211664)
				)
				(arc
					(start 195.83273 -213.211664)
					(mid 195.796809 -213.226543)
					(end 195.78193 -213.262464)
				)
			)
		)
	)
	(zone
		(layers "In1.Cu" "In2.Cu")
		(hatch none 0.5)
		(connect_pads
			(clearance 0)
		)
		(min_thickness 0.25)
		(keepout
			(tracks not_allowed)
			(vias allowed)
			(pads allowed)
			(copperpour not_allowed)
			(footprints allowed)
		)
		(placement
			(enabled no)
			(sheetname "")
		)
		(fill yes
			(thermal_gap 0.5)
			(thermal_bridge_width 0.5)
			(island_removal_mode 0)
		)
		(polygon
			(pts
				(arc
					(start 22.47773 -273.171412)
					(mid 22.492609 -273.207333)
					(end 22.52853 -273.222212)
				)
				(arc
					(start 23.92807 -273.222212)
					(mid 23.963991 -273.207333)
					(end 23.97887 -273.171412)
				)
				(arc
					(start 23.97887 -272.762472)
					(mid 23.963991 -272.726551)
					(end 23.92807 -272.711672)
				)
				(arc
					(start 22.52853 -272.711672)
					(mid 22.492609 -272.726551)
					(end 22.47773 -272.762472)
				)
			)
		)
	)
	(zone
		(layers "In1.Cu" "In2.Cu")
		(hatch none 0.5)
		(connect_pads
			(clearance 0)
		)
		(min_thickness 0.25)
		(keepout
			(tracks not_allowed)
			(vias allowed)
			(pads allowed)
			(copperpour not_allowed)
			(footprints allowed)
		)
		(placement
			(enabled no)
			(sheetname "")
		)
		(fill yes
			(thermal_gap 0.5)
			(thermal_bridge_width 0.5)
			(island_removal_mode 0)
		)
		(polygon
			(pts
				(arc
					(start 304.693066 -262.121396)
					(mid 304.707945 -262.157317)
					(end 304.743866 -262.172196)
				)
				(arc
					(start 306.143406 -262.172196)
					(mid 306.179327 -262.157317)
					(end 306.194206 -262.121396)
				)
				(arc
					(start 306.194206 -261.712456)
					(mid 306.179327 -261.676535)
					(end 306.143406 -261.661656)
				)
				(arc
					(start 304.743866 -261.661656)
					(mid 304.707945 -261.676535)
					(end 304.693066 -261.712456)
				)
			)
		)
	)
	(zone
		(layers "In1.Cu" "In2.Cu")
		(hatch none 0.5)
		(connect_pads
			(clearance 0)
		)
		(min_thickness 0.25)
		(keepout
			(tracks not_allowed)
			(vias allowed)
			(pads allowed)
			(copperpour not_allowed)
			(footprints allowed)
		)
		(placement
			(enabled no)
			(sheetname "")
		)
		(fill yes
			(thermal_gap 0.5)
			(thermal_bridge_width 0.5)
			(island_removal_mode 0)
		)
		(polygon
			(pts
				(arc
					(start 312.236866 -313.971432)
					(mid 312.251745 -314.007353)
					(end 312.287666 -314.022232)
				)
				(arc
					(start 313.687206 -314.022232)
					(mid 313.723127 -314.007353)
					(end 313.738006 -313.971432)
				)
				(arc
					(start 313.738006 -313.562492)
					(mid 313.723127 -313.526571)
					(end 313.687206 -313.511692)
				)
				(arc
					(start 312.287666 -313.511692)
					(mid 312.251745 -313.526571)
					(end 312.236866 -313.562492)
				)
			)
		)
	)
	(zone
		(layers "In1.Cu" "In2.Cu")
		(hatch none 0.5)
		(connect_pads
			(clearance 0)
		)
		(min_thickness 0.25)
		(keepout
			(tracks not_allowed)
			(vias allowed)
			(pads allowed)
			(copperpour not_allowed)
			(footprints allowed)
		)
		(placement
			(enabled no)
			(sheetname "")
		)
		(fill yes
			(thermal_gap 0.5)
			(thermal_bridge_width 0.5)
			(island_removal_mode 0)
		)
		(polygon
			(pts
				(arc
					(start 41.665398 -259.57149)
					(mid 41.680277 -259.607411)
					(end 41.716198 -259.62229)
				)
				(arc
					(start 43.115738 -259.62229)
					(mid 43.151659 -259.607411)
					(end 43.166538 -259.57149)
				)
				(arc
					(start 43.166538 -259.16255)
					(mid 43.151659 -259.126629)
					(end 43.115738 -259.11175)
				)
				(arc
					(start 41.716198 -259.11175)
					(mid 41.680277 -259.126629)
					(end 41.665398 -259.16255)
				)
			)
		)
	)
	(zone
		(layers "In1.Cu" "In2.Cu")
		(hatch none 0.5)
		(connect_pads
			(clearance 0)
		)
		(min_thickness 0.25)
		(keepout
			(tracks not_allowed)
			(vias allowed)
			(pads allowed)
			(copperpour not_allowed)
			(footprints allowed)
		)
		(placement
			(enabled no)
			(sheetname "")
		)
		(fill yes
			(thermal_gap 0.5)
			(thermal_bridge_width 0.5)
			(island_removal_mode 0)
		)
		(polygon
			(pts
				(arc
					(start 165.60673 -282.521406)
					(mid 165.621609 -282.557327)
					(end 165.65753 -282.572206)
				)
				(arc
					(start 167.05707 -282.572206)
					(mid 167.092991 -282.557327)
					(end 167.10787 -282.521406)
				)
				(arc
					(start 167.10787 -282.112466)
					(mid 167.092991 -282.076545)
					(end 167.05707 -282.061666)
				)
				(arc
					(start 165.65753 -282.061666)
					(mid 165.621609 -282.076545)
					(end 165.60673 -282.112466)
				)
			)
		)
	)
	(zone
		(layers "In1.Cu" "In2.Cu")
		(hatch none 0.5)
		(connect_pads
			(clearance 0)
		)
		(min_thickness 0.25)
		(keepout
			(tracks not_allowed)
			(vias allowed)
			(pads allowed)
			(copperpour not_allowed)
			(footprints allowed)
		)
		(placement
			(enabled no)
			(sheetname "")
		)
		(fill yes
			(thermal_gap 0.5)
			(thermal_bridge_width 0.5)
			(island_removal_mode 0)
		)
		(polygon
			(pts
				(arc
					(start 14.93393 -213.671404)
					(mid 14.948809 -213.707325)
					(end 14.98473 -213.722204)
				)
				(arc
					(start 16.38427 -213.722204)
					(mid 16.420191 -213.707325)
					(end 16.43507 -213.671404)
				)
				(arc
					(start 16.43507 -213.262464)
					(mid 16.420191 -213.226543)
					(end 16.38427 -213.211664)
				)
				(arc
					(start 14.98473 -213.211664)
					(mid 14.948809 -213.226543)
					(end 14.93393 -213.262464)
				)
			)
		)
	)
	(zone
		(layers "In1.Cu" "In2.Cu")
		(hatch none 0.5)
		(connect_pads
			(clearance 0)
		)
		(min_thickness 0.25)
		(keepout
			(tracks not_allowed)
			(vias allowed)
			(pads allowed)
			(copperpour not_allowed)
			(footprints allowed)
		)
		(placement
			(enabled no)
			(sheetname "")
		)
		(fill yes
			(thermal_gap 0.5)
			(thermal_bridge_width 0.5)
			(island_removal_mode 0)
		)
		(polygon
			(pts
				(arc
					(start 447.822066 -222.171514)
					(mid 447.836945 -222.207435)
					(end 447.872866 -222.222314)
				)
				(arc
					(start 449.272406 -222.222314)
					(mid 449.308327 -222.207435)
					(end 449.323206 -222.171514)
				)
				(arc
					(start 449.323206 -221.762574)
					(mid 449.308327 -221.726653)
					(end 449.272406 -221.711774)
				)
				(arc
					(start 447.872866 -221.711774)
					(mid 447.836945 -221.726653)
					(end 447.822066 -221.762574)
				)
			)
		)
	)
	(zone
		(layers "In1.Cu" "In2.Cu")
		(hatch none 0.5)
		(connect_pads
			(clearance 0)
		)
		(min_thickness 0.25)
		(keepout
			(tracks not_allowed)
			(vias allowed)
			(pads allowed)
			(copperpour not_allowed)
			(footprints allowed)
		)
		(placement
			(enabled no)
			(sheetname "")
		)
		(fill yes
			(thermal_gap 0.5)
			(thermal_bridge_width 0.5)
			(island_removal_mode 0)
		)
		(polygon
			(pts
				(arc
					(start 447.822066 -293.571422)
					(mid 447.836945 -293.607343)
					(end 447.872866 -293.622222)
				)
				(arc
					(start 449.272406 -293.622222)
					(mid 449.308327 -293.607343)
					(end 449.323206 -293.571422)
				)
				(arc
					(start 449.323206 -293.162482)
					(mid 449.308327 -293.126561)
					(end 449.272406 -293.111682)
				)
				(arc
					(start 447.872866 -293.111682)
					(mid 447.836945 -293.126561)
					(end 447.822066 -293.162482)
				)
			)
		)
	)
	(zone
		(layers "In1.Cu" "In2.Cu")
		(hatch none 0.5)
		(connect_pads
			(clearance 0)
		)
		(min_thickness 0.25)
		(keepout
			(tracks not_allowed)
			(vias allowed)
			(pads allowed)
			(copperpour not_allowed)
			(footprints allowed)
		)
		(placement
			(enabled no)
			(sheetname "")
		)
		(fill yes
			(thermal_gap 0.5)
			(thermal_bridge_width 0.5)
			(island_removal_mode 0)
		)
		(polygon
			(pts
				(arc
					(start 308.136798 -288.471356)
					(mid 308.151677 -288.507277)
					(end 308.187598 -288.522156)
				)
				(arc
					(start 309.587138 -288.522156)
					(mid 309.623059 -288.507277)
					(end 309.637938 -288.471356)
				)
				(arc
					(start 309.637938 -288.062416)
					(mid 309.623059 -288.026495)
					(end 309.587138 -288.011616)
				)
				(arc
					(start 308.187598 -288.011616)
					(mid 308.151677 -288.026495)
					(end 308.136798 -288.062416)
				)
			)
		)
	)
	(zone
		(layers "In1.Cu" "In2.Cu")
		(hatch none 0.5)
		(connect_pads
			(clearance 0)
		)
		(min_thickness 0.25)
		(keepout
			(tracks not_allowed)
			(vias allowed)
			(pads allowed)
			(copperpour not_allowed)
			(footprints allowed)
		)
		(placement
			(enabled no)
			(sheetname "")
		)
		(fill yes
			(thermal_gap 0.5)
			(thermal_bridge_width 0.5)
			(island_removal_mode 0)
		)
		(polygon
			(pts
				(arc
					(start 312.236866 -240.871502)
					(mid 312.251745 -240.907423)
					(end 312.287666 -240.922302)
				)
				(arc
					(start 313.687206 -240.922302)
					(mid 313.723127 -240.907423)
					(end 313.738006 -240.871502)
				)
				(arc
					(start 313.738006 -240.462562)
					(mid 313.723127 -240.426641)
					(end 313.687206 -240.411762)
				)
				(arc
					(start 312.287666 -240.411762)
					(mid 312.251745 -240.426641)
					(end 312.236866 -240.462562)
				)
			)
		)
	)
	(zone
		(layers "In1.Cu" "In2.Cu")
		(hatch none 0.5)
		(connect_pads
			(clearance 0)
		)
		(min_thickness 0.25)
		(keepout
			(tracks not_allowed)
			(vias allowed)
			(pads allowed)
			(copperpour not_allowed)
			(footprints allowed)
		)
		(placement
			(enabled no)
			(sheetname "")
		)
		(fill yes
			(thermal_gap 0.5)
			(thermal_bridge_width 0.5)
			(island_removal_mode 0)
		)
		(polygon
			(pts
				(arc
					(start 173.15053 -262.971534)
					(mid 173.165409 -263.007455)
					(end 173.20133 -263.022334)
				)
				(arc
					(start 174.60087 -263.022334)
					(mid 174.636791 -263.007455)
					(end 174.65167 -262.971534)
				)
				(arc
					(start 174.65167 -262.562594)
					(mid 174.636791 -262.526673)
					(end 174.60087 -262.511794)
				)
				(arc
					(start 173.20133 -262.511794)
					(mid 173.165409 -262.526673)
					(end 173.15053 -262.562594)
				)
			)
		)
	)
	(zone
		(layers "In1.Cu" "In2.Cu")
		(hatch none 0.5)
		(connect_pads
			(clearance 0)
		)
		(min_thickness 0.25)
		(keepout
			(tracks not_allowed)
			(vias allowed)
			(pads allowed)
			(copperpour not_allowed)
			(footprints allowed)
		)
		(placement
			(enabled no)
			(sheetname "")
		)
		(fill yes
			(thermal_gap 0.5)
			(thermal_bridge_width 0.5)
			(island_removal_mode 0)
		)
		(polygon
			(pts
				(arc
					(start 274.517866 -285.92145)
					(mid 274.532745 -285.957371)
					(end 274.568666 -285.97225)
				)
				(arc
					(start 275.968206 -285.97225)
					(mid 276.004127 -285.957371)
					(end 276.019006 -285.92145)
				)
				(arc
					(start 276.019006 -285.51251)
					(mid 276.004127 -285.476589)
					(end 275.968206 -285.46171)
				)
				(arc
					(start 274.568666 -285.46171)
					(mid 274.532745 -285.476589)
					(end 274.517866 -285.51251)
				)
			)
		)
	)
	(zone
		(layers "In1.Cu" "In2.Cu")
		(hatch none 0.5)
		(connect_pads
			(clearance 0)
		)
		(min_thickness 0.25)
		(keepout
			(tracks not_allowed)
			(vias allowed)
			(pads allowed)
			(copperpour not_allowed)
			(footprints allowed)
		)
		(placement
			(enabled no)
			(sheetname "")
		)
		(fill yes
			(thermal_gap 0.5)
			(thermal_bridge_width 0.5)
			(island_removal_mode 0)
		)
		(polygon
			(pts
				(arc
					(start 440.278266 -296.971466)
					(mid 440.293145 -297.007387)
					(end 440.329066 -297.022266)
				)
				(arc
					(start 441.728606 -297.022266)
					(mid 441.764527 -297.007387)
					(end 441.779406 -296.971466)
				)
				(arc
					(start 441.779406 -296.562526)
					(mid 441.764527 -296.526605)
					(end 441.728606 -296.511726)
				)
				(arc
					(start 440.329066 -296.511726)
					(mid 440.293145 -296.526605)
					(end 440.278266 -296.562526)
				)
			)
		)
	)
	(zone
		(layers "In1.Cu" "In2.Cu")
		(hatch none 0.5)
		(connect_pads
			(clearance 0)
		)
		(min_thickness 0.25)
		(keepout
			(tracks not_allowed)
			(vias allowed)
			(pads allowed)
			(copperpour not_allowed)
			(footprints allowed)
		)
		(placement
			(enabled no)
			(sheetname "")
		)
		(fill yes
			(thermal_gap 0.5)
			(thermal_bridge_width 0.5)
			(island_removal_mode 0)
		)
		(polygon
			(pts
				(arc
					(start 421.090598 -273.171412)
					(mid 421.105477 -273.207333)
					(end 421.141398 -273.222212)
				)
				(arc
					(start 422.540938 -273.222212)
					(mid 422.576859 -273.207333)
					(end 422.591738 -273.171412)
				)
				(arc
					(start 422.591738 -272.762472)
					(mid 422.576859 -272.726551)
					(end 422.540938 -272.711672)
				)
				(arc
					(start 421.141398 -272.711672)
					(mid 421.105477 -272.726551)
					(end 421.090598 -272.762472)
				)
			)
		)
	)
	(zone
		(layers "In1.Cu" "In2.Cu")
		(hatch none 0.5)
		(connect_pads
			(clearance 0)
		)
		(min_thickness 0.25)
		(keepout
			(tracks not_allowed)
			(vias allowed)
			(pads allowed)
			(copperpour not_allowed)
			(footprints allowed)
		)
		(placement
			(enabled no)
			(sheetname "")
		)
		(fill yes
			(thermal_gap 0.5)
			(thermal_bridge_width 0.5)
			(island_removal_mode 0)
		)
		(polygon
			(pts
				(arc
					(start 304.693066 -195.821554)
					(mid 304.707945 -195.857475)
					(end 304.743866 -195.872354)
				)
				(arc
					(start 306.143406 -195.872354)
					(mid 306.179327 -195.857475)
					(end 306.194206 -195.821554)
				)
				(arc
					(start 306.194206 -195.412614)
					(mid 306.179327 -195.376693)
					(end 306.143406 -195.361814)
				)
				(arc
					(start 304.743866 -195.361814)
					(mid 304.707945 -195.376693)
					(end 304.693066 -195.412614)
				)
			)
		)
	)
	(zone
		(layers "In1.Cu" "In2.Cu")
		(hatch none 0.5)
		(connect_pads
			(clearance 0)
		)
		(min_thickness 0.25)
		(keepout
			(tracks not_allowed)
			(vias allowed)
			(pads allowed)
			(copperpour not_allowed)
			(footprints allowed)
		)
		(placement
			(enabled no)
			(sheetname "")
		)
		(fill yes
			(thermal_gap 0.5)
			(thermal_bridge_width 0.5)
			(island_removal_mode 0)
		)
		(polygon
			(pts
				(arc
					(start 406.002998 -211.971382)
					(mid 406.017877 -212.007303)
					(end 406.053798 -212.022182)
				)
				(arc
					(start 407.453338 -212.022182)
					(mid 407.489259 -212.007303)
					(end 407.504138 -211.971382)
				)
				(arc
					(start 407.504138 -211.562442)
					(mid 407.489259 -211.526521)
					(end 407.453338 -211.511642)
				)
				(arc
					(start 406.053798 -211.511642)
					(mid 406.017877 -211.526521)
					(end 406.002998 -211.562442)
				)
			)
		)
	)
	(zone
		(layers "In1.Cu" "In2.Cu")
		(hatch none 0.5)
		(connect_pads
			(clearance 0)
		)
		(min_thickness 0.25)
		(keepout
			(tracks not_allowed)
			(vias allowed)
			(pads allowed)
			(copperpour not_allowed)
			(footprints allowed)
		)
		(placement
			(enabled no)
			(sheetname "")
		)
		(fill yes
			(thermal_gap 0.5)
			(thermal_bridge_width 0.5)
			(island_removal_mode 0)
		)
		(polygon
			(pts
				(arc
					(start 30.02153 -310.571388)
					(mid 30.036409 -310.607309)
					(end 30.07233 -310.622188)
				)
				(arc
					(start 31.47187 -310.622188)
					(mid 31.507791 -310.607309)
					(end 31.52267 -310.571388)
				)
				(arc
					(start 31.52267 -310.162448)
					(mid 31.507791 -310.126527)
					(end 31.47187 -310.111648)
				)
				(arc
					(start 30.07233 -310.111648)
					(mid 30.036409 -310.126527)
					(end 30.02153 -310.162448)
				)
			)
		)
	)
	(zone
		(layers "In1.Cu" "In2.Cu")
		(hatch none 0.5)
		(connect_pads
			(clearance 0)
		)
		(min_thickness 0.25)
		(keepout
			(tracks not_allowed)
			(vias allowed)
			(pads allowed)
			(copperpour not_allowed)
			(footprints allowed)
		)
		(placement
			(enabled no)
			(sheetname "")
		)
		(fill yes
			(thermal_gap 0.5)
			(thermal_bridge_width 0.5)
			(island_removal_mode 0)
		)
		(polygon
			(pts
				(arc
					(start 14.93393 -238.321342)
					(mid 14.948809 -238.357263)
					(end 14.98473 -238.372142)
				)
				(arc
					(start 16.38427 -238.372142)
					(mid 16.420191 -238.357263)
					(end 16.43507 -238.321342)
				)
				(arc
					(start 16.43507 -237.912402)
					(mid 16.420191 -237.876481)
					(end 16.38427 -237.861602)
				)
				(arc
					(start 14.98473 -237.861602)
					(mid 14.948809 -237.876481)
					(end 14.93393 -237.912402)
				)
			)
		)
	)
	(zone
		(layers "In1.Cu" "In2.Cu")
		(hatch none 0.5)
		(connect_pads
			(clearance 0)
		)
		(min_thickness 0.25)
		(keepout
			(tracks not_allowed)
			(vias allowed)
			(pads allowed)
			(copperpour not_allowed)
			(footprints allowed)
		)
		(placement
			(enabled no)
			(sheetname "")
		)
		(fill yes
			(thermal_gap 0.5)
			(thermal_bridge_width 0.5)
			(island_removal_mode 0)
		)
		(polygon
			(pts
				(arc
					(start 277.961598 -302.921416)
					(mid 277.976477 -302.957337)
					(end 278.012398 -302.972216)
				)
				(arc
					(start 279.411938 -302.972216)
					(mid 279.447859 -302.957337)
					(end 279.462738 -302.921416)
				)
				(arc
					(start 279.462738 -302.512476)
					(mid 279.447859 -302.476555)
					(end 279.411938 -302.461676)
				)
				(arc
					(start 278.012398 -302.461676)
					(mid 277.976477 -302.476555)
					(end 277.961598 -302.512476)
				)
			)
		)
	)
	(zone
		(layers "In1.Cu" "In2.Cu")
		(hatch none 0.5)
		(connect_pads
			(clearance 0)
		)
		(min_thickness 0.25)
		(keepout
			(tracks not_allowed)
			(vias allowed)
			(pads allowed)
			(copperpour not_allowed)
			(footprints allowed)
		)
		(placement
			(enabled no)
			(sheetname "")
		)
		(fill yes
			(thermal_gap 0.5)
			(thermal_bridge_width 0.5)
			(island_removal_mode 0)
		)
		(polygon
			(pts
				(arc
					(start 180.69433 -200.071482)
					(mid 180.709209 -200.107403)
					(end 180.74513 -200.122282)
				)
				(arc
					(start 182.14467 -200.122282)
					(mid 182.180591 -200.107403)
					(end 182.19547 -200.071482)
				)
				(arc
					(start 182.19547 -199.662542)
					(mid 182.180591 -199.626621)
					(end 182.14467 -199.611742)
				)
				(arc
					(start 180.74513 -199.611742)
					(mid 180.709209 -199.626621)
					(end 180.69433 -199.662542)
				)
			)
		)
	)
	(zone
		(layers "In1.Cu" "In2.Cu")
		(hatch none 0.5)
		(connect_pads
			(clearance 0)
		)
		(min_thickness 0.25)
		(keepout
			(tracks not_allowed)
			(vias allowed)
			(pads allowed)
			(copperpour not_allowed)
			(footprints allowed)
		)
		(placement
			(enabled no)
			(sheetname "")
		)
		(fill yes
			(thermal_gap 0.5)
			(thermal_bridge_width 0.5)
			(island_removal_mode 0)
		)
		(polygon
			(pts
				(arc
					(start 270.417798 -286.771334)
					(mid 270.432677 -286.807255)
					(end 270.468598 -286.822134)
				)
				(arc
					(start 271.868138 -286.822134)
					(mid 271.904059 -286.807255)
					(end 271.918938 -286.771334)
				)
				(arc
					(start 271.918938 -286.362394)
					(mid 271.904059 -286.326473)
					(end 271.868138 -286.311594)
				)
				(arc
					(start 270.468598 -286.311594)
					(mid 270.432677 -286.326473)
					(end 270.417798 -286.362394)
				)
			)
		)
	)
	(zone
		(layers "In1.Cu" "In2.Cu")
		(hatch none 0.5)
		(connect_pads
			(clearance 0)
		)
		(min_thickness 0.25)
		(keepout
			(tracks not_allowed)
			(vias allowed)
			(pads allowed)
			(copperpour not_allowed)
			(footprints allowed)
		)
		(placement
			(enabled no)
			(sheetname "")
		)
		(fill yes
			(thermal_gap 0.5)
			(thermal_bridge_width 0.5)
			(island_removal_mode 0)
		)
		(polygon
			(pts
				(arc
					(start 22.47773 -280.821384)
					(mid 22.492609 -280.857305)
					(end 22.52853 -280.872184)
				)
				(arc
					(start 23.92807 -280.872184)
					(mid 23.963991 -280.857305)
					(end 23.97887 -280.821384)
				)
				(arc
					(start 23.97887 -280.412444)
					(mid 23.963991 -280.376523)
					(end 23.92807 -280.361644)
				)
				(arc
					(start 22.52853 -280.361644)
					(mid 22.492609 -280.376523)
					(end 22.47773 -280.412444)
				)
			)
		)
	)
	(zone
		(layers "In1.Cu" "In2.Cu")
		(hatch none 0.5)
		(connect_pads
			(clearance 0)
		)
		(min_thickness 0.25)
		(keepout
			(tracks not_allowed)
			(vias allowed)
			(pads allowed)
			(copperpour not_allowed)
			(footprints allowed)
		)
		(placement
			(enabled no)
			(sheetname "")
		)
		(fill yes
			(thermal_gap 0.5)
			(thermal_bridge_width 0.5)
			(island_removal_mode 0)
		)
		(polygon
			(pts
				(arc
					(start 282.061666 -211.121498)
					(mid 282.076545 -211.157419)
					(end 282.112466 -211.172298)
				)
				(arc
					(start 283.512006 -211.172298)
					(mid 283.547927 -211.157419)
					(end 283.562806 -211.121498)
				)
				(arc
					(start 283.562806 -210.712558)
					(mid 283.547927 -210.676637)
					(end 283.512006 -210.661758)
				)
				(arc
					(start 282.112466 -210.661758)
					(mid 282.076545 -210.676637)
					(end 282.061666 -210.712558)
				)
			)
		)
	)
	(zone
		(layers "In1.Cu" "In2.Cu")
		(hatch none 0.5)
		(connect_pads
			(clearance 0)
		)
		(min_thickness 0.25)
		(keepout
			(tracks not_allowed)
			(vias allowed)
			(pads allowed)
			(copperpour not_allowed)
			(footprints allowed)
		)
		(placement
			(enabled no)
			(sheetname "")
		)
		(fill yes
			(thermal_gap 0.5)
			(thermal_bridge_width 0.5)
			(island_removal_mode 0)
		)
		(polygon
			(pts
				(arc
					(start 289.605466 -270.621506)
					(mid 289.620345 -270.657427)
					(end 289.656266 -270.672306)
				)
				(arc
					(start 291.055806 -270.672306)
					(mid 291.091727 -270.657427)
					(end 291.106606 -270.621506)
				)
				(arc
					(start 291.106606 -270.212566)
					(mid 291.091727 -270.176645)
					(end 291.055806 -270.161766)
				)
				(arc
					(start 289.656266 -270.161766)
					(mid 289.620345 -270.176645)
					(end 289.605466 -270.212566)
				)
			)
		)
	)
	(zone
		(layers "In1.Cu" "In2.Cu")
		(hatch none 0.5)
		(connect_pads
			(clearance 0)
		)
		(min_thickness 0.25)
		(keepout
			(tracks not_allowed)
			(vias allowed)
			(pads allowed)
			(copperpour not_allowed)
			(footprints allowed)
		)
		(placement
			(enabled no)
			(sheetname "")
		)
		(fill yes
			(thermal_gap 0.5)
			(thermal_bridge_width 0.5)
			(island_removal_mode 0)
		)
		(polygon
			(pts
				(arc
					(start 458.809598 -316.521338)
					(mid 458.824477 -316.557259)
					(end 458.860398 -316.572138)
				)
				(arc
					(start 460.259938 -316.572138)
					(mid 460.295859 -316.557259)
					(end 460.310738 -316.521338)
				)
				(arc
					(start 460.310738 -316.112398)
					(mid 460.295859 -316.076477)
					(end 460.259938 -316.061598)
				)
				(arc
					(start 458.860398 -316.061598)
					(mid 458.824477 -316.076477)
					(end 458.809598 -316.112398)
				)
			)
		)
	)
	(zone
		(layers "In1.Cu" "In2.Cu")
		(hatch none 0.5)
		(connect_pads
			(clearance 0)
		)
		(min_thickness 0.25)
		(keepout
			(tracks not_allowed)
			(vias allowed)
			(pads allowed)
			(copperpour not_allowed)
			(footprints allowed)
		)
		(placement
			(enabled no)
			(sheetname "")
		)
		(fill yes
			(thermal_gap 0.5)
			(thermal_bridge_width 0.5)
			(island_removal_mode 0)
		)
		(polygon
			(pts
				(arc
					(start 432.734466 -250.221496)
					(mid 432.749345 -250.257417)
					(end 432.785266 -250.272296)
				)
				(arc
					(start 434.184806 -250.272296)
					(mid 434.220727 -250.257417)
					(end 434.235606 -250.221496)
				)
				(arc
					(start 434.235606 -249.812556)
					(mid 434.220727 -249.776635)
					(end 434.184806 -249.761756)
				)
				(arc
					(start 432.785266 -249.761756)
					(mid 432.749345 -249.776635)
					(end 432.734466 -249.812556)
				)
			)
		)
	)
	(zone
		(layers "In1.Cu" "In2.Cu")
		(hatch none 0.5)
		(connect_pads
			(clearance 0)
		)
		(min_thickness 0.25)
		(keepout
			(tracks not_allowed)
			(vias allowed)
			(pads allowed)
			(copperpour not_allowed)
			(footprints allowed)
		)
		(placement
			(enabled no)
			(sheetname "")
		)
		(fill yes
			(thermal_gap 0.5)
			(thermal_bridge_width 0.5)
			(island_removal_mode 0)
		)
		(polygon
			(pts
				(arc
					(start 410.103066 -267.221462)
					(mid 410.117945 -267.257383)
					(end 410.153866 -267.272262)
				)
				(arc
					(start 411.553406 -267.272262)
					(mid 411.589327 -267.257383)
					(end 411.604206 -267.221462)
				)
				(arc
					(start 411.604206 -266.812522)
					(mid 411.589327 -266.776601)
					(end 411.553406 -266.761722)
				)
				(arc
					(start 410.153866 -266.761722)
					(mid 410.117945 -266.776601)
					(end 410.103066 -266.812522)
				)
			)
		)
	)
	(zone
		(layers "In1.Cu" "In2.Cu")
		(hatch none 0.5)
		(connect_pads
			(clearance 0)
		)
		(min_thickness 0.25)
		(keepout
			(tracks not_allowed)
			(vias allowed)
			(pads allowed)
			(copperpour not_allowed)
			(footprints allowed)
		)
		(placement
			(enabled no)
			(sheetname "")
		)
		(fill yes
			(thermal_gap 0.5)
			(thermal_bridge_width 0.5)
			(island_removal_mode 0)
		)
		(polygon
			(pts
				(arc
					(start 462.909666 -292.721538)
					(mid 462.924545 -292.757459)
					(end 462.960466 -292.772338)
				)
				(arc
					(start 464.360006 -292.772338)
					(mid 464.395927 -292.757459)
					(end 464.410806 -292.721538)
				)
				(arc
					(start 464.410806 -292.312598)
					(mid 464.395927 -292.276677)
					(end 464.360006 -292.261798)
				)
				(arc
					(start 462.960466 -292.261798)
					(mid 462.924545 -292.276677)
					(end 462.909666 -292.312598)
				)
			)
		)
	)
	(zone
		(layers "In1.Cu" "In2.Cu")
		(hatch none 0.5)
		(connect_pads
			(clearance 0)
		)
		(min_thickness 0.25)
		(keepout
			(tracks not_allowed)
			(vias allowed)
			(pads allowed)
			(copperpour not_allowed)
			(footprints allowed)
		)
		(placement
			(enabled no)
			(sheetname "")
		)
		(fill yes
			(thermal_gap 0.5)
			(thermal_bridge_width 0.5)
			(island_removal_mode 0)
		)
		(polygon
			(pts
				(arc
					(start 26.577798 -276.571456)
					(mid 26.592677 -276.607377)
					(end 26.628598 -276.622256)
				)
				(arc
					(start 28.028138 -276.622256)
					(mid 28.064059 -276.607377)
					(end 28.078938 -276.571456)
				)
				(arc
					(start 28.078938 -276.162516)
					(mid 28.064059 -276.126595)
					(end 28.028138 -276.111716)
				)
				(arc
					(start 26.628598 -276.111716)
					(mid 26.592677 -276.126595)
					(end 26.577798 -276.162516)
				)
			)
		)
	)
	(zone
		(layers "In1.Cu" "In2.Cu")
		(hatch none 0.5)
		(connect_pads
			(clearance 0)
		)
		(min_thickness 0.25)
		(keepout
			(tracks not_allowed)
			(vias allowed)
			(pads allowed)
			(copperpour not_allowed)
			(footprints allowed)
		)
		(placement
			(enabled no)
			(sheetname "")
		)
		(fill yes
			(thermal_gap 0.5)
			(thermal_bridge_width 0.5)
			(island_removal_mode 0)
		)
		(polygon
			(pts
				(arc
					(start 421.090598 -310.571388)
					(mid 421.105477 -310.607309)
					(end 421.141398 -310.622188)
				)
				(arc
					(start 422.540938 -310.622188)
					(mid 422.576859 -310.607309)
					(end 422.591738 -310.571388)
				)
				(arc
					(start 422.591738 -310.162448)
					(mid 422.576859 -310.126527)
					(end 422.540938 -310.111648)
				)
				(arc
					(start 421.141398 -310.111648)
					(mid 421.105477 -310.126527)
					(end 421.090598 -310.162448)
				)
			)
		)
	)
	(zone
		(layers "In1.Cu" "In2.Cu")
		(hatch none 0.5)
		(connect_pads
			(clearance 0)
		)
		(min_thickness 0.25)
		(keepout
			(tracks not_allowed)
			(vias allowed)
			(pads allowed)
			(copperpour not_allowed)
			(footprints allowed)
		)
		(placement
			(enabled no)
			(sheetname "")
		)
		(fill yes
			(thermal_gap 0.5)
			(thermal_bridge_width 0.5)
			(island_removal_mode 0)
		)
		(polygon
			(pts
				(arc
					(start 210.86953 -211.971382)
					(mid 210.884409 -212.007303)
					(end 210.92033 -212.022182)
				)
				(arc
					(start 212.31987 -212.022182)
					(mid 212.355791 -212.007303)
					(end 212.37067 -211.971382)
				)
				(arc
					(start 212.37067 -211.562442)
					(mid 212.355791 -211.526521)
					(end 212.31987 -211.511642)
				)
				(arc
					(start 210.92033 -211.511642)
					(mid 210.884409 -211.526521)
					(end 210.86953 -211.562442)
				)
			)
		)
	)
	(zone
		(layers "In1.Cu" "In2.Cu")
		(hatch none 0.5)
		(connect_pads
			(clearance 0)
		)
		(min_thickness 0.25)
		(keepout
			(tracks not_allowed)
			(vias allowed)
			(pads allowed)
			(copperpour not_allowed)
			(footprints allowed)
		)
		(placement
			(enabled no)
			(sheetname "")
		)
		(fill yes
			(thermal_gap 0.5)
			(thermal_bridge_width 0.5)
			(island_removal_mode 0)
		)
		(polygon
			(pts
				(arc
					(start 436.178198 -302.921416)
					(mid 436.193077 -302.957337)
					(end 436.228998 -302.972216)
				)
				(arc
					(start 437.628538 -302.972216)
					(mid 437.664459 -302.957337)
					(end 437.679338 -302.921416)
				)
				(arc
					(start 437.679338 -302.512476)
					(mid 437.664459 -302.476555)
					(end 437.628538 -302.461676)
				)
				(arc
					(start 436.228998 -302.461676)
					(mid 436.193077 -302.476555)
					(end 436.178198 -302.512476)
				)
			)
		)
	)
	(zone
		(layers "In1.Cu" "In2.Cu")
		(hatch none 0.5)
		(connect_pads
			(clearance 0)
		)
		(min_thickness 0.25)
		(keepout
			(tracks not_allowed)
			(vias allowed)
			(pads allowed)
			(copperpour not_allowed)
			(footprints allowed)
		)
		(placement
			(enabled no)
			(sheetname "")
		)
		(fill yes
			(thermal_gap 0.5)
			(thermal_bridge_width 0.5)
			(island_removal_mode 0)
		)
		(polygon
			(pts
				(arc
					(start 428.634398 -288.471356)
					(mid 428.649277 -288.507277)
					(end 428.685198 -288.522156)
				)
				(arc
					(start 430.084738 -288.522156)
					(mid 430.120659 -288.507277)
					(end 430.135538 -288.471356)
				)
				(arc
					(start 430.135538 -288.062416)
					(mid 430.120659 -288.026495)
					(end 430.084738 -288.011616)
				)
				(arc
					(start 428.685198 -288.011616)
					(mid 428.649277 -288.026495)
					(end 428.634398 -288.062416)
				)
			)
		)
	)
	(zone
		(layers "In1.Cu" "In2.Cu")
		(hatch none 0.5)
		(connect_pads
			(clearance 0)
		)
		(min_thickness 0.25)
		(keepout
			(tracks not_allowed)
			(vias allowed)
			(pads allowed)
			(copperpour not_allowed)
			(footprints allowed)
		)
		(placement
			(enabled no)
			(sheetname "")
		)
		(fill yes
			(thermal_gap 0.5)
			(thermal_bridge_width 0.5)
			(island_removal_mode 0)
		)
		(polygon
			(pts
				(arc
					(start 293.049198 -245.971314)
					(mid 293.064077 -246.007235)
					(end 293.099998 -246.022114)
				)
				(arc
					(start 294.499538 -246.022114)
					(mid 294.535459 -246.007235)
					(end 294.550338 -245.971314)
				)
				(arc
					(start 294.550338 -245.562374)
					(mid 294.535459 -245.526453)
					(end 294.499538 -245.511574)
				)
				(arc
					(start 293.099998 -245.511574)
					(mid 293.064077 -245.526453)
					(end 293.049198 -245.562374)
				)
			)
		)
	)
	(zone
		(layers "In1.Cu" "In2.Cu")
		(hatch none 0.5)
		(connect_pads
			(clearance 0)
		)
		(min_thickness 0.25)
		(keepout
			(tracks not_allowed)
			(vias allowed)
			(pads allowed)
			(copperpour not_allowed)
			(footprints allowed)
		)
		(placement
			(enabled no)
			(sheetname "")
		)
		(fill yes
			(thermal_gap 0.5)
			(thermal_bridge_width 0.5)
			(island_removal_mode 0)
		)
		(polygon
			(pts
				(arc
					(start 22.47773 -262.971534)
					(mid 22.492609 -263.007455)
					(end 22.52853 -263.022334)
				)
				(arc
					(start 23.92807 -263.022334)
					(mid 23.963991 -263.007455)
					(end 23.97887 -262.971534)
				)
				(arc
					(start 23.97887 -262.562594)
					(mid 23.963991 -262.526673)
					(end 23.92807 -262.511794)
				)
				(arc
					(start 22.52853 -262.511794)
					(mid 22.492609 -262.526673)
					(end 22.47773 -262.562594)
				)
			)
		)
	)
	(zone
		(layers "In1.Cu" "In2.Cu")
		(hatch none 0.5)
		(connect_pads
			(clearance 0)
		)
		(min_thickness 0.25)
		(keepout
			(tracks not_allowed)
			(vias allowed)
			(pads allowed)
			(copperpour not_allowed)
			(footprints allowed)
		)
		(placement
			(enabled no)
			(sheetname "")
		)
		(fill yes
			(thermal_gap 0.5)
			(thermal_bridge_width 0.5)
			(island_removal_mode 0)
		)
		(polygon
			(pts
				(arc
					(start 165.60673 -210.27136)
					(mid 165.621609 -210.307281)
					(end 165.65753 -210.32216)
				)
				(arc
					(start 167.05707 -210.32216)
					(mid 167.092991 -210.307281)
					(end 167.10787 -210.27136)
				)
				(arc
					(start 167.10787 -209.86242)
					(mid 167.092991 -209.826499)
					(end 167.05707 -209.81162)
				)
				(arc
					(start 165.65753 -209.81162)
					(mid 165.621609 -209.826499)
					(end 165.60673 -209.86242)
				)
			)
		)
	)
	(zone
		(layers "In1.Cu" "In2.Cu")
		(hatch none 0.5)
		(connect_pads
			(clearance 0)
		)
		(min_thickness 0.25)
		(keepout
			(tracks not_allowed)
			(vias allowed)
			(pads allowed)
			(copperpour not_allowed)
			(footprints allowed)
		)
		(placement
			(enabled no)
			(sheetname "")
		)
		(fill yes
			(thermal_gap 0.5)
			(thermal_bridge_width 0.5)
			(island_removal_mode 0)
		)
		(polygon
			(pts
				(arc
					(start 308.136798 -226.421442)
					(mid 308.151677 -226.457363)
					(end 308.187598 -226.472242)
				)
				(arc
					(start 309.587138 -226.472242)
					(mid 309.623059 -226.457363)
					(end 309.637938 -226.421442)
				)
				(arc
					(start 309.637938 -226.012502)
					(mid 309.623059 -225.976581)
					(end 309.587138 -225.961702)
				)
				(arc
					(start 308.187598 -225.961702)
					(mid 308.151677 -225.976581)
					(end 308.136798 -226.012502)
				)
			)
		)
	)
	(zone
		(layers "In1.Cu" "In2.Cu")
		(hatch none 0.5)
		(connect_pads
			(clearance 0)
		)
		(min_thickness 0.25)
		(keepout
			(tracks not_allowed)
			(vias allowed)
			(pads allowed)
			(copperpour not_allowed)
			(footprints allowed)
		)
		(placement
			(enabled no)
			(sheetname "")
		)
		(fill yes
			(thermal_gap 0.5)
			(thermal_bridge_width 0.5)
			(island_removal_mode 0)
		)
		(polygon
			(pts
				(arc
					(start 266.974066 -274.871434)
					(mid 266.988945 -274.907355)
					(end 267.024866 -274.922234)
				)
				(arc
					(start 268.424406 -274.922234)
					(mid 268.460327 -274.907355)
					(end 268.475206 -274.871434)
				)
				(arc
					(start 268.475206 -274.462494)
					(mid 268.460327 -274.426573)
					(end 268.424406 -274.411694)
				)
				(arc
					(start 267.024866 -274.411694)
					(mid 266.988945 -274.426573)
					(end 266.974066 -274.462494)
				)
			)
		)
	)
	(zone
		(layers "In1.Cu" "In2.Cu")
		(hatch none 0.5)
		(connect_pads
			(clearance 0)
		)
		(min_thickness 0.25)
		(keepout
			(tracks not_allowed)
			(vias allowed)
			(pads allowed)
			(copperpour not_allowed)
			(footprints allowed)
		)
		(placement
			(enabled no)
			(sheetname "")
		)
		(fill yes
			(thermal_gap 0.5)
			(thermal_bridge_width 0.5)
			(island_removal_mode 0)
		)
		(polygon
			(pts
				(arc
					(start 34.121598 -268.921484)
					(mid 34.136477 -268.957405)
					(end 34.172398 -268.972284)
				)
				(arc
					(start 35.571938 -268.972284)
					(mid 35.607859 -268.957405)
					(end 35.622738 -268.921484)
				)
				(arc
					(start 35.622738 -268.512544)
					(mid 35.607859 -268.476623)
					(end 35.571938 -268.461744)
				)
				(arc
					(start 34.172398 -268.461744)
					(mid 34.136477 -268.476623)
					(end 34.121598 -268.512544)
				)
			)
		)
	)
	(zone
		(layers "In1.Cu" "In2.Cu")
		(hatch none 0.5)
		(connect_pads
			(clearance 0)
		)
		(min_thickness 0.25)
		(keepout
			(tracks not_allowed)
			(vias allowed)
			(pads allowed)
			(copperpour not_allowed)
			(footprints allowed)
		)
		(placement
			(enabled no)
			(sheetname "")
		)
		(fill yes
			(thermal_gap 0.5)
			(thermal_bridge_width 0.5)
			(island_removal_mode 0)
		)
		(polygon
			(pts
				(arc
					(start 447.822066 -217.921332)
					(mid 447.836945 -217.957253)
					(end 447.872866 -217.972132)
				)
				(arc
					(start 449.272406 -217.972132)
					(mid 449.308327 -217.957253)
					(end 449.323206 -217.921332)
				)
				(arc
					(start 449.323206 -217.512392)
					(mid 449.308327 -217.476471)
					(end 449.272406 -217.461592)
				)
				(arc
					(start 447.872866 -217.461592)
					(mid 447.836945 -217.476471)
					(end 447.822066 -217.512392)
				)
			)
		)
	)
	(zone
		(layers "In1.Cu" "In2.Cu")
		(hatch none 0.5)
		(connect_pads
			(clearance 0)
		)
		(min_thickness 0.25)
		(keepout
			(tracks not_allowed)
			(vias allowed)
			(pads allowed)
			(copperpour not_allowed)
			(footprints allowed)
		)
		(placement
			(enabled no)
			(sheetname "")
		)
		(fill yes
			(thermal_gap 0.5)
			(thermal_bridge_width 0.5)
			(island_removal_mode 0)
		)
		(polygon
			(pts
				(arc
					(start 37.56533 -251.07138)
					(mid 37.580209 -251.107301)
					(end 37.61613 -251.12218)
				)
				(arc
					(start 39.01567 -251.12218)
					(mid 39.051591 -251.107301)
					(end 39.06647 -251.07138)
				)
				(arc
					(start 39.06647 -250.66244)
					(mid 39.051591 -250.626519)
					(end 39.01567 -250.61164)
				)
				(arc
					(start 37.61613 -250.61164)
					(mid 37.580209 -250.626519)
					(end 37.56533 -250.66244)
				)
			)
		)
	)
	(zone
		(layers "In1.Cu" "In2.Cu")
		(hatch none 0.5)
		(connect_pads
			(clearance 0)
		)
		(min_thickness 0.25)
		(keepout
			(tracks not_allowed)
			(vias allowed)
			(pads allowed)
			(copperpour not_allowed)
			(footprints allowed)
		)
		(placement
			(enabled no)
			(sheetname "")
		)
		(fill yes
			(thermal_gap 0.5)
			(thermal_bridge_width 0.5)
			(island_removal_mode 0)
		)
		(polygon
			(pts
				(arc
					(start 417.646866 -292.721538)
					(mid 417.661745 -292.757459)
					(end 417.697666 -292.772338)
				)
				(arc
					(start 419.097206 -292.772338)
					(mid 419.133127 -292.757459)
					(end 419.148006 -292.721538)
				)
				(arc
					(start 419.148006 -292.312598)
					(mid 419.133127 -292.276677)
					(end 419.097206 -292.261798)
				)
				(arc
					(start 417.697666 -292.261798)
					(mid 417.661745 -292.276677)
					(end 417.646866 -292.312598)
				)
			)
		)
	)
	(zone
		(layers "In1.Cu" "In2.Cu")
		(hatch none 0.5)
		(connect_pads
			(clearance 0)
		)
		(min_thickness 0.25)
		(keepout
			(tracks not_allowed)
			(vias allowed)
			(pads allowed)
			(copperpour not_allowed)
			(footprints allowed)
		)
		(placement
			(enabled no)
			(sheetname "")
		)
		(fill yes
			(thermal_gap 0.5)
			(thermal_bridge_width 0.5)
			(island_removal_mode 0)
		)
		(polygon
			(pts
				(arc
					(start 64.296798 -231.521508)
					(mid 64.311677 -231.557429)
					(end 64.347598 -231.572308)
				)
				(arc
					(start 65.747138 -231.572308)
					(mid 65.783059 -231.557429)
					(end 65.797938 -231.521508)
				)
				(arc
					(start 65.797938 -231.112568)
					(mid 65.783059 -231.076647)
					(end 65.747138 -231.061768)
				)
				(arc
					(start 64.347598 -231.061768)
					(mid 64.311677 -231.076647)
					(end 64.296798 -231.112568)
				)
			)
		)
	)
	(zone
		(layers "In1.Cu" "In2.Cu")
		(hatch none 0.5)
		(connect_pads
			(clearance 0)
		)
		(min_thickness 0.25)
		(keepout
			(tracks not_allowed)
			(vias allowed)
			(pads allowed)
			(copperpour not_allowed)
			(footprints allowed)
		)
		(placement
			(enabled no)
			(sheetname "")
		)
		(fill yes
			(thermal_gap 0.5)
			(thermal_bridge_width 0.5)
			(island_removal_mode 0)
		)
		(polygon
			(pts
				(arc
					(start 203.32573 -273.171412)
					(mid 203.340609 -273.207333)
					(end 203.37653 -273.222212)
				)
				(arc
					(start 204.77607 -273.222212)
					(mid 204.811991 -273.207333)
					(end 204.82687 -273.171412)
				)
				(arc
					(start 204.82687 -272.762472)
					(mid 204.811991 -272.726551)
					(end 204.77607 -272.711672)
				)
				(arc
					(start 203.37653 -272.711672)
					(mid 203.340609 -272.726551)
					(end 203.32573 -272.762472)
				)
			)
		)
	)
	(zone
		(layers "In1.Cu" "In2.Cu")
		(hatch none 0.5)
		(connect_pads
			(clearance 0)
		)
		(min_thickness 0.25)
		(keepout
			(tracks not_allowed)
			(vias allowed)
			(pads allowed)
			(copperpour not_allowed)
			(footprints allowed)
		)
		(placement
			(enabled no)
			(sheetname "")
		)
		(fill yes
			(thermal_gap 0.5)
			(thermal_bridge_width 0.5)
			(island_removal_mode 0)
		)
		(polygon
			(pts
				(arc
					(start 180.69433 -209.421476)
					(mid 180.709209 -209.457397)
					(end 180.74513 -209.472276)
				)
				(arc
					(start 182.14467 -209.472276)
					(mid 182.180591 -209.457397)
					(end 182.19547 -209.421476)
				)
				(arc
					(start 182.19547 -209.012536)
					(mid 182.180591 -208.976615)
					(end 182.14467 -208.961736)
				)
				(arc
					(start 180.74513 -208.961736)
					(mid 180.709209 -208.976615)
					(end 180.69433 -209.012536)
				)
			)
		)
	)
	(zone
		(layers "In1.Cu" "In2.Cu")
		(hatch none 0.5)
		(connect_pads
			(clearance 0)
		)
		(min_thickness 0.25)
		(keepout
			(tracks not_allowed)
			(vias allowed)
			(pads allowed)
			(copperpour not_allowed)
			(footprints allowed)
		)
		(placement
			(enabled no)
			(sheetname "")
		)
		(fill yes
			(thermal_gap 0.5)
			(thermal_bridge_width 0.5)
			(island_removal_mode 0)
		)
		(polygon
			(pts
				(arc
					(start 447.822066 -214.521542)
					(mid 447.836945 -214.557463)
					(end 447.872866 -214.572342)
				)
				(arc
					(start 449.272406 -214.572342)
					(mid 449.308327 -214.557463)
					(end 449.323206 -214.521542)
				)
				(arc
					(start 449.323206 -214.112602)
					(mid 449.308327 -214.076681)
					(end 449.272406 -214.061802)
				)
				(arc
					(start 447.872866 -214.061802)
					(mid 447.836945 -214.076681)
					(end 447.822066 -214.112602)
				)
			)
		)
	)
	(zone
		(layers "In1.Cu" "In2.Cu")
		(hatch none 0.5)
		(connect_pads
			(clearance 0)
		)
		(min_thickness 0.25)
		(keepout
			(tracks not_allowed)
			(vias allowed)
			(pads allowed)
			(copperpour not_allowed)
			(footprints allowed)
		)
		(placement
			(enabled no)
			(sheetname "")
		)
		(fill yes
			(thermal_gap 0.5)
			(thermal_bridge_width 0.5)
			(island_removal_mode 0)
		)
		(polygon
			(pts
				(arc
					(start 37.56533 -245.971314)
					(mid 37.580209 -246.007235)
					(end 37.61613 -246.022114)
				)
				(arc
					(start 39.01567 -246.022114)
					(mid 39.051591 -246.007235)
					(end 39.06647 -245.971314)
				)
				(arc
					(start 39.06647 -245.562374)
					(mid 39.051591 -245.526453)
					(end 39.01567 -245.511574)
				)
				(arc
					(start 37.61613 -245.511574)
					(mid 37.580209 -245.526453)
					(end 37.56533 -245.562374)
				)
			)
		)
	)
	(zone
		(layers "In1.Cu" "In2.Cu")
		(hatch none 0.5)
		(connect_pads
			(clearance 0)
		)
		(min_thickness 0.25)
		(keepout
			(tracks not_allowed)
			(vias allowed)
			(pads allowed)
			(copperpour not_allowed)
			(footprints allowed)
		)
		(placement
			(enabled no)
			(sheetname "")
		)
		(fill yes
			(thermal_gap 0.5)
			(thermal_bridge_width 0.5)
			(island_removal_mode 0)
		)
		(polygon
			(pts
				(arc
					(start 270.417798 -280.821384)
					(mid 270.432677 -280.857305)
					(end 270.468598 -280.872184)
				)
				(arc
					(start 271.868138 -280.872184)
					(mid 271.904059 -280.857305)
					(end 271.918938 -280.821384)
				)
				(arc
					(start 271.918938 -280.412444)
					(mid 271.904059 -280.376523)
					(end 271.868138 -280.361644)
				)
				(arc
					(start 270.468598 -280.361644)
					(mid 270.432677 -280.376523)
					(end 270.417798 -280.412444)
				)
			)
		)
	)
	(zone
		(layers "In1.Cu" "In2.Cu")
		(hatch none 0.5)
		(connect_pads
			(clearance 0)
		)
		(min_thickness 0.25)
		(keepout
			(tracks not_allowed)
			(vias allowed)
			(pads allowed)
			(copperpour not_allowed)
			(footprints allowed)
		)
		(placement
			(enabled no)
			(sheetname "")
		)
		(fill yes
			(thermal_gap 0.5)
			(thermal_bridge_width 0.5)
			(island_removal_mode 0)
		)
		(polygon
			(pts
				(arc
					(start 177.250598 -195.821554)
					(mid 177.265477 -195.857475)
					(end 177.301398 -195.872354)
				)
				(arc
					(start 178.700938 -195.872354)
					(mid 178.736859 -195.857475)
					(end 178.751738 -195.821554)
				)
				(arc
					(start 178.751738 -195.412614)
					(mid 178.736859 -195.376693)
					(end 178.700938 -195.361814)
				)
				(arc
					(start 177.301398 -195.361814)
					(mid 177.265477 -195.376693)
					(end 177.250598 -195.412614)
				)
			)
		)
	)
	(zone
		(layers "In1.Cu" "In2.Cu")
		(hatch none 0.5)
		(connect_pads
			(clearance 0)
		)
		(min_thickness 0.25)
		(keepout
			(tracks not_allowed)
			(vias allowed)
			(pads allowed)
			(copperpour not_allowed)
			(footprints allowed)
		)
		(placement
			(enabled no)
			(sheetname "")
		)
		(fill yes
			(thermal_gap 0.5)
			(thermal_bridge_width 0.5)
			(island_removal_mode 0)
		)
		(polygon
			(pts
				(arc
					(start 30.02153 -274.871434)
					(mid 30.036409 -274.907355)
					(end 30.07233 -274.922234)
				)
				(arc
					(start 31.47187 -274.922234)
					(mid 31.507791 -274.907355)
					(end 31.52267 -274.871434)
				)
				(arc
					(start 31.52267 -274.462494)
					(mid 31.507791 -274.426573)
					(end 31.47187 -274.411694)
				)
				(arc
					(start 30.07233 -274.411694)
					(mid 30.036409 -274.426573)
					(end 30.02153 -274.462494)
				)
			)
		)
	)
	(zone
		(layers "In1.Cu" "In2.Cu")
		(hatch none 0.5)
		(connect_pads
			(clearance 0)
		)
		(min_thickness 0.25)
		(keepout
			(tracks not_allowed)
			(vias allowed)
			(pads allowed)
			(copperpour not_allowed)
			(footprints allowed)
		)
		(placement
			(enabled no)
			(sheetname "")
		)
		(fill yes
			(thermal_gap 0.5)
			(thermal_bridge_width 0.5)
			(island_removal_mode 0)
		)
		(polygon
			(pts
				(arc
					(start 262.873998 -301.221394)
					(mid 262.888877 -301.257315)
					(end 262.924798 -301.272194)
				)
				(arc
					(start 264.324338 -301.272194)
					(mid 264.360259 -301.257315)
					(end 264.375138 -301.221394)
				)
				(arc
					(start 264.375138 -300.812454)
					(mid 264.360259 -300.776533)
					(end 264.324338 -300.761654)
				)
				(arc
					(start 262.924798 -300.761654)
					(mid 262.888877 -300.776533)
					(end 262.873998 -300.812454)
				)
			)
		)
	)
	(zone
		(layers "In1.Cu" "In2.Cu")
		(hatch none 0.5)
		(connect_pads
			(clearance 0)
		)
		(min_thickness 0.25)
		(keepout
			(tracks not_allowed)
			(vias allowed)
			(pads allowed)
			(copperpour not_allowed)
			(footprints allowed)
		)
		(placement
			(enabled no)
			(sheetname "")
		)
		(fill yes
			(thermal_gap 0.5)
			(thermal_bridge_width 0.5)
			(island_removal_mode 0)
		)
		(polygon
			(pts
				(arc
					(start 312.236866 -203.471526)
					(mid 312.251745 -203.507447)
					(end 312.287666 -203.522326)
				)
				(arc
					(start 313.687206 -203.522326)
					(mid 313.723127 -203.507447)
					(end 313.738006 -203.471526)
				)
				(arc
					(start 313.738006 -203.062586)
					(mid 313.723127 -203.026665)
					(end 313.687206 -203.011786)
				)
				(arc
					(start 312.287666 -203.011786)
					(mid 312.251745 -203.026665)
					(end 312.236866 -203.062586)
				)
			)
		)
	)
	(zone
		(layers "In1.Cu" "In2.Cu")
		(hatch none 0.5)
		(connect_pads
			(clearance 0)
		)
		(min_thickness 0.25)
		(keepout
			(tracks not_allowed)
			(vias allowed)
			(pads allowed)
			(copperpour not_allowed)
			(footprints allowed)
		)
		(placement
			(enabled no)
			(sheetname "")
		)
		(fill yes
			(thermal_gap 0.5)
			(thermal_bridge_width 0.5)
			(island_removal_mode 0)
		)
		(polygon
			(pts
				(arc
					(start 300.592998 -213.671404)
					(mid 300.607877 -213.707325)
					(end 300.643798 -213.722204)
				)
				(arc
					(start 302.043338 -213.722204)
					(mid 302.079259 -213.707325)
					(end 302.094138 -213.671404)
				)
				(arc
					(start 302.094138 -213.262464)
					(mid 302.079259 -213.226543)
					(end 302.043338 -213.211664)
				)
				(arc
					(start 300.643798 -213.211664)
					(mid 300.607877 -213.226543)
					(end 300.592998 -213.262464)
				)
			)
		)
	)
	(zone
		(layers "In1.Cu" "In2.Cu")
		(hatch none 0.5)
		(connect_pads
			(clearance 0)
		)
		(min_thickness 0.25)
		(keepout
			(tracks not_allowed)
			(vias allowed)
			(pads allowed)
			(copperpour not_allowed)
			(footprints allowed)
		)
		(placement
			(enabled no)
			(sheetname "")
		)
		(fill yes
			(thermal_gap 0.5)
			(thermal_bridge_width 0.5)
			(island_removal_mode 0)
		)
		(polygon
			(pts
				(arc
					(start 304.693066 -265.52144)
					(mid 304.707945 -265.557361)
					(end 304.743866 -265.57224)
				)
				(arc
					(start 306.143406 -265.57224)
					(mid 306.179327 -265.557361)
					(end 306.194206 -265.52144)
				)
				(arc
					(start 306.194206 -265.1125)
					(mid 306.179327 -265.076579)
					(end 306.143406 -265.0617)
				)
				(arc
					(start 304.743866 -265.0617)
					(mid 304.707945 -265.076579)
					(end 304.693066 -265.1125)
				)
			)
		)
	)
	(zone
		(layers "In1.Cu" "In2.Cu")
		(hatch none 0.5)
		(connect_pads
			(clearance 0)
		)
		(min_thickness 0.25)
		(keepout
			(tracks not_allowed)
			(vias allowed)
			(pads allowed)
			(copperpour not_allowed)
			(footprints allowed)
		)
		(placement
			(enabled no)
			(sheetname "")
		)
		(fill yes
			(thermal_gap 0.5)
			(thermal_bridge_width 0.5)
			(island_removal_mode 0)
		)
		(polygon
			(pts
				(arc
					(start 22.47773 -232.371392)
					(mid 22.492609 -232.407313)
					(end 22.52853 -232.422192)
				)
				(arc
					(start 23.92807 -232.422192)
					(mid 23.963991 -232.407313)
					(end 23.97887 -232.371392)
				)
				(arc
					(start 23.97887 -231.962452)
					(mid 23.963991 -231.926531)
					(end 23.92807 -231.911652)
				)
				(arc
					(start 22.52853 -231.911652)
					(mid 22.492609 -231.926531)
					(end 22.47773 -231.962452)
				)
			)
		)
	)
	(zone
		(layers "In1.Cu" "In2.Cu")
		(hatch none 0.5)
		(connect_pads
			(clearance 0)
		)
		(min_thickness 0.25)
		(keepout
			(tracks not_allowed)
			(vias allowed)
			(pads allowed)
			(copperpour not_allowed)
			(footprints allowed)
		)
		(placement
			(enabled no)
			(sheetname "")
		)
		(fill yes
			(thermal_gap 0.5)
			(thermal_bridge_width 0.5)
			(island_removal_mode 0)
		)
		(polygon
			(pts
				(arc
					(start 210.86953 -277.42134)
					(mid 210.884409 -277.457261)
					(end 210.92033 -277.47214)
				)
				(arc
					(start 212.31987 -277.47214)
					(mid 212.355791 -277.457261)
					(end 212.37067 -277.42134)
				)
				(arc
					(start 212.37067 -277.0124)
					(mid 212.355791 -276.976479)
					(end 212.31987 -276.9616)
				)
				(arc
					(start 210.92033 -276.9616)
					(mid 210.884409 -276.976479)
					(end 210.86953 -277.0124)
				)
			)
		)
	)
	(zone
		(layers "In1.Cu" "In2.Cu")
		(hatch none 0.5)
		(connect_pads
			(clearance 0)
		)
		(min_thickness 0.25)
		(keepout
			(tracks not_allowed)
			(vias allowed)
			(pads allowed)
			(copperpour not_allowed)
			(footprints allowed)
		)
		(placement
			(enabled no)
			(sheetname "")
		)
		(fill yes
			(thermal_gap 0.5)
			(thermal_bridge_width 0.5)
			(island_removal_mode 0)
		)
		(polygon
			(pts
				(arc
					(start 30.02153 -235.771436)
					(mid 30.036409 -235.807357)
					(end 30.07233 -235.822236)
				)
				(arc
					(start 31.47187 -235.822236)
					(mid 31.507791 -235.807357)
					(end 31.52267 -235.771436)
				)
				(arc
					(start 31.52267 -235.362496)
					(mid 31.507791 -235.326575)
					(end 31.47187 -235.311696)
				)
				(arc
					(start 30.07233 -235.311696)
					(mid 30.036409 -235.326575)
					(end 30.02153 -235.362496)
				)
			)
		)
	)
	(zone
		(layers "In1.Cu" "In2.Cu")
		(hatch none 0.5)
		(connect_pads
			(clearance 0)
		)
		(min_thickness 0.25)
		(keepout
			(tracks not_allowed)
			(vias allowed)
			(pads allowed)
			(copperpour not_allowed)
			(footprints allowed)
		)
		(placement
			(enabled no)
			(sheetname "")
		)
		(fill yes
			(thermal_gap 0.5)
			(thermal_bridge_width 0.5)
			(island_removal_mode 0)
		)
		(polygon
			(pts
				(arc
					(start 462.909666 -222.171514)
					(mid 462.924545 -222.207435)
					(end 462.960466 -222.222314)
				)
				(arc
					(start 464.360006 -222.222314)
					(mid 464.395927 -222.207435)
					(end 464.410806 -222.171514)
				)
				(arc
					(start 464.410806 -221.762574)
					(mid 464.395927 -221.726653)
					(end 464.360006 -221.711774)
				)
				(arc
					(start 462.960466 -221.711774)
					(mid 462.924545 -221.726653)
					(end 462.909666 -221.762574)
				)
			)
		)
	)
	(zone
		(layers "In1.Cu" "In2.Cu")
		(hatch none 0.5)
		(connect_pads
			(clearance 0)
		)
		(min_thickness 0.25)
		(keepout
			(tracks not_allowed)
			(vias allowed)
			(pads allowed)
			(copperpour not_allowed)
			(footprints allowed)
		)
		(placement
			(enabled no)
			(sheetname "")
		)
		(fill yes
			(thermal_gap 0.5)
			(thermal_bridge_width 0.5)
			(island_removal_mode 0)
		)
		(polygon
			(pts
				(arc
					(start 195.78193 -207.721454)
					(mid 195.796809 -207.757375)
					(end 195.83273 -207.772254)
				)
				(arc
					(start 197.23227 -207.772254)
					(mid 197.268191 -207.757375)
					(end 197.28307 -207.721454)
				)
				(arc
					(start 197.28307 -207.312514)
					(mid 197.268191 -207.276593)
					(end 197.23227 -207.261714)
				)
				(arc
					(start 195.83273 -207.261714)
					(mid 195.796809 -207.276593)
					(end 195.78193 -207.312514)
				)
			)
		)
	)
	(zone
		(layers "In1.Cu" "In2.Cu")
		(hatch none 0.5)
		(connect_pads
			(clearance 0)
		)
		(min_thickness 0.25)
		(keepout
			(tracks not_allowed)
			(vias allowed)
			(pads allowed)
			(copperpour not_allowed)
			(footprints allowed)
		)
		(placement
			(enabled no)
			(sheetname "")
		)
		(fill yes
			(thermal_gap 0.5)
			(thermal_bridge_width 0.5)
			(island_removal_mode 0)
		)
		(polygon
			(pts
				(arc
					(start 259.430266 -272.321528)
					(mid 259.445145 -272.357449)
					(end 259.481066 -272.372328)
				)
				(arc
					(start 260.880606 -272.372328)
					(mid 260.916527 -272.357449)
					(end 260.931406 -272.321528)
				)
				(arc
					(start 260.931406 -271.912588)
					(mid 260.916527 -271.876667)
					(end 260.880606 -271.861788)
				)
				(arc
					(start 259.481066 -271.861788)
					(mid 259.445145 -271.876667)
					(end 259.430266 -271.912588)
				)
			)
		)
	)
	(zone
		(layers "In1.Cu" "In2.Cu")
		(hatch none 0.5)
		(connect_pads
			(clearance 0)
		)
		(min_thickness 0.25)
		(keepout
			(tracks not_allowed)
			(vias allowed)
			(pads allowed)
			(copperpour not_allowed)
			(footprints allowed)
		)
		(placement
			(enabled no)
			(sheetname "")
		)
		(fill yes
			(thermal_gap 0.5)
			(thermal_bridge_width 0.5)
			(island_removal_mode 0)
		)
		(polygon
			(pts
				(arc
					(start 455.365866 -315.671454)
					(mid 455.380745 -315.707375)
					(end 455.416666 -315.722254)
				)
				(arc
					(start 456.816206 -315.722254)
					(mid 456.852127 -315.707375)
					(end 456.867006 -315.671454)
				)
				(arc
					(start 456.867006 -315.262514)
					(mid 456.852127 -315.226593)
					(end 456.816206 -315.211714)
				)
				(arc
					(start 455.416666 -315.211714)
					(mid 455.380745 -315.226593)
					(end 455.365866 -315.262514)
				)
			)
		)
	)
	(zone
		(layers "In1.Cu" "In2.Cu")
		(hatch none 0.5)
		(connect_pads
			(clearance 0)
		)
		(min_thickness 0.25)
		(keepout
			(tracks not_allowed)
			(vias allowed)
			(pads allowed)
			(copperpour not_allowed)
			(footprints allowed)
		)
		(placement
			(enabled no)
			(sheetname "")
		)
		(fill yes
			(thermal_gap 0.5)
			(thermal_bridge_width 0.5)
			(island_removal_mode 0)
		)
		(polygon
			(pts
				(arc
					(start 195.78193 -277.42134)
					(mid 195.796809 -277.457261)
					(end 195.83273 -277.47214)
				)
				(arc
					(start 197.23227 -277.47214)
					(mid 197.268191 -277.457261)
					(end 197.28307 -277.42134)
				)
				(arc
					(start 197.28307 -277.0124)
					(mid 197.268191 -276.976479)
					(end 197.23227 -276.9616)
				)
				(arc
					(start 195.83273 -276.9616)
					(mid 195.796809 -276.976479)
					(end 195.78193 -277.0124)
				)
			)
		)
	)
	(zone
		(layers "In1.Cu" "In2.Cu")
		(hatch none 0.5)
		(connect_pads
			(clearance 0)
		)
		(min_thickness 0.25)
		(keepout
			(tracks not_allowed)
			(vias allowed)
			(pads allowed)
			(copperpour not_allowed)
			(footprints allowed)
		)
		(placement
			(enabled no)
			(sheetname "")
		)
		(fill yes
			(thermal_gap 0.5)
			(thermal_bridge_width 0.5)
			(island_removal_mode 0)
		)
		(polygon
			(pts
				(arc
					(start 26.577798 -245.12143)
					(mid 26.592677 -245.157351)
					(end 26.628598 -245.17223)
				)
				(arc
					(start 28.028138 -245.17223)
					(mid 28.064059 -245.157351)
					(end 28.078938 -245.12143)
				)
				(arc
					(start 28.078938 -244.71249)
					(mid 28.064059 -244.676569)
					(end 28.028138 -244.66169)
				)
				(arc
					(start 26.628598 -244.66169)
					(mid 26.592677 -244.676569)
					(end 26.577798 -244.71249)
				)
			)
		)
	)
	(zone
		(layers "In1.Cu" "In2.Cu")
		(hatch none 0.5)
		(connect_pads
			(clearance 0)
		)
		(min_thickness 0.25)
		(keepout
			(tracks not_allowed)
			(vias allowed)
			(pads allowed)
			(copperpour not_allowed)
			(footprints allowed)
		)
		(placement
			(enabled no)
			(sheetname "")
		)
		(fill yes
			(thermal_gap 0.5)
			(thermal_bridge_width 0.5)
			(island_removal_mode 0)
		)
		(polygon
			(pts
				(arc
					(start 255.330198 -200.071482)
					(mid 255.345077 -200.107403)
					(end 255.380998 -200.122282)
				)
				(arc
					(start 256.780538 -200.122282)
					(mid 256.816459 -200.107403)
					(end 256.831338 -200.071482)
				)
				(arc
					(start 256.831338 -199.662542)
					(mid 256.816459 -199.626621)
					(end 256.780538 -199.611742)
				)
				(arc
					(start 255.380998 -199.611742)
					(mid 255.345077 -199.626621)
					(end 255.330198 -199.662542)
				)
			)
		)
	)
	(zone
		(layers "In1.Cu" "In2.Cu")
		(hatch none 0.5)
		(connect_pads
			(clearance 0)
		)
		(min_thickness 0.25)
		(keepout
			(tracks not_allowed)
			(vias allowed)
			(pads allowed)
			(copperpour not_allowed)
			(footprints allowed)
		)
		(placement
			(enabled no)
			(sheetname "")
		)
		(fill yes
			(thermal_gap 0.5)
			(thermal_bridge_width 0.5)
			(island_removal_mode 0)
		)
		(polygon
			(pts
				(arc
					(start 207.425798 -205.171548)
					(mid 207.440677 -205.207469)
					(end 207.476598 -205.222348)
				)
				(arc
					(start 208.876138 -205.222348)
					(mid 208.912059 -205.207469)
					(end 208.926938 -205.171548)
				)
				(arc
					(start 208.926938 -204.762608)
					(mid 208.912059 -204.726687)
					(end 208.876138 -204.711808)
				)
				(arc
					(start 207.476598 -204.711808)
					(mid 207.440677 -204.726687)
					(end 207.425798 -204.762608)
				)
			)
		)
	)
	(zone
		(layers "In1.Cu" "In2.Cu")
		(hatch none 0.5)
		(connect_pads
			(clearance 0)
		)
		(min_thickness 0.25)
		(keepout
			(tracks not_allowed)
			(vias allowed)
			(pads allowed)
			(copperpour not_allowed)
			(footprints allowed)
		)
		(placement
			(enabled no)
			(sheetname "")
		)
		(fill yes
			(thermal_gap 0.5)
			(thermal_bridge_width 0.5)
			(island_removal_mode 0)
		)
		(polygon
			(pts
				(arc
					(start 158.06293 -221.321376)
					(mid 158.077809 -221.357297)
					(end 158.11373 -221.372176)
				)
				(arc
					(start 159.51327 -221.372176)
					(mid 159.549191 -221.357297)
					(end 159.56407 -221.321376)
				)
				(arc
					(start 159.56407 -220.912436)
					(mid 159.549191 -220.876515)
					(end 159.51327 -220.861636)
				)
				(arc
					(start 158.11373 -220.861636)
					(mid 158.077809 -220.876515)
					(end 158.06293 -220.912436)
				)
			)
		)
	)
	(zone
		(layers "In1.Cu" "In2.Cu")
		(hatch none 0.5)
		(connect_pads
			(clearance 0)
		)
		(min_thickness 0.25)
		(keepout
			(tracks not_allowed)
			(vias allowed)
			(pads allowed)
			(copperpour not_allowed)
			(footprints allowed)
		)
		(placement
			(enabled no)
			(sheetname "")
		)
		(fill yes
			(thermal_gap 0.5)
			(thermal_bridge_width 0.5)
			(island_removal_mode 0)
		)
		(polygon
			(pts
				(arc
					(start 451.265798 -268.071346)
					(mid 451.280677 -268.107267)
					(end 451.316598 -268.122146)
				)
				(arc
					(start 452.716138 -268.122146)
					(mid 452.752059 -268.107267)
					(end 452.766938 -268.071346)
				)
				(arc
					(start 452.766938 -267.662406)
					(mid 452.752059 -267.626485)
					(end 452.716138 -267.611606)
				)
				(arc
					(start 451.316598 -267.611606)
					(mid 451.280677 -267.626485)
					(end 451.265798 -267.662406)
				)
			)
		)
	)
	(zone
		(layers "In1.Cu" "In2.Cu")
		(hatch none 0.5)
		(connect_pads
			(clearance 0)
		)
		(min_thickness 0.25)
		(keepout
			(tracks not_allowed)
			(vias allowed)
			(pads allowed)
			(copperpour not_allowed)
			(footprints allowed)
		)
		(placement
			(enabled no)
			(sheetname "")
		)
		(fill yes
			(thermal_gap 0.5)
			(thermal_bridge_width 0.5)
			(island_removal_mode 0)
		)
		(polygon
			(pts
				(arc
					(start 255.330198 -210.27136)
					(mid 255.345077 -210.307281)
					(end 255.380998 -210.32216)
				)
				(arc
					(start 256.780538 -210.32216)
					(mid 256.816459 -210.307281)
					(end 256.831338 -210.27136)
				)
				(arc
					(start 256.831338 -209.86242)
					(mid 256.816459 -209.826499)
					(end 256.780538 -209.81162)
				)
				(arc
					(start 255.380998 -209.81162)
					(mid 255.345077 -209.826499)
					(end 255.330198 -209.86242)
				)
			)
		)
	)
	(zone
		(layers "In1.Cu" "In2.Cu")
		(hatch none 0.5)
		(connect_pads
			(clearance 0)
		)
		(min_thickness 0.25)
		(keepout
			(tracks not_allowed)
			(vias allowed)
			(pads allowed)
			(copperpour not_allowed)
			(footprints allowed)
		)
		(placement
			(enabled no)
			(sheetname "")
		)
		(fill yes
			(thermal_gap 0.5)
			(thermal_bridge_width 0.5)
			(island_removal_mode 0)
		)
		(polygon
			(pts
				(arc
					(start 282.061666 -267.221462)
					(mid 282.076545 -267.257383)
					(end 282.112466 -267.272262)
				)
				(arc
					(start 283.512006 -267.272262)
					(mid 283.547927 -267.257383)
					(end 283.562806 -267.221462)
				)
				(arc
					(start 283.562806 -266.812522)
					(mid 283.547927 -266.776601)
					(end 283.512006 -266.761722)
				)
				(arc
					(start 282.112466 -266.761722)
					(mid 282.076545 -266.776601)
					(end 282.061666 -266.812522)
				)
			)
		)
	)
	(zone
		(layers "In1.Cu" "In2.Cu")
		(hatch none 0.5)
		(connect_pads
			(clearance 0)
		)
		(min_thickness 0.25)
		(keepout
			(tracks not_allowed)
			(vias allowed)
			(pads allowed)
			(copperpour not_allowed)
			(footprints allowed)
		)
		(placement
			(enabled no)
			(sheetname "")
		)
		(fill yes
			(thermal_gap 0.5)
			(thermal_bridge_width 0.5)
			(island_removal_mode 0)
		)
		(polygon
			(pts
				(arc
					(start 255.330198 -223.021398)
					(mid 255.345077 -223.057319)
					(end 255.380998 -223.072198)
				)
				(arc
					(start 256.780538 -223.072198)
					(mid 256.816459 -223.057319)
					(end 256.831338 -223.021398)
				)
				(arc
					(start 256.831338 -222.612458)
					(mid 256.816459 -222.576537)
					(end 256.780538 -222.561658)
				)
				(arc
					(start 255.380998 -222.561658)
					(mid 255.345077 -222.576537)
					(end 255.330198 -222.612458)
				)
			)
		)
	)
	(zone
		(layers "In1.Cu" "In2.Cu")
		(hatch none 0.5)
		(connect_pads
			(clearance 0)
		)
		(min_thickness 0.25)
		(keepout
			(tracks not_allowed)
			(vias allowed)
			(pads allowed)
			(copperpour not_allowed)
			(footprints allowed)
		)
		(placement
			(enabled no)
			(sheetname "")
		)
		(fill yes
			(thermal_gap 0.5)
			(thermal_bridge_width 0.5)
			(island_removal_mode 0)
		)
		(polygon
			(pts
				(arc
					(start 34.121598 -312.27141)
					(mid 34.136477 -312.307331)
					(end 34.172398 -312.32221)
				)
				(arc
					(start 35.571938 -312.32221)
					(mid 35.607859 -312.307331)
					(end 35.622738 -312.27141)
				)
				(arc
					(start 35.622738 -311.86247)
					(mid 35.607859 -311.826549)
					(end 35.571938 -311.81167)
				)
				(arc
					(start 34.172398 -311.81167)
					(mid 34.136477 -311.826549)
					(end 34.121598 -311.86247)
				)
			)
		)
	)
	(zone
		(layers "In1.Cu" "In2.Cu")
		(hatch none 0.5)
		(connect_pads
			(clearance 0)
		)
		(min_thickness 0.25)
		(keepout
			(tracks not_allowed)
			(vias allowed)
			(pads allowed)
			(copperpour not_allowed)
			(footprints allowed)
		)
		(placement
			(enabled no)
			(sheetname "")
		)
		(fill yes
			(thermal_gap 0.5)
			(thermal_bridge_width 0.5)
			(island_removal_mode 0)
		)
		(polygon
			(pts
				(arc
					(start 34.121598 -200.071482)
					(mid 34.136477 -200.107403)
					(end 34.172398 -200.122282)
				)
				(arc
					(start 35.571938 -200.122282)
					(mid 35.607859 -200.107403)
					(end 35.622738 -200.071482)
				)
				(arc
					(start 35.622738 -199.662542)
					(mid 35.607859 -199.626621)
					(end 35.571938 -199.611742)
				)
				(arc
					(start 34.172398 -199.611742)
					(mid 34.136477 -199.626621)
					(end 34.121598 -199.662542)
				)
			)
		)
	)
	(zone
		(layers "In1.Cu" "In2.Cu")
		(hatch none 0.5)
		(connect_pads
			(clearance 0)
		)
		(min_thickness 0.25)
		(keepout
			(tracks not_allowed)
			(vias allowed)
			(pads allowed)
			(copperpour not_allowed)
			(footprints allowed)
		)
		(placement
			(enabled no)
			(sheetname "")
		)
		(fill yes
			(thermal_gap 0.5)
			(thermal_bridge_width 0.5)
			(island_removal_mode 0)
		)
		(polygon
			(pts
				(arc
					(start 462.909666 -239.17148)
					(mid 462.924545 -239.207401)
					(end 462.960466 -239.22228)
				)
				(arc
					(start 464.360006 -239.22228)
					(mid 464.395927 -239.207401)
					(end 464.410806 -239.17148)
				)
				(arc
					(start 464.410806 -238.76254)
					(mid 464.395927 -238.726619)
					(end 464.360006 -238.71174)
				)
				(arc
					(start 462.960466 -238.71174)
					(mid 462.924545 -238.726619)
					(end 462.909666 -238.76254)
				)
			)
		)
	)
	(zone
		(layers "In1.Cu" "In2.Cu")
		(hatch none 0.5)
		(connect_pads
			(clearance 0)
		)
		(min_thickness 0.25)
		(keepout
			(tracks not_allowed)
			(vias allowed)
			(pads allowed)
			(copperpour not_allowed)
			(footprints allowed)
		)
		(placement
			(enabled no)
			(sheetname "")
		)
		(fill yes
			(thermal_gap 0.5)
			(thermal_bridge_width 0.5)
			(island_removal_mode 0)
		)
		(polygon
			(pts
				(arc
					(start 30.02153 -251.07138)
					(mid 30.036409 -251.107301)
					(end 30.07233 -251.12218)
				)
				(arc
					(start 31.47187 -251.12218)
					(mid 31.507791 -251.107301)
					(end 31.52267 -251.07138)
				)
				(arc
					(start 31.52267 -250.66244)
					(mid 31.507791 -250.626519)
					(end 31.47187 -250.61164)
				)
				(arc
					(start 30.07233 -250.61164)
					(mid 30.036409 -250.626519)
					(end 30.02153 -250.66244)
				)
			)
		)
	)
	(zone
		(layers "In1.Cu" "In2.Cu")
		(hatch none 0.5)
		(connect_pads
			(clearance 0)
		)
		(min_thickness 0.25)
		(keepout
			(tracks not_allowed)
			(vias allowed)
			(pads allowed)
			(copperpour not_allowed)
			(footprints allowed)
		)
		(placement
			(enabled no)
			(sheetname "")
		)
		(fill yes
			(thermal_gap 0.5)
			(thermal_bridge_width 0.5)
			(island_removal_mode 0)
		)
		(polygon
			(pts
				(arc
					(start 440.278266 -199.221344)
					(mid 440.293145 -199.257265)
					(end 440.329066 -199.272144)
				)
				(arc
					(start 441.728606 -199.272144)
					(mid 441.764527 -199.257265)
					(end 441.779406 -199.221344)
				)
				(arc
					(start 441.779406 -198.812404)
					(mid 441.764527 -198.776483)
					(end 441.728606 -198.761604)
				)
				(arc
					(start 440.329066 -198.761604)
					(mid 440.293145 -198.776483)
					(end 440.278266 -198.812404)
				)
			)
		)
	)
	(zone
		(layers "In1.Cu" "In2.Cu")
		(hatch none 0.5)
		(connect_pads
			(clearance 0)
		)
		(min_thickness 0.25)
		(keepout
			(tracks not_allowed)
			(vias allowed)
			(pads allowed)
			(copperpour not_allowed)
			(footprints allowed)
		)
		(placement
			(enabled no)
			(sheetname "")
		)
		(fill yes
			(thermal_gap 0.5)
			(thermal_bridge_width 0.5)
			(island_removal_mode 0)
		)
		(polygon
			(pts
				(arc
					(start 300.592998 -285.071312)
					(mid 300.607877 -285.107233)
					(end 300.643798 -285.122112)
				)
				(arc
					(start 302.043338 -285.122112)
					(mid 302.079259 -285.107233)
					(end 302.094138 -285.071312)
				)
				(arc
					(start 302.094138 -284.662372)
					(mid 302.079259 -284.626451)
					(end 302.043338 -284.611572)
				)
				(arc
					(start 300.643798 -284.611572)
					(mid 300.607877 -284.626451)
					(end 300.592998 -284.662372)
				)
			)
		)
	)
	(zone
		(layers "In1.Cu" "In2.Cu")
		(hatch none 0.5)
		(connect_pads
			(clearance 0)
		)
		(min_thickness 0.25)
		(keepout
			(tracks not_allowed)
			(vias allowed)
			(pads allowed)
			(copperpour not_allowed)
			(footprints allowed)
		)
		(placement
			(enabled no)
			(sheetname "")
		)
		(fill yes
			(thermal_gap 0.5)
			(thermal_bridge_width 0.5)
			(island_removal_mode 0)
		)
		(polygon
			(pts
				(arc
					(start 421.090598 -288.471356)
					(mid 421.105477 -288.507277)
					(end 421.141398 -288.522156)
				)
				(arc
					(start 422.540938 -288.522156)
					(mid 422.576859 -288.507277)
					(end 422.591738 -288.471356)
				)
				(arc
					(start 422.591738 -288.062416)
					(mid 422.576859 -288.026495)
					(end 422.540938 -288.011616)
				)
				(arc
					(start 421.141398 -288.011616)
					(mid 421.105477 -288.026495)
					(end 421.090598 -288.062416)
				)
			)
		)
	)
	(zone
		(layers "In1.Cu" "In2.Cu")
		(hatch none 0.5)
		(connect_pads
			(clearance 0)
		)
		(min_thickness 0.25)
		(keepout
			(tracks not_allowed)
			(vias allowed)
			(pads allowed)
			(copperpour not_allowed)
			(footprints allowed)
		)
		(placement
			(enabled no)
			(sheetname "")
		)
		(fill yes
			(thermal_gap 0.5)
			(thermal_bridge_width 0.5)
			(island_removal_mode 0)
		)
		(polygon
			(pts
				(arc
					(start 413.546798 -308.871366)
					(mid 413.561677 -308.907287)
					(end 413.597598 -308.922166)
				)
				(arc
					(start 414.997138 -308.922166)
					(mid 415.033059 -308.907287)
					(end 415.047938 -308.871366)
				)
				(arc
					(start 415.047938 -308.462426)
					(mid 415.033059 -308.426505)
					(end 414.997138 -308.411626)
				)
				(arc
					(start 413.597598 -308.411626)
					(mid 413.561677 -308.426505)
					(end 413.546798 -308.462426)
				)
			)
		)
	)
	(zone
		(layers "In1.Cu" "In2.Cu")
		(hatch none 0.5)
		(connect_pads
			(clearance 0)
		)
		(min_thickness 0.25)
		(keepout
			(tracks not_allowed)
			(vias allowed)
			(pads allowed)
			(copperpour not_allowed)
			(footprints allowed)
		)
		(placement
			(enabled no)
			(sheetname "")
		)
		(fill yes
			(thermal_gap 0.5)
			(thermal_bridge_width 0.5)
			(island_removal_mode 0)
		)
		(polygon
			(pts
				(arc
					(start 158.06293 -215.371426)
					(mid 158.077809 -215.407347)
					(end 158.11373 -215.422226)
				)
				(arc
					(start 159.51327 -215.422226)
					(mid 159.549191 -215.407347)
					(end 159.56407 -215.371426)
				)
				(arc
					(start 159.56407 -214.962486)
					(mid 159.549191 -214.926565)
					(end 159.51327 -214.911686)
				)
				(arc
					(start 158.11373 -214.911686)
					(mid 158.077809 -214.926565)
					(end 158.06293 -214.962486)
				)
			)
		)
	)
	(zone
		(layers "In1.Cu" "In2.Cu")
		(hatch none 0.5)
		(connect_pads
			(clearance 0)
		)
		(min_thickness 0.25)
		(keepout
			(tracks not_allowed)
			(vias allowed)
			(pads allowed)
			(copperpour not_allowed)
			(footprints allowed)
		)
		(placement
			(enabled no)
			(sheetname "")
		)
		(fill yes
			(thermal_gap 0.5)
			(thermal_bridge_width 0.5)
			(island_removal_mode 0)
		)
		(polygon
			(pts
				(arc
					(start 188.23813 -259.57149)
					(mid 188.253009 -259.607411)
					(end 188.28893 -259.62229)
				)
				(arc
					(start 189.68847 -259.62229)
					(mid 189.724391 -259.607411)
					(end 189.73927 -259.57149)
				)
				(arc
					(start 189.73927 -259.16255)
					(mid 189.724391 -259.126629)
					(end 189.68847 -259.11175)
				)
				(arc
					(start 188.28893 -259.11175)
					(mid 188.253009 -259.126629)
					(end 188.23813 -259.16255)
				)
			)
		)
	)
	(zone
		(layers "In1.Cu" "In2.Cu")
		(hatch none 0.5)
		(connect_pads
			(clearance 0)
		)
		(min_thickness 0.25)
		(keepout
			(tracks not_allowed)
			(vias allowed)
			(pads allowed)
			(copperpour not_allowed)
			(footprints allowed)
		)
		(placement
			(enabled no)
			(sheetname "")
		)
		(fill yes
			(thermal_gap 0.5)
			(thermal_bridge_width 0.5)
			(island_removal_mode 0)
		)
		(polygon
			(pts
				(arc
					(start 207.425798 -211.121498)
					(mid 207.440677 -211.157419)
					(end 207.476598 -211.172298)
				)
				(arc
					(start 208.876138 -211.172298)
					(mid 208.912059 -211.157419)
					(end 208.926938 -211.121498)
				)
				(arc
					(start 208.926938 -210.712558)
					(mid 208.912059 -210.676637)
					(end 208.876138 -210.661758)
				)
				(arc
					(start 207.476598 -210.661758)
					(mid 207.440677 -210.676637)
					(end 207.425798 -210.712558)
				)
			)
		)
	)
	(zone
		(layers "In1.Cu" "In2.Cu")
		(hatch none 0.5)
		(connect_pads
			(clearance 0)
		)
		(min_thickness 0.25)
		(keepout
			(tracks not_allowed)
			(vias allowed)
			(pads allowed)
			(copperpour not_allowed)
			(footprints allowed)
		)
		(placement
			(enabled no)
			(sheetname "")
		)
		(fill yes
			(thermal_gap 0.5)
			(thermal_bridge_width 0.5)
			(island_removal_mode 0)
		)
		(polygon
			(pts
				(arc
					(start 304.693066 -233.22153)
					(mid 304.707945 -233.257451)
					(end 304.743866 -233.27233)
				)
				(arc
					(start 306.143406 -233.27233)
					(mid 306.179327 -233.257451)
					(end 306.194206 -233.22153)
				)
				(arc
					(start 306.194206 -232.81259)
					(mid 306.179327 -232.776669)
					(end 306.143406 -232.76179)
				)
				(arc
					(start 304.743866 -232.76179)
					(mid 304.707945 -232.776669)
					(end 304.693066 -232.81259)
				)
			)
		)
	)
	(zone
		(layers "In1.Cu" "In2.Cu")
		(hatch none 0.5)
		(connect_pads
			(clearance 0)
		)
		(min_thickness 0.25)
		(keepout
			(tracks not_allowed)
			(vias allowed)
			(pads allowed)
			(copperpour not_allowed)
			(footprints allowed)
		)
		(placement
			(enabled no)
			(sheetname "")
		)
		(fill yes
			(thermal_gap 0.5)
			(thermal_bridge_width 0.5)
			(island_removal_mode 0)
		)
		(polygon
			(pts
				(arc
					(start 214.969598 -276.571456)
					(mid 214.984477 -276.607377)
					(end 215.020398 -276.622256)
				)
				(arc
					(start 216.419938 -276.622256)
					(mid 216.455859 -276.607377)
					(end 216.470738 -276.571456)
				)
				(arc
					(start 216.470738 -276.162516)
					(mid 216.455859 -276.126595)
					(end 216.419938 -276.111716)
				)
				(arc
					(start 215.020398 -276.111716)
					(mid 214.984477 -276.126595)
					(end 214.969598 -276.162516)
				)
			)
		)
	)
	(zone
		(layers "In1.Cu" "In2.Cu")
		(hatch none 0.5)
		(connect_pads
			(clearance 0)
		)
		(min_thickness 0.25)
		(keepout
			(tracks not_allowed)
			(vias allowed)
			(pads allowed)
			(copperpour not_allowed)
			(footprints allowed)
		)
		(placement
			(enabled no)
			(sheetname "")
		)
		(fill yes
			(thermal_gap 0.5)
			(thermal_bridge_width 0.5)
			(island_removal_mode 0)
		)
		(polygon
			(pts
				(arc
					(start 297.149266 -308.021482)
					(mid 297.164145 -308.057403)
					(end 297.200066 -308.072282)
				)
				(arc
					(start 298.599606 -308.072282)
					(mid 298.635527 -308.057403)
					(end 298.650406 -308.021482)
				)
				(arc
					(start 298.650406 -307.612542)
					(mid 298.635527 -307.576621)
					(end 298.599606 -307.561742)
				)
				(arc
					(start 297.200066 -307.561742)
					(mid 297.164145 -307.576621)
					(end 297.149266 -307.612542)
				)
			)
		)
	)
	(zone
		(layers "In1.Cu" "In2.Cu")
		(hatch none 0.5)
		(connect_pads
			(clearance 0)
		)
		(min_thickness 0.25)
		(keepout
			(tracks not_allowed)
			(vias allowed)
			(pads allowed)
			(copperpour not_allowed)
			(footprints allowed)
		)
		(placement
			(enabled no)
			(sheetname "")
		)
		(fill yes
			(thermal_gap 0.5)
			(thermal_bridge_width 0.5)
			(island_removal_mode 0)
		)
		(polygon
			(pts
				(arc
					(start 266.974066 -209.421476)
					(mid 266.988945 -209.457397)
					(end 267.024866 -209.472276)
				)
				(arc
					(start 268.424406 -209.472276)
					(mid 268.460327 -209.457397)
					(end 268.475206 -209.421476)
				)
				(arc
					(start 268.475206 -209.012536)
					(mid 268.460327 -208.976615)
					(end 268.424406 -208.961736)
				)
				(arc
					(start 267.024866 -208.961736)
					(mid 266.988945 -208.976615)
					(end 266.974066 -209.012536)
				)
			)
		)
	)
	(zone
		(layers "In1.Cu" "In2.Cu")
		(hatch none 0.5)
		(connect_pads
			(clearance 0)
		)
		(min_thickness 0.25)
		(keepout
			(tracks not_allowed)
			(vias allowed)
			(pads allowed)
			(copperpour not_allowed)
			(footprints allowed)
		)
		(placement
			(enabled no)
			(sheetname "")
		)
		(fill yes
			(thermal_gap 0.5)
			(thermal_bridge_width 0.5)
			(island_removal_mode 0)
		)
		(polygon
			(pts
				(arc
					(start 300.592998 -261.271512)
					(mid 300.607877 -261.307433)
					(end 300.643798 -261.322312)
				)
				(arc
					(start 302.043338 -261.322312)
					(mid 302.079259 -261.307433)
					(end 302.094138 -261.271512)
				)
				(arc
					(start 302.094138 -260.862572)
					(mid 302.079259 -260.826651)
					(end 302.043338 -260.811772)
				)
				(arc
					(start 300.643798 -260.811772)
					(mid 300.607877 -260.826651)
					(end 300.592998 -260.862572)
				)
			)
		)
	)
	(zone
		(layers "In1.Cu" "In2.Cu")
		(hatch none 0.5)
		(connect_pads
			(clearance 0)
		)
		(min_thickness 0.25)
		(keepout
			(tracks not_allowed)
			(vias allowed)
			(pads allowed)
			(copperpour not_allowed)
			(footprints allowed)
		)
		(placement
			(enabled no)
			(sheetname "")
		)
		(fill yes
			(thermal_gap 0.5)
			(thermal_bridge_width 0.5)
			(island_removal_mode 0)
		)
		(polygon
			(pts
				(arc
					(start 406.002998 -223.021398)
					(mid 406.017877 -223.057319)
					(end 406.053798 -223.072198)
				)
				(arc
					(start 407.453338 -223.072198)
					(mid 407.489259 -223.057319)
					(end 407.504138 -223.021398)
				)
				(arc
					(start 407.504138 -222.612458)
					(mid 407.489259 -222.576537)
					(end 407.453338 -222.561658)
				)
				(arc
					(start 406.053798 -222.561658)
					(mid 406.017877 -222.576537)
					(end 406.002998 -222.612458)
				)
			)
		)
	)
	(zone
		(layers "In1.Cu" "In2.Cu")
		(hatch none 0.5)
		(connect_pads
			(clearance 0)
		)
		(min_thickness 0.25)
		(keepout
			(tracks not_allowed)
			(vias allowed)
			(pads allowed)
			(copperpour not_allowed)
			(footprints allowed)
		)
		(placement
			(enabled no)
			(sheetname "")
		)
		(fill yes
			(thermal_gap 0.5)
			(thermal_bridge_width 0.5)
			(island_removal_mode 0)
		)
		(polygon
			(pts
				(arc
					(start 297.149266 -313.971432)
					(mid 297.164145 -314.007353)
					(end 297.200066 -314.022232)
				)
				(arc
					(start 298.599606 -314.022232)
					(mid 298.635527 -314.007353)
					(end 298.650406 -313.971432)
				)
				(arc
					(start 298.650406 -313.562492)
					(mid 298.635527 -313.526571)
					(end 298.599606 -313.511692)
				)
				(arc
					(start 297.200066 -313.511692)
					(mid 297.164145 -313.526571)
					(end 297.149266 -313.562492)
				)
			)
		)
	)
	(zone
		(layers "In1.Cu" "In2.Cu")
		(hatch none 0.5)
		(connect_pads
			(clearance 0)
		)
		(min_thickness 0.25)
		(keepout
			(tracks not_allowed)
			(vias allowed)
			(pads allowed)
			(copperpour not_allowed)
			(footprints allowed)
		)
		(placement
			(enabled no)
			(sheetname "")
		)
		(fill yes
			(thermal_gap 0.5)
			(thermal_bridge_width 0.5)
			(island_removal_mode 0)
		)
		(polygon
			(pts
				(arc
					(start 266.974066 -239.17148)
					(mid 266.988945 -239.207401)
					(end 267.024866 -239.22228)
				)
				(arc
					(start 268.424406 -239.22228)
					(mid 268.460327 -239.207401)
					(end 268.475206 -239.17148)
				)
				(arc
					(start 268.475206 -238.76254)
					(mid 268.460327 -238.726619)
					(end 268.424406 -238.71174)
				)
				(arc
					(start 267.024866 -238.71174)
					(mid 266.988945 -238.726619)
					(end 266.974066 -238.76254)
				)
			)
		)
	)
	(zone
		(layers "In1.Cu" "In2.Cu")
		(hatch none 0.5)
		(connect_pads
			(clearance 0)
		)
		(min_thickness 0.25)
		(keepout
			(tracks not_allowed)
			(vias allowed)
			(pads allowed)
			(copperpour not_allowed)
			(footprints allowed)
		)
		(placement
			(enabled no)
			(sheetname "")
		)
		(fill yes
			(thermal_gap 0.5)
			(thermal_bridge_width 0.5)
			(island_removal_mode 0)
		)
		(polygon
			(pts
				(arc
					(start 443.721998 -282.521406)
					(mid 443.736877 -282.557327)
					(end 443.772798 -282.572206)
				)
				(arc
					(start 445.172338 -282.572206)
					(mid 445.208259 -282.557327)
					(end 445.223138 -282.521406)
				)
				(arc
					(start 445.223138 -282.112466)
					(mid 445.208259 -282.076545)
					(end 445.172338 -282.061666)
				)
				(arc
					(start 443.772798 -282.061666)
					(mid 443.736877 -282.076545)
					(end 443.721998 -282.112466)
				)
			)
		)
	)
	(zone
		(layers "In1.Cu" "In2.Cu")
		(hatch none 0.5)
		(connect_pads
			(clearance 0)
		)
		(min_thickness 0.25)
		(keepout
			(tracks not_allowed)
			(vias allowed)
			(pads allowed)
			(copperpour not_allowed)
			(footprints allowed)
		)
		(placement
			(enabled no)
			(sheetname "")
		)
		(fill yes
			(thermal_gap 0.5)
			(thermal_bridge_width 0.5)
			(island_removal_mode 0)
		)
		(polygon
			(pts
				(arc
					(start 266.974066 -233.22153)
					(mid 266.988945 -233.257451)
					(end 267.024866 -233.27233)
				)
				(arc
					(start 268.424406 -233.27233)
					(mid 268.460327 -233.257451)
					(end 268.475206 -233.22153)
				)
				(arc
					(start 268.475206 -232.81259)
					(mid 268.460327 -232.776669)
					(end 268.424406 -232.76179)
				)
				(arc
					(start 267.024866 -232.76179)
					(mid 266.988945 -232.776669)
					(end 266.974066 -232.81259)
				)
			)
		)
	)
	(zone
		(layers "In1.Cu" "In2.Cu")
		(hatch none 0.5)
		(connect_pads
			(clearance 0)
		)
		(min_thickness 0.25)
		(keepout
			(tracks not_allowed)
			(vias allowed)
			(pads allowed)
			(copperpour not_allowed)
			(footprints allowed)
		)
		(placement
			(enabled no)
			(sheetname "")
		)
		(fill yes
			(thermal_gap 0.5)
			(thermal_bridge_width 0.5)
			(island_removal_mode 0)
		)
		(polygon
			(pts
				(arc
					(start 285.505398 -293.571422)
					(mid 285.520277 -293.607343)
					(end 285.556198 -293.622222)
				)
				(arc
					(start 286.955738 -293.622222)
					(mid 286.991659 -293.607343)
					(end 287.006538 -293.571422)
				)
				(arc
					(start 287.006538 -293.162482)
					(mid 286.991659 -293.126561)
					(end 286.955738 -293.111682)
				)
				(arc
					(start 285.556198 -293.111682)
					(mid 285.520277 -293.126561)
					(end 285.505398 -293.162482)
				)
			)
		)
	)
	(zone
		(layers "In1.Cu" "In2.Cu")
		(hatch none 0.5)
		(connect_pads
			(clearance 0)
		)
		(min_thickness 0.25)
		(keepout
			(tracks not_allowed)
			(vias allowed)
			(pads allowed)
			(copperpour not_allowed)
			(footprints allowed)
		)
		(placement
			(enabled no)
			(sheetname "")
		)
		(fill yes
			(thermal_gap 0.5)
			(thermal_bridge_width 0.5)
			(island_removal_mode 0)
		)
		(polygon
			(pts
				(arc
					(start 289.605466 -262.121396)
					(mid 289.620345 -262.157317)
					(end 289.656266 -262.172196)
				)
				(arc
					(start 291.055806 -262.172196)
					(mid 291.091727 -262.157317)
					(end 291.106606 -262.121396)
				)
				(arc
					(start 291.106606 -261.712456)
					(mid 291.091727 -261.676535)
					(end 291.055806 -261.661656)
				)
				(arc
					(start 289.656266 -261.661656)
					(mid 289.620345 -261.676535)
					(end 289.605466 -261.712456)
				)
			)
		)
	)
	(zone
		(layers "In1.Cu" "In2.Cu")
		(hatch none 0.5)
		(connect_pads
			(clearance 0)
		)
		(min_thickness 0.25)
		(keepout
			(tracks not_allowed)
			(vias allowed)
			(pads allowed)
			(copperpour not_allowed)
			(footprints allowed)
		)
		(placement
			(enabled no)
			(sheetname "")
		)
		(fill yes
			(thermal_gap 0.5)
			(thermal_bridge_width 0.5)
			(island_removal_mode 0)
		)
		(polygon
			(pts
				(arc
					(start 255.330198 -273.171412)
					(mid 255.345077 -273.207333)
					(end 255.380998 -273.222212)
				)
				(arc
					(start 256.780538 -273.222212)
					(mid 256.816459 -273.207333)
					(end 256.831338 -273.171412)
				)
				(arc
					(start 256.831338 -272.762472)
					(mid 256.816459 -272.726551)
					(end 256.780538 -272.711672)
				)
				(arc
					(start 255.380998 -272.711672)
					(mid 255.345077 -272.726551)
					(end 255.330198 -272.762472)
				)
			)
		)
	)
	(zone
		(layers "In1.Cu" "In2.Cu")
		(hatch none 0.5)
		(connect_pads
			(clearance 0)
		)
		(min_thickness 0.25)
		(keepout
			(tracks not_allowed)
			(vias allowed)
			(pads allowed)
			(copperpour not_allowed)
			(footprints allowed)
		)
		(placement
			(enabled no)
			(sheetname "")
		)
		(fill yes
			(thermal_gap 0.5)
			(thermal_bridge_width 0.5)
			(island_removal_mode 0)
		)
		(polygon
			(pts
				(arc
					(start 184.794398 -298.671488)
					(mid 184.809277 -298.707409)
					(end 184.845198 -298.722288)
				)
				(arc
					(start 186.244738 -298.722288)
					(mid 186.280659 -298.707409)
					(end 186.295538 -298.671488)
				)
				(arc
					(start 186.295538 -298.262548)
					(mid 186.280659 -298.226627)
					(end 186.244738 -298.211748)
				)
				(arc
					(start 184.845198 -298.211748)
					(mid 184.809277 -298.226627)
					(end 184.794398 -298.262548)
				)
			)
		)
	)
	(zone
		(layers "In1.Cu" "In2.Cu")
		(hatch none 0.5)
		(connect_pads
			(clearance 0)
		)
		(min_thickness 0.25)
		(keepout
			(tracks not_allowed)
			(vias allowed)
			(pads allowed)
			(copperpour not_allowed)
			(footprints allowed)
		)
		(placement
			(enabled no)
			(sheetname "")
		)
		(fill yes
			(thermal_gap 0.5)
			(thermal_bridge_width 0.5)
			(island_removal_mode 0)
		)
		(polygon
			(pts
				(arc
					(start 262.873998 -280.821384)
					(mid 262.888877 -280.857305)
					(end 262.924798 -280.872184)
				)
				(arc
					(start 264.324338 -280.872184)
					(mid 264.360259 -280.857305)
					(end 264.375138 -280.821384)
				)
				(arc
					(start 264.375138 -280.412444)
					(mid 264.360259 -280.376523)
					(end 264.324338 -280.361644)
				)
				(arc
					(start 262.924798 -280.361644)
					(mid 262.888877 -280.376523)
					(end 262.873998 -280.412444)
				)
			)
		)
	)
	(zone
		(layers "In1.Cu" "In2.Cu")
		(hatch none 0.5)
		(connect_pads
			(clearance 0)
		)
		(min_thickness 0.25)
		(keepout
			(tracks not_allowed)
			(vias allowed)
			(pads allowed)
			(copperpour not_allowed)
			(footprints allowed)
		)
		(placement
			(enabled no)
			(sheetname "")
		)
		(fill yes
			(thermal_gap 0.5)
			(thermal_bridge_width 0.5)
			(island_removal_mode 0)
		)
		(polygon
			(pts
				(arc
					(start 462.909666 -233.22153)
					(mid 462.924545 -233.257451)
					(end 462.960466 -233.27233)
				)
				(arc
					(start 464.360006 -233.27233)
					(mid 464.395927 -233.257451)
					(end 464.410806 -233.22153)
				)
				(arc
					(start 464.410806 -232.81259)
					(mid 464.395927 -232.776669)
					(end 464.360006 -232.76179)
				)
				(arc
					(start 462.960466 -232.76179)
					(mid 462.924545 -232.776669)
					(end 462.909666 -232.81259)
				)
			)
		)
	)
	(zone
		(layers "In1.Cu" "In2.Cu")
		(hatch none 0.5)
		(connect_pads
			(clearance 0)
		)
		(min_thickness 0.25)
		(keepout
			(tracks not_allowed)
			(vias allowed)
			(pads allowed)
			(copperpour not_allowed)
			(footprints allowed)
		)
		(placement
			(enabled no)
			(sheetname "")
		)
		(fill yes
			(thermal_gap 0.5)
			(thermal_bridge_width 0.5)
			(island_removal_mode 0)
		)
		(polygon
			(pts
				(arc
					(start 203.32573 -230.67137)
					(mid 203.340609 -230.707291)
					(end 203.37653 -230.72217)
				)
				(arc
					(start 204.77607 -230.72217)
					(mid 204.811991 -230.707291)
					(end 204.82687 -230.67137)
				)
				(arc
					(start 204.82687 -230.26243)
					(mid 204.811991 -230.226509)
					(end 204.77607 -230.21163)
				)
				(arc
					(start 203.37653 -230.21163)
					(mid 203.340609 -230.226509)
					(end 203.32573 -230.26243)
				)
			)
		)
	)
	(zone
		(layers "In1.Cu" "In2.Cu")
		(hatch none 0.5)
		(connect_pads
			(clearance 0)
		)
		(min_thickness 0.25)
		(keepout
			(tracks not_allowed)
			(vias allowed)
			(pads allowed)
			(copperpour not_allowed)
			(footprints allowed)
		)
		(placement
			(enabled no)
			(sheetname "")
		)
		(fill yes
			(thermal_gap 0.5)
			(thermal_bridge_width 0.5)
			(island_removal_mode 0)
		)
		(polygon
			(pts
				(arc
					(start 432.734466 -281.671522)
					(mid 432.749345 -281.707443)
					(end 432.785266 -281.722322)
				)
				(arc
					(start 434.184806 -281.722322)
					(mid 434.220727 -281.707443)
					(end 434.235606 -281.671522)
				)
				(arc
					(start 434.235606 -281.262582)
					(mid 434.220727 -281.226661)
					(end 434.184806 -281.211782)
				)
				(arc
					(start 432.785266 -281.211782)
					(mid 432.749345 -281.226661)
					(end 432.734466 -281.262582)
				)
			)
		)
	)
	(zone
		(layers "In1.Cu" "In2.Cu")
		(hatch none 0.5)
		(connect_pads
			(clearance 0)
		)
		(min_thickness 0.25)
		(keepout
			(tracks not_allowed)
			(vias allowed)
			(pads allowed)
			(copperpour not_allowed)
			(footprints allowed)
		)
		(placement
			(enabled no)
			(sheetname "")
		)
		(fill yes
			(thermal_gap 0.5)
			(thermal_bridge_width 0.5)
			(island_removal_mode 0)
		)
		(polygon
			(pts
				(arc
					(start 289.605466 -227.271326)
					(mid 289.620345 -227.307247)
					(end 289.656266 -227.322126)
				)
				(arc
					(start 291.055806 -227.322126)
					(mid 291.091727 -227.307247)
					(end 291.106606 -227.271326)
				)
				(arc
					(start 291.106606 -226.862386)
					(mid 291.091727 -226.826465)
					(end 291.055806 -226.811586)
				)
				(arc
					(start 289.656266 -226.811586)
					(mid 289.620345 -226.826465)
					(end 289.605466 -226.862386)
				)
			)
		)
	)
	(zone
		(layers "In1.Cu" "In2.Cu")
		(hatch none 0.5)
		(connect_pads
			(clearance 0)
		)
		(min_thickness 0.25)
		(keepout
			(tracks not_allowed)
			(vias allowed)
			(pads allowed)
			(copperpour not_allowed)
			(footprints allowed)
		)
		(placement
			(enabled no)
			(sheetname "")
		)
		(fill yes
			(thermal_gap 0.5)
			(thermal_bridge_width 0.5)
			(island_removal_mode 0)
		)
		(polygon
			(pts
				(arc
					(start 421.090598 -232.371392)
					(mid 421.105477 -232.407313)
					(end 421.141398 -232.422192)
				)
				(arc
					(start 422.540938 -232.422192)
					(mid 422.576859 -232.407313)
					(end 422.591738 -232.371392)
				)
				(arc
					(start 422.591738 -231.962452)
					(mid 422.576859 -231.926531)
					(end 422.540938 -231.911652)
				)
				(arc
					(start 421.141398 -231.911652)
					(mid 421.105477 -231.926531)
					(end 421.090598 -231.962452)
				)
			)
		)
	)
	(zone
		(layers "In1.Cu" "In2.Cu")
		(hatch none 0.5)
		(connect_pads
			(clearance 0)
		)
		(min_thickness 0.25)
		(keepout
			(tracks not_allowed)
			(vias allowed)
			(pads allowed)
			(copperpour not_allowed)
			(footprints allowed)
		)
		(placement
			(enabled no)
			(sheetname "")
		)
		(fill yes
			(thermal_gap 0.5)
			(thermal_bridge_width 0.5)
			(island_removal_mode 0)
		)
		(polygon
			(pts
				(arc
					(start 262.873998 -312.27141)
					(mid 262.888877 -312.307331)
					(end 262.924798 -312.32221)
				)
				(arc
					(start 264.324338 -312.32221)
					(mid 264.360259 -312.307331)
					(end 264.375138 -312.27141)
				)
				(arc
					(start 264.375138 -311.86247)
					(mid 264.360259 -311.826549)
					(end 264.324338 -311.81167)
				)
				(arc
					(start 262.924798 -311.81167)
					(mid 262.888877 -311.826549)
					(end 262.873998 -311.86247)
				)
			)
		)
	)
	(zone
		(layers "In1.Cu" "In2.Cu")
		(hatch none 0.5)
		(connect_pads
			(clearance 0)
		)
		(min_thickness 0.25)
		(keepout
			(tracks not_allowed)
			(vias allowed)
			(pads allowed)
			(copperpour not_allowed)
			(footprints allowed)
		)
		(placement
			(enabled no)
			(sheetname "")
		)
		(fill yes
			(thermal_gap 0.5)
			(thermal_bridge_width 0.5)
			(island_removal_mode 0)
		)
		(polygon
			(pts
				(arc
					(start 207.425798 -311.421526)
					(mid 207.440677 -311.457447)
					(end 207.476598 -311.472326)
				)
				(arc
					(start 208.876138 -311.472326)
					(mid 208.912059 -311.457447)
					(end 208.926938 -311.421526)
				)
				(arc
					(start 208.926938 -311.012586)
					(mid 208.912059 -310.976665)
					(end 208.876138 -310.961786)
				)
				(arc
					(start 207.476598 -310.961786)
					(mid 207.440677 -310.976665)
					(end 207.425798 -311.012586)
				)
			)
		)
	)
	(zone
		(layers "In1.Cu" "In2.Cu")
		(hatch none 0.5)
		(connect_pads
			(clearance 0)
		)
		(min_thickness 0.25)
		(keepout
			(tracks not_allowed)
			(vias allowed)
			(pads allowed)
			(copperpour not_allowed)
			(footprints allowed)
		)
		(placement
			(enabled no)
			(sheetname "")
		)
		(fill yes
			(thermal_gap 0.5)
			(thermal_bridge_width 0.5)
			(island_removal_mode 0)
		)
		(polygon
			(pts
				(arc
					(start 406.002998 -232.371392)
					(mid 406.017877 -232.407313)
					(end 406.053798 -232.422192)
				)
				(arc
					(start 407.453338 -232.422192)
					(mid 407.489259 -232.407313)
					(end 407.504138 -232.371392)
				)
				(arc
					(start 407.504138 -231.962452)
					(mid 407.489259 -231.926531)
					(end 407.453338 -231.911652)
				)
				(arc
					(start 406.053798 -231.911652)
					(mid 406.017877 -231.926531)
					(end 406.002998 -231.962452)
				)
			)
		)
	)
	(zone
		(layers "In1.Cu" "In2.Cu")
		(hatch none 0.5)
		(connect_pads
			(clearance 0)
		)
		(min_thickness 0.25)
		(keepout
			(tracks not_allowed)
			(vias allowed)
			(pads allowed)
			(copperpour not_allowed)
			(footprints allowed)
		)
		(placement
			(enabled no)
			(sheetname "")
		)
		(fill yes
			(thermal_gap 0.5)
			(thermal_bridge_width 0.5)
			(island_removal_mode 0)
		)
		(polygon
			(pts
				(arc
					(start 304.693066 -306.32146)
					(mid 304.707945 -306.357381)
					(end 304.743866 -306.37226)
				)
				(arc
					(start 306.143406 -306.37226)
					(mid 306.179327 -306.357381)
					(end 306.194206 -306.32146)
				)
				(arc
					(start 306.194206 -305.91252)
					(mid 306.179327 -305.876599)
					(end 306.143406 -305.86172)
				)
				(arc
					(start 304.743866 -305.86172)
					(mid 304.707945 -305.876599)
					(end 304.693066 -305.91252)
				)
			)
		)
	)
	(zone
		(layers "In1.Cu" "In2.Cu")
		(hatch none 0.5)
		(connect_pads
			(clearance 0)
		)
		(min_thickness 0.25)
		(keepout
			(tracks not_allowed)
			(vias allowed)
			(pads allowed)
			(copperpour not_allowed)
			(footprints allowed)
		)
		(placement
			(enabled no)
			(sheetname "")
		)
		(fill yes
			(thermal_gap 0.5)
			(thermal_bridge_width 0.5)
			(island_removal_mode 0)
		)
		(polygon
			(pts
				(arc
					(start 443.721998 -249.371358)
					(mid 443.736877 -249.407279)
					(end 443.772798 -249.422158)
				)
				(arc
					(start 445.172338 -249.422158)
					(mid 445.208259 -249.407279)
					(end 445.223138 -249.371358)
				)
				(arc
					(start 445.223138 -248.962418)
					(mid 445.208259 -248.926497)
					(end 445.172338 -248.911618)
				)
				(arc
					(start 443.772798 -248.911618)
					(mid 443.736877 -248.926497)
					(end 443.721998 -248.962418)
				)
			)
		)
	)
	(zone
		(layers "In1.Cu" "In2.Cu")
		(hatch none 0.5)
		(connect_pads
			(clearance 0)
		)
		(min_thickness 0.25)
		(keepout
			(tracks not_allowed)
			(vias allowed)
			(pads allowed)
			(copperpour not_allowed)
			(footprints allowed)
		)
		(placement
			(enabled no)
			(sheetname "")
		)
		(fill yes
			(thermal_gap 0.5)
			(thermal_bridge_width 0.5)
			(island_removal_mode 0)
		)
		(polygon
			(pts
				(arc
					(start 199.881998 -302.921416)
					(mid 199.896877 -302.957337)
					(end 199.932798 -302.972216)
				)
				(arc
					(start 201.332338 -302.972216)
					(mid 201.368259 -302.957337)
					(end 201.383138 -302.921416)
				)
				(arc
					(start 201.383138 -302.512476)
					(mid 201.368259 -302.476555)
					(end 201.332338 -302.461676)
				)
				(arc
					(start 199.932798 -302.461676)
					(mid 199.896877 -302.476555)
					(end 199.881998 -302.512476)
				)
			)
		)
	)
	(zone
		(layers "In1.Cu" "In2.Cu")
		(hatch none 0.5)
		(connect_pads
			(clearance 0)
		)
		(min_thickness 0.25)
		(keepout
			(tracks not_allowed)
			(vias allowed)
			(pads allowed)
			(copperpour not_allowed)
			(footprints allowed)
		)
		(placement
			(enabled no)
			(sheetname "")
		)
		(fill yes
			(thermal_gap 0.5)
			(thermal_bridge_width 0.5)
			(island_removal_mode 0)
		)
		(polygon
			(pts
				(arc
					(start 210.86953 -296.121328)
					(mid 210.884409 -296.157249)
					(end 210.92033 -296.172128)
				)
				(arc
					(start 212.31987 -296.172128)
					(mid 212.355791 -296.157249)
					(end 212.37067 -296.121328)
				)
				(arc
					(start 212.37067 -295.712388)
					(mid 212.355791 -295.676467)
					(end 212.31987 -295.661588)
				)
				(arc
					(start 210.92033 -295.661588)
					(mid 210.884409 -295.676467)
					(end 210.86953 -295.712388)
				)
			)
		)
	)
	(zone
		(layers "In1.Cu" "In2.Cu")
		(hatch none 0.5)
		(connect_pads
			(clearance 0)
		)
		(min_thickness 0.25)
		(keepout
			(tracks not_allowed)
			(vias allowed)
			(pads allowed)
			(copperpour not_allowed)
			(footprints allowed)
		)
		(placement
			(enabled no)
			(sheetname "")
		)
		(fill yes
			(thermal_gap 0.5)
			(thermal_bridge_width 0.5)
			(island_removal_mode 0)
		)
		(polygon
			(pts
				(arc
					(start 158.06293 -210.27136)
					(mid 158.077809 -210.307281)
					(end 158.11373 -210.32216)
				)
				(arc
					(start 159.51327 -210.32216)
					(mid 159.549191 -210.307281)
					(end 159.56407 -210.27136)
				)
				(arc
					(start 159.56407 -209.86242)
					(mid 159.549191 -209.826499)
					(end 159.51327 -209.81162)
				)
				(arc
					(start 158.11373 -209.81162)
					(mid 158.077809 -209.826499)
					(end 158.06293 -209.86242)
				)
			)
		)
	)
	(zone
		(layers "In1.Cu" "In2.Cu")
		(hatch none 0.5)
		(connect_pads
			(clearance 0)
		)
		(min_thickness 0.25)
		(keepout
			(tracks not_allowed)
			(vias allowed)
			(pads allowed)
			(copperpour not_allowed)
			(footprints allowed)
		)
		(placement
			(enabled no)
			(sheetname "")
		)
		(fill yes
			(thermal_gap 0.5)
			(thermal_bridge_width 0.5)
			(island_removal_mode 0)
		)
		(polygon
			(pts
				(arc
					(start 30.02153 -262.971534)
					(mid 30.036409 -263.007455)
					(end 30.07233 -263.022334)
				)
				(arc
					(start 31.47187 -263.022334)
					(mid 31.507791 -263.007455)
					(end 31.52267 -262.971534)
				)
				(arc
					(start 31.52267 -262.562594)
					(mid 31.507791 -262.526673)
					(end 31.47187 -262.511794)
				)
				(arc
					(start 30.07233 -262.511794)
					(mid 30.036409 -262.526673)
					(end 30.02153 -262.562594)
				)
			)
		)
	)
	(zone
		(layers "In1.Cu" "In2.Cu")
		(hatch none 0.5)
		(connect_pads
			(clearance 0)
		)
		(min_thickness 0.25)
		(keepout
			(tracks not_allowed)
			(vias allowed)
			(pads allowed)
			(copperpour not_allowed)
			(footprints allowed)
		)
		(placement
			(enabled no)
			(sheetname "")
		)
		(fill yes
			(thermal_gap 0.5)
			(thermal_bridge_width 0.5)
			(island_removal_mode 0)
		)
		(polygon
			(pts
				(arc
					(start 26.577798 -199.221344)
					(mid 26.592677 -199.257265)
					(end 26.628598 -199.272144)
				)
				(arc
					(start 28.028138 -199.272144)
					(mid 28.064059 -199.257265)
					(end 28.078938 -199.221344)
				)
				(arc
					(start 28.078938 -198.812404)
					(mid 28.064059 -198.776483)
					(end 28.028138 -198.761604)
				)
				(arc
					(start 26.628598 -198.761604)
					(mid 26.592677 -198.776483)
					(end 26.577798 -198.812404)
				)
			)
		)
	)
	(zone
		(layers "In1.Cu" "In2.Cu")
		(hatch none 0.5)
		(connect_pads
			(clearance 0)
		)
		(min_thickness 0.25)
		(keepout
			(tracks not_allowed)
			(vias allowed)
			(pads allowed)
			(copperpour not_allowed)
			(footprints allowed)
		)
		(placement
			(enabled no)
			(sheetname "")
		)
		(fill yes
			(thermal_gap 0.5)
			(thermal_bridge_width 0.5)
			(island_removal_mode 0)
		)
		(polygon
			(pts
				(arc
					(start 34.121598 -223.871536)
					(mid 34.136477 -223.907457)
					(end 34.172398 -223.922336)
				)
				(arc
					(start 35.571938 -223.922336)
					(mid 35.607859 -223.907457)
					(end 35.622738 -223.871536)
				)
				(arc
					(start 35.622738 -223.462596)
					(mid 35.607859 -223.426675)
					(end 35.571938 -223.411796)
				)
				(arc
					(start 34.172398 -223.411796)
					(mid 34.136477 -223.426675)
					(end 34.121598 -223.462596)
				)
			)
		)
	)
	(zone
		(layers "In1.Cu" "In2.Cu")
		(hatch none 0.5)
		(connect_pads
			(clearance 0)
		)
		(min_thickness 0.25)
		(keepout
			(tracks not_allowed)
			(vias allowed)
			(pads allowed)
			(copperpour not_allowed)
			(footprints allowed)
		)
		(placement
			(enabled no)
			(sheetname "")
		)
		(fill yes
			(thermal_gap 0.5)
			(thermal_bridge_width 0.5)
			(island_removal_mode 0)
		)
		(polygon
			(pts
				(arc
					(start 451.265798 -296.121328)
					(mid 451.280677 -296.157249)
					(end 451.316598 -296.172128)
				)
				(arc
					(start 452.716138 -296.172128)
					(mid 452.752059 -296.157249)
					(end 452.766938 -296.121328)
				)
				(arc
					(start 452.766938 -295.712388)
					(mid 452.752059 -295.676467)
					(end 452.716138 -295.661588)
				)
				(arc
					(start 451.316598 -295.661588)
					(mid 451.280677 -295.676467)
					(end 451.265798 -295.712388)
				)
			)
		)
	)
	(zone
		(layers "In1.Cu" "In2.Cu")
		(hatch none 0.5)
		(connect_pads
			(clearance 0)
		)
		(min_thickness 0.25)
		(keepout
			(tracks not_allowed)
			(vias allowed)
			(pads allowed)
			(copperpour not_allowed)
			(footprints allowed)
		)
		(placement
			(enabled no)
			(sheetname "")
		)
		(fill yes
			(thermal_gap 0.5)
			(thermal_bridge_width 0.5)
			(island_removal_mode 0)
		)
		(polygon
			(pts
				(arc
					(start 293.049198 -241.721386)
					(mid 293.064077 -241.757307)
					(end 293.099998 -241.772186)
				)
				(arc
					(start 294.499538 -241.772186)
					(mid 294.535459 -241.757307)
					(end 294.550338 -241.721386)
				)
				(arc
					(start 294.550338 -241.312446)
					(mid 294.535459 -241.276525)
					(end 294.499538 -241.261646)
				)
				(arc
					(start 293.099998 -241.261646)
					(mid 293.064077 -241.276525)
					(end 293.049198 -241.312446)
				)
			)
		)
	)
	(zone
		(layers "In1.Cu" "In2.Cu")
		(hatch none 0.5)
		(connect_pads
			(clearance 0)
		)
		(min_thickness 0.25)
		(keepout
			(tracks not_allowed)
			(vias allowed)
			(pads allowed)
			(copperpour not_allowed)
			(footprints allowed)
		)
		(placement
			(enabled no)
			(sheetname "")
		)
		(fill yes
			(thermal_gap 0.5)
			(thermal_bridge_width 0.5)
			(island_removal_mode 0)
		)
		(polygon
			(pts
				(arc
					(start 56.752998 -233.22153)
					(mid 56.767877 -233.257451)
					(end 56.803798 -233.27233)
				)
				(arc
					(start 58.203338 -233.27233)
					(mid 58.239259 -233.257451)
					(end 58.254138 -233.22153)
				)
				(arc
					(start 58.254138 -232.81259)
					(mid 58.239259 -232.776669)
					(end 58.203338 -232.76179)
				)
				(arc
					(start 56.803798 -232.76179)
					(mid 56.767877 -232.776669)
					(end 56.752998 -232.81259)
				)
			)
		)
	)
	(zone
		(layers "In1.Cu" "In2.Cu")
		(hatch none 0.5)
		(connect_pads
			(clearance 0)
		)
		(min_thickness 0.25)
		(keepout
			(tracks not_allowed)
			(vias allowed)
			(pads allowed)
			(copperpour not_allowed)
			(footprints allowed)
		)
		(placement
			(enabled no)
			(sheetname "")
		)
		(fill yes
			(thermal_gap 0.5)
			(thermal_bridge_width 0.5)
			(island_removal_mode 0)
		)
		(polygon
			(pts
				(arc
					(start 406.002998 -284.221428)
					(mid 406.017877 -284.257349)
					(end 406.053798 -284.272228)
				)
				(arc
					(start 407.453338 -284.272228)
					(mid 407.489259 -284.257349)
					(end 407.504138 -284.221428)
				)
				(arc
					(start 407.504138 -283.812488)
					(mid 407.489259 -283.776567)
					(end 407.453338 -283.761688)
				)
				(arc
					(start 406.053798 -283.761688)
					(mid 406.017877 -283.776567)
					(end 406.002998 -283.812488)
				)
			)
		)
	)
	(zone
		(layers "In1.Cu" "In2.Cu")
		(hatch none 0.5)
		(connect_pads
			(clearance 0)
		)
		(min_thickness 0.25)
		(keepout
			(tracks not_allowed)
			(vias allowed)
			(pads allowed)
			(copperpour not_allowed)
			(footprints allowed)
		)
		(placement
			(enabled no)
			(sheetname "")
		)
		(fill yes
			(thermal_gap 0.5)
			(thermal_bridge_width 0.5)
			(island_removal_mode 0)
		)
		(polygon
			(pts
				(arc
					(start 458.809598 -252.771402)
					(mid 458.824477 -252.807323)
					(end 458.860398 -252.822202)
				)
				(arc
					(start 460.259938 -252.822202)
					(mid 460.295859 -252.807323)
					(end 460.310738 -252.771402)
				)
				(arc
					(start 460.310738 -252.362462)
					(mid 460.295859 -252.326541)
					(end 460.259938 -252.311662)
				)
				(arc
					(start 458.860398 -252.311662)
					(mid 458.824477 -252.326541)
					(end 458.809598 -252.362462)
				)
			)
		)
	)
	(zone
		(layers "In1.Cu" "In2.Cu")
		(hatch none 0.5)
		(connect_pads
			(clearance 0)
		)
		(min_thickness 0.25)
		(keepout
			(tracks not_allowed)
			(vias allowed)
			(pads allowed)
			(copperpour not_allowed)
			(footprints allowed)
		)
		(placement
			(enabled no)
			(sheetname "")
		)
		(fill yes
			(thermal_gap 0.5)
			(thermal_bridge_width 0.5)
			(island_removal_mode 0)
		)
		(polygon
			(pts
				(arc
					(start 26.577798 -274.02155)
					(mid 26.592677 -274.057471)
					(end 26.628598 -274.07235)
				)
				(arc
					(start 28.028138 -274.07235)
					(mid 28.064059 -274.057471)
					(end 28.078938 -274.02155)
				)
				(arc
					(start 28.078938 -273.61261)
					(mid 28.064059 -273.576689)
					(end 28.028138 -273.56181)
				)
				(arc
					(start 26.628598 -273.56181)
					(mid 26.592677 -273.576689)
					(end 26.577798 -273.61261)
				)
			)
		)
	)
	(zone
		(layers "In1.Cu" "In2.Cu")
		(hatch none 0.5)
		(connect_pads
			(clearance 0)
		)
		(min_thickness 0.25)
		(keepout
			(tracks not_allowed)
			(vias allowed)
			(pads allowed)
			(copperpour not_allowed)
			(footprints allowed)
		)
		(placement
			(enabled no)
			(sheetname "")
		)
		(fill yes
			(thermal_gap 0.5)
			(thermal_bridge_width 0.5)
			(island_removal_mode 0)
		)
		(polygon
			(pts
				(arc
					(start 158.06293 -284.221428)
					(mid 158.077809 -284.257349)
					(end 158.11373 -284.272228)
				)
				(arc
					(start 159.51327 -284.272228)
					(mid 159.549191 -284.257349)
					(end 159.56407 -284.221428)
				)
				(arc
					(start 159.56407 -283.812488)
					(mid 159.549191 -283.776567)
					(end 159.51327 -283.761688)
				)
				(arc
					(start 158.11373 -283.761688)
					(mid 158.077809 -283.776567)
					(end 158.06293 -283.812488)
				)
			)
		)
	)
	(zone
		(layers "In1.Cu" "In2.Cu")
		(hatch none 0.5)
		(connect_pads
			(clearance 0)
		)
		(min_thickness 0.25)
		(keepout
			(tracks not_allowed)
			(vias allowed)
			(pads allowed)
			(copperpour not_allowed)
			(footprints allowed)
		)
		(placement
			(enabled no)
			(sheetname "")
		)
		(fill yes
			(thermal_gap 0.5)
			(thermal_bridge_width 0.5)
			(island_removal_mode 0)
		)
		(polygon
			(pts
				(arc
					(start 277.961598 -230.67137)
					(mid 277.976477 -230.707291)
					(end 278.012398 -230.72217)
				)
				(arc
					(start 279.411938 -230.72217)
					(mid 279.447859 -230.707291)
					(end 279.462738 -230.67137)
				)
				(arc
					(start 279.462738 -230.26243)
					(mid 279.447859 -230.226509)
					(end 279.411938 -230.21163)
				)
				(arc
					(start 278.012398 -230.21163)
					(mid 277.976477 -230.226509)
					(end 277.961598 -230.26243)
				)
			)
		)
	)
	(zone
		(layers "In1.Cu" "In2.Cu")
		(hatch none 0.5)
		(connect_pads
			(clearance 0)
		)
		(min_thickness 0.25)
		(keepout
			(tracks not_allowed)
			(vias allowed)
			(pads allowed)
			(copperpour not_allowed)
			(footprints allowed)
		)
		(placement
			(enabled no)
			(sheetname "")
		)
		(fill yes
			(thermal_gap 0.5)
			(thermal_bridge_width 0.5)
			(island_removal_mode 0)
		)
		(polygon
			(pts
				(arc
					(start 22.47773 -196.671438)
					(mid 22.492609 -196.707359)
					(end 22.52853 -196.722238)
				)
				(arc
					(start 23.92807 -196.722238)
					(mid 23.963991 -196.707359)
					(end 23.97887 -196.671438)
				)
				(arc
					(start 23.97887 -196.262498)
					(mid 23.963991 -196.226577)
					(end 23.92807 -196.211698)
				)
				(arc
					(start 22.52853 -196.211698)
					(mid 22.492609 -196.226577)
					(end 22.47773 -196.262498)
				)
			)
		)
	)
	(zone
		(layers "In1.Cu" "In2.Cu")
		(hatch none 0.5)
		(connect_pads
			(clearance 0)
		)
		(min_thickness 0.25)
		(keepout
			(tracks not_allowed)
			(vias allowed)
			(pads allowed)
			(copperpour not_allowed)
			(footprints allowed)
		)
		(placement
			(enabled no)
			(sheetname "")
		)
		(fill yes
			(thermal_gap 0.5)
			(thermal_bridge_width 0.5)
			(island_removal_mode 0)
		)
		(polygon
			(pts
				(arc
					(start 188.23813 -200.921366)
					(mid 188.253009 -200.957287)
					(end 188.28893 -200.972166)
				)
				(arc
					(start 189.68847 -200.972166)
					(mid 189.724391 -200.957287)
					(end 189.73927 -200.921366)
				)
				(arc
					(start 189.73927 -200.512426)
					(mid 189.724391 -200.476505)
					(end 189.68847 -200.461626)
				)
				(arc
					(start 188.28893 -200.461626)
					(mid 188.253009 -200.476505)
					(end 188.23813 -200.512426)
				)
			)
		)
	)
	(zone
		(layers "In1.Cu" "In2.Cu")
		(hatch none 0.5)
		(connect_pads
			(clearance 0)
		)
		(min_thickness 0.25)
		(keepout
			(tracks not_allowed)
			(vias allowed)
			(pads allowed)
			(copperpour not_allowed)
			(footprints allowed)
		)
		(placement
			(enabled no)
			(sheetname "")
		)
		(fill yes
			(thermal_gap 0.5)
			(thermal_bridge_width 0.5)
			(island_removal_mode 0)
		)
		(polygon
			(pts
				(arc
					(start 443.721998 -259.57149)
					(mid 443.736877 -259.607411)
					(end 443.772798 -259.62229)
				)
				(arc
					(start 445.172338 -259.62229)
					(mid 445.208259 -259.607411)
					(end 445.223138 -259.57149)
				)
				(arc
					(start 445.223138 -259.16255)
					(mid 445.208259 -259.126629)
					(end 445.172338 -259.11175)
				)
				(arc
					(start 443.772798 -259.11175)
					(mid 443.736877 -259.126629)
					(end 443.721998 -259.16255)
				)
			)
		)
	)
	(zone
		(layers "In1.Cu" "In2.Cu")
		(hatch none 0.5)
		(connect_pads
			(clearance 0)
		)
		(min_thickness 0.25)
		(keepout
			(tracks not_allowed)
			(vias allowed)
			(pads allowed)
			(copperpour not_allowed)
			(footprints allowed)
		)
		(placement
			(enabled no)
			(sheetname "")
		)
		(fill yes
			(thermal_gap 0.5)
			(thermal_bridge_width 0.5)
			(island_removal_mode 0)
		)
		(polygon
			(pts
				(arc
					(start 41.665398 -225.571304)
					(mid 41.680277 -225.607225)
					(end 41.716198 -225.622104)
				)
				(arc
					(start 43.115738 -225.622104)
					(mid 43.151659 -225.607225)
					(end 43.166538 -225.571304)
				)
				(arc
					(start 43.166538 -225.162364)
					(mid 43.151659 -225.126443)
					(end 43.115738 -225.111564)
				)
				(arc
					(start 41.716198 -225.111564)
					(mid 41.680277 -225.126443)
					(end 41.665398 -225.162364)
				)
			)
		)
	)
	(zone
		(layers "In1.Cu" "In2.Cu")
		(hatch none 0.5)
		(connect_pads
			(clearance 0)
		)
		(min_thickness 0.25)
		(keepout
			(tracks not_allowed)
			(vias allowed)
			(pads allowed)
			(copperpour not_allowed)
			(footprints allowed)
		)
		(placement
			(enabled no)
			(sheetname "")
		)
		(fill yes
			(thermal_gap 0.5)
			(thermal_bridge_width 0.5)
			(island_removal_mode 0)
		)
		(polygon
			(pts
				(arc
					(start 304.693066 -231.521508)
					(mid 304.707945 -231.557429)
					(end 304.743866 -231.572308)
				)
				(arc
					(start 306.143406 -231.572308)
					(mid 306.179327 -231.557429)
					(end 306.194206 -231.521508)
				)
				(arc
					(start 306.194206 -231.112568)
					(mid 306.179327 -231.076647)
					(end 306.143406 -231.061768)
				)
				(arc
					(start 304.743866 -231.061768)
					(mid 304.707945 -231.076647)
					(end 304.693066 -231.112568)
				)
			)
		)
	)
	(zone
		(layers "In1.Cu" "In2.Cu")
		(hatch none 0.5)
		(connect_pads
			(clearance 0)
		)
		(min_thickness 0.25)
		(keepout
			(tracks not_allowed)
			(vias allowed)
			(pads allowed)
			(copperpour not_allowed)
			(footprints allowed)
		)
		(placement
			(enabled no)
			(sheetname "")
		)
		(fill yes
			(thermal_gap 0.5)
			(thermal_bridge_width 0.5)
			(island_removal_mode 0)
		)
		(polygon
			(pts
				(arc
					(start 203.32573 -297.82135)
					(mid 203.340609 -297.857271)
					(end 203.37653 -297.87215)
				)
				(arc
					(start 204.77607 -297.87215)
					(mid 204.811991 -297.857271)
					(end 204.82687 -297.82135)
				)
				(arc
					(start 204.82687 -297.41241)
					(mid 204.811991 -297.376489)
					(end 204.77607 -297.36161)
				)
				(arc
					(start 203.37653 -297.36161)
					(mid 203.340609 -297.376489)
					(end 203.32573 -297.41241)
				)
			)
		)
	)
	(zone
		(layers "In1.Cu" "In2.Cu")
		(hatch none 0.5)
		(connect_pads
			(clearance 0)
		)
		(min_thickness 0.25)
		(keepout
			(tracks not_allowed)
			(vias allowed)
			(pads allowed)
			(copperpour not_allowed)
			(footprints allowed)
		)
		(placement
			(enabled no)
			(sheetname "")
		)
		(fill yes
			(thermal_gap 0.5)
			(thermal_bridge_width 0.5)
			(island_removal_mode 0)
		)
		(polygon
			(pts
				(arc
					(start 432.734466 -209.421476)
					(mid 432.749345 -209.457397)
					(end 432.785266 -209.472276)
				)
				(arc
					(start 434.184806 -209.472276)
					(mid 434.220727 -209.457397)
					(end 434.235606 -209.421476)
				)
				(arc
					(start 434.235606 -209.012536)
					(mid 434.220727 -208.976615)
					(end 434.184806 -208.961736)
				)
				(arc
					(start 432.785266 -208.961736)
					(mid 432.749345 -208.976615)
					(end 432.734466 -209.012536)
				)
			)
		)
	)
	(zone
		(layers "In1.Cu" "In2.Cu")
		(hatch none 0.5)
		(connect_pads
			(clearance 0)
		)
		(min_thickness 0.25)
		(keepout
			(tracks not_allowed)
			(vias allowed)
			(pads allowed)
			(copperpour not_allowed)
			(footprints allowed)
		)
		(placement
			(enabled no)
			(sheetname "")
		)
		(fill yes
			(thermal_gap 0.5)
			(thermal_bridge_width 0.5)
			(island_removal_mode 0)
		)
		(polygon
			(pts
				(arc
					(start 64.296798 -248.521474)
					(mid 64.311677 -248.557395)
					(end 64.347598 -248.572274)
				)
				(arc
					(start 65.747138 -248.572274)
					(mid 65.783059 -248.557395)
					(end 65.797938 -248.521474)
				)
				(arc
					(start 65.797938 -248.112534)
					(mid 65.783059 -248.076613)
					(end 65.747138 -248.061734)
				)
				(arc
					(start 64.347598 -248.061734)
					(mid 64.311677 -248.076613)
					(end 64.296798 -248.112534)
				)
			)
		)
	)
	(zone
		(layers "In1.Cu" "In2.Cu")
		(hatch none 0.5)
		(connect_pads
			(clearance 0)
		)
		(min_thickness 0.25)
		(keepout
			(tracks not_allowed)
			(vias allowed)
			(pads allowed)
			(copperpour not_allowed)
			(footprints allowed)
		)
		(placement
			(enabled no)
			(sheetname "")
		)
		(fill yes
			(thermal_gap 0.5)
			(thermal_bridge_width 0.5)
			(island_removal_mode 0)
		)
		(polygon
			(pts
				(arc
					(start 447.822066 -259.57149)
					(mid 447.836945 -259.607411)
					(end 447.872866 -259.62229)
				)
				(arc
					(start 449.272406 -259.62229)
					(mid 449.308327 -259.607411)
					(end 449.323206 -259.57149)
				)
				(arc
					(start 449.323206 -259.16255)
					(mid 449.308327 -259.126629)
					(end 449.272406 -259.11175)
				)
				(arc
					(start 447.872866 -259.11175)
					(mid 447.836945 -259.126629)
					(end 447.822066 -259.16255)
				)
			)
		)
	)
	(zone
		(layers "In1.Cu" "In2.Cu")
		(hatch none 0.5)
		(connect_pads
			(clearance 0)
		)
		(min_thickness 0.25)
		(keepout
			(tracks not_allowed)
			(vias allowed)
			(pads allowed)
			(copperpour not_allowed)
			(footprints allowed)
		)
		(placement
			(enabled no)
			(sheetname "")
		)
		(fill yes
			(thermal_gap 0.5)
			(thermal_bridge_width 0.5)
			(island_removal_mode 0)
		)
		(polygon
			(pts
				(arc
					(start 41.665398 -279.9715)
					(mid 41.680277 -280.007421)
					(end 41.716198 -280.0223)
				)
				(arc
					(start 43.115738 -280.0223)
					(mid 43.151659 -280.007421)
					(end 43.166538 -279.9715)
				)
				(arc
					(start 43.166538 -279.56256)
					(mid 43.151659 -279.526639)
					(end 43.115738 -279.51176)
				)
				(arc
					(start 41.716198 -279.51176)
					(mid 41.680277 -279.526639)
					(end 41.665398 -279.56256)
				)
			)
		)
	)
	(zone
		(layers "In1.Cu" "In2.Cu")
		(hatch none 0.5)
		(connect_pads
			(clearance 0)
		)
		(min_thickness 0.25)
		(keepout
			(tracks not_allowed)
			(vias allowed)
			(pads allowed)
			(copperpour not_allowed)
			(footprints allowed)
		)
		(placement
			(enabled no)
			(sheetname "")
		)
		(fill yes
			(thermal_gap 0.5)
			(thermal_bridge_width 0.5)
			(island_removal_mode 0)
		)
		(polygon
			(pts
				(arc
					(start 45.10913 -310.571388)
					(mid 45.124009 -310.607309)
					(end 45.15993 -310.622188)
				)
				(arc
					(start 46.55947 -310.622188)
					(mid 46.595391 -310.607309)
					(end 46.61027 -310.571388)
				)
				(arc
					(start 46.61027 -310.162448)
					(mid 46.595391 -310.126527)
					(end 46.55947 -310.111648)
				)
				(arc
					(start 45.15993 -310.111648)
					(mid 45.124009 -310.126527)
					(end 45.10913 -310.162448)
				)
			)
		)
	)
	(zone
		(layers "In1.Cu" "In2.Cu")
		(hatch none 0.5)
		(connect_pads
			(clearance 0)
		)
		(min_thickness 0.25)
		(keepout
			(tracks not_allowed)
			(vias allowed)
			(pads allowed)
			(copperpour not_allowed)
			(footprints allowed)
		)
		(placement
			(enabled no)
			(sheetname "")
		)
		(fill yes
			(thermal_gap 0.5)
			(thermal_bridge_width 0.5)
			(island_removal_mode 0)
		)
		(polygon
			(pts
				(arc
					(start 255.330198 -219.621354)
					(mid 255.345077 -219.657275)
					(end 255.380998 -219.672154)
				)
				(arc
					(start 256.780538 -219.672154)
					(mid 256.816459 -219.657275)
					(end 256.831338 -219.621354)
				)
				(arc
					(start 256.831338 -219.212414)
					(mid 256.816459 -219.176493)
					(end 256.780538 -219.161614)
				)
				(arc
					(start 255.380998 -219.161614)
					(mid 255.345077 -219.176493)
					(end 255.330198 -219.212414)
				)
			)
		)
	)
	(zone
		(layers "In1.Cu" "In2.Cu")
		(hatch none 0.5)
		(connect_pads
			(clearance 0)
		)
		(min_thickness 0.25)
		(keepout
			(tracks not_allowed)
			(vias allowed)
			(pads allowed)
			(copperpour not_allowed)
			(footprints allowed)
		)
		(placement
			(enabled no)
			(sheetname "")
		)
		(fill yes
			(thermal_gap 0.5)
			(thermal_bridge_width 0.5)
			(island_removal_mode 0)
		)
		(polygon
			(pts
				(arc
					(start 270.417798 -213.671404)
					(mid 270.432677 -213.707325)
					(end 270.468598 -213.722204)
				)
				(arc
					(start 271.868138 -213.722204)
					(mid 271.904059 -213.707325)
					(end 271.918938 -213.671404)
				)
				(arc
					(start 271.918938 -213.262464)
					(mid 271.904059 -213.226543)
					(end 271.868138 -213.211664)
				)
				(arc
					(start 270.468598 -213.211664)
					(mid 270.432677 -213.226543)
					(end 270.417798 -213.262464)
				)
			)
		)
	)
	(zone
		(layers "In1.Cu" "In2.Cu")
		(hatch none 0.5)
		(connect_pads
			(clearance 0)
		)
		(min_thickness 0.25)
		(keepout
			(tracks not_allowed)
			(vias allowed)
			(pads allowed)
			(copperpour not_allowed)
			(footprints allowed)
		)
		(placement
			(enabled no)
			(sheetname "")
		)
		(fill yes
			(thermal_gap 0.5)
			(thermal_bridge_width 0.5)
			(island_removal_mode 0)
		)
		(polygon
			(pts
				(arc
					(start 462.909666 -197.521322)
					(mid 462.924545 -197.557243)
					(end 462.960466 -197.572122)
				)
				(arc
					(start 464.360006 -197.572122)
					(mid 464.395927 -197.557243)
					(end 464.410806 -197.521322)
				)
				(arc
					(start 464.410806 -197.112382)
					(mid 464.395927 -197.076461)
					(end 464.360006 -197.061582)
				)
				(arc
					(start 462.960466 -197.061582)
					(mid 462.924545 -197.076461)
					(end 462.909666 -197.112382)
				)
			)
		)
	)
	(zone
		(layers "In1.Cu" "In2.Cu")
		(hatch none 0.5)
		(connect_pads
			(clearance 0)
		)
		(min_thickness 0.25)
		(keepout
			(tracks not_allowed)
			(vias allowed)
			(pads allowed)
			(copperpour not_allowed)
			(footprints allowed)
		)
		(placement
			(enabled no)
			(sheetname "")
		)
		(fill yes
			(thermal_gap 0.5)
			(thermal_bridge_width 0.5)
			(island_removal_mode 0)
		)
		(polygon
			(pts
				(arc
					(start 443.721998 -213.671404)
					(mid 443.736877 -213.707325)
					(end 443.772798 -213.722204)
				)
				(arc
					(start 445.172338 -213.722204)
					(mid 445.208259 -213.707325)
					(end 445.223138 -213.671404)
				)
				(arc
					(start 445.223138 -213.262464)
					(mid 445.208259 -213.226543)
					(end 445.172338 -213.211664)
				)
				(arc
					(start 443.772798 -213.211664)
					(mid 443.736877 -213.226543)
					(end 443.721998 -213.262464)
				)
			)
		)
	)
	(zone
		(layers "In1.Cu" "In2.Cu")
		(hatch none 0.5)
		(connect_pads
			(clearance 0)
		)
		(min_thickness 0.25)
		(keepout
			(tracks not_allowed)
			(vias allowed)
			(pads allowed)
			(copperpour not_allowed)
			(footprints allowed)
		)
		(placement
			(enabled no)
			(sheetname "")
		)
		(fill yes
			(thermal_gap 0.5)
			(thermal_bridge_width 0.5)
			(island_removal_mode 0)
		)
		(polygon
			(pts
				(arc
					(start 214.969598 -281.671522)
					(mid 214.984477 -281.707443)
					(end 215.020398 -281.722322)
				)
				(arc
					(start 216.419938 -281.722322)
					(mid 216.455859 -281.707443)
					(end 216.470738 -281.671522)
				)
				(arc
					(start 216.470738 -281.262582)
					(mid 216.455859 -281.226661)
					(end 216.419938 -281.211782)
				)
				(arc
					(start 215.020398 -281.211782)
					(mid 214.984477 -281.226661)
					(end 214.969598 -281.262582)
				)
			)
		)
	)
	(zone
		(layers "In1.Cu" "In2.Cu")
		(hatch none 0.5)
		(connect_pads
			(clearance 0)
		)
		(min_thickness 0.25)
		(keepout
			(tracks not_allowed)
			(vias allowed)
			(pads allowed)
			(copperpour not_allowed)
			(footprints allowed)
		)
		(placement
			(enabled no)
			(sheetname "")
		)
		(fill yes
			(thermal_gap 0.5)
			(thermal_bridge_width 0.5)
			(island_removal_mode 0)
		)
		(polygon
			(pts
				(arc
					(start 210.86953 -202.621388)
					(mid 210.884409 -202.657309)
					(end 210.92033 -202.672188)
				)
				(arc
					(start 212.31987 -202.672188)
					(mid 212.355791 -202.657309)
					(end 212.37067 -202.621388)
				)
				(arc
					(start 212.37067 -202.212448)
					(mid 212.355791 -202.176527)
					(end 212.31987 -202.161648)
				)
				(arc
					(start 210.92033 -202.161648)
					(mid 210.884409 -202.176527)
					(end 210.86953 -202.212448)
				)
			)
		)
	)
	(zone
		(layers "In1.Cu" "In2.Cu")
		(hatch none 0.5)
		(connect_pads
			(clearance 0)
		)
		(min_thickness 0.25)
		(keepout
			(tracks not_allowed)
			(vias allowed)
			(pads allowed)
			(copperpour not_allowed)
			(footprints allowed)
		)
		(placement
			(enabled no)
			(sheetname "")
		)
		(fill yes
			(thermal_gap 0.5)
			(thermal_bridge_width 0.5)
			(island_removal_mode 0)
		)
		(polygon
			(pts
				(arc
					(start 304.693066 -311.421526)
					(mid 304.707945 -311.457447)
					(end 304.743866 -311.472326)
				)
				(arc
					(start 306.143406 -311.472326)
					(mid 306.179327 -311.457447)
					(end 306.194206 -311.421526)
				)
				(arc
					(start 306.194206 -311.012586)
					(mid 306.179327 -310.976665)
					(end 306.143406 -310.961786)
				)
				(arc
					(start 304.743866 -310.961786)
					(mid 304.707945 -310.976665)
					(end 304.693066 -311.012586)
				)
			)
		)
	)
	(zone
		(layers "In1.Cu" "In2.Cu")
		(hatch none 0.5)
		(connect_pads
			(clearance 0)
		)
		(min_thickness 0.25)
		(keepout
			(tracks not_allowed)
			(vias allowed)
			(pads allowed)
			(copperpour not_allowed)
			(footprints allowed)
		)
		(placement
			(enabled no)
			(sheetname "")
		)
		(fill yes
			(thermal_gap 0.5)
			(thermal_bridge_width 0.5)
			(island_removal_mode 0)
		)
		(polygon
			(pts
				(arc
					(start 410.103066 -287.621472)
					(mid 410.117945 -287.657393)
					(end 410.153866 -287.672272)
				)
				(arc
					(start 411.553406 -287.672272)
					(mid 411.589327 -287.657393)
					(end 411.604206 -287.621472)
				)
				(arc
					(start 411.604206 -287.212532)
					(mid 411.589327 -287.176611)
					(end 411.553406 -287.161732)
				)
				(arc
					(start 410.153866 -287.161732)
					(mid 410.117945 -287.176611)
					(end 410.103066 -287.212532)
				)
			)
		)
	)
	(zone
		(layers "In1.Cu" "In2.Cu")
		(hatch none 0.5)
		(connect_pads
			(clearance 0)
		)
		(min_thickness 0.25)
		(keepout
			(tracks not_allowed)
			(vias allowed)
			(pads allowed)
			(copperpour not_allowed)
			(footprints allowed)
		)
		(placement
			(enabled no)
			(sheetname "")
		)
		(fill yes
			(thermal_gap 0.5)
			(thermal_bridge_width 0.5)
			(island_removal_mode 0)
		)
		(polygon
			(pts
				(arc
					(start 440.278266 -229.821486)
					(mid 440.293145 -229.857407)
					(end 440.329066 -229.872286)
				)
				(arc
					(start 441.728606 -229.872286)
					(mid 441.764527 -229.857407)
					(end 441.779406 -229.821486)
				)
				(arc
					(start 441.779406 -229.412546)
					(mid 441.764527 -229.376625)
					(end 441.728606 -229.361746)
				)
				(arc
					(start 440.329066 -229.361746)
					(mid 440.293145 -229.376625)
					(end 440.278266 -229.412546)
				)
			)
		)
	)
	(zone
		(layers "In1.Cu" "In2.Cu")
		(hatch none 0.5)
		(connect_pads
			(clearance 0)
		)
		(min_thickness 0.25)
		(keepout
			(tracks not_allowed)
			(vias allowed)
			(pads allowed)
			(copperpour not_allowed)
			(footprints allowed)
		)
		(placement
			(enabled no)
			(sheetname "")
		)
		(fill yes
			(thermal_gap 0.5)
			(thermal_bridge_width 0.5)
			(island_removal_mode 0)
		)
		(polygon
			(pts
				(arc
					(start 60.19673 -226.421442)
					(mid 60.211609 -226.457363)
					(end 60.24753 -226.472242)
				)
				(arc
					(start 61.64707 -226.472242)
					(mid 61.682991 -226.457363)
					(end 61.69787 -226.421442)
				)
				(arc
					(start 61.69787 -226.012502)
					(mid 61.682991 -225.976581)
					(end 61.64707 -225.961702)
				)
				(arc
					(start 60.24753 -225.961702)
					(mid 60.211609 -225.976581)
					(end 60.19673 -226.012502)
				)
			)
		)
	)
	(zone
		(layers "In1.Cu" "In2.Cu")
		(hatch none 0.5)
		(connect_pads
			(clearance 0)
		)
		(min_thickness 0.25)
		(keepout
			(tracks not_allowed)
			(vias allowed)
			(pads allowed)
			(copperpour not_allowed)
			(footprints allowed)
		)
		(placement
			(enabled no)
			(sheetname "")
		)
		(fill yes
			(thermal_gap 0.5)
			(thermal_bridge_width 0.5)
			(island_removal_mode 0)
		)
		(polygon
			(pts
				(arc
					(start 169.706798 -212.82152)
					(mid 169.721677 -212.857441)
					(end 169.757598 -212.87232)
				)
				(arc
					(start 171.157138 -212.87232)
					(mid 171.193059 -212.857441)
					(end 171.207938 -212.82152)
				)
				(arc
					(start 171.207938 -212.41258)
					(mid 171.193059 -212.376659)
					(end 171.157138 -212.36178)
				)
				(arc
					(start 169.757598 -212.36178)
					(mid 169.721677 -212.376659)
					(end 169.706798 -212.41258)
				)
			)
		)
	)
	(zone
		(layers "In1.Cu" "In2.Cu")
		(hatch none 0.5)
		(connect_pads
			(clearance 0)
		)
		(min_thickness 0.25)
		(keepout
			(tracks not_allowed)
			(vias allowed)
			(pads allowed)
			(copperpour not_allowed)
			(footprints allowed)
		)
		(placement
			(enabled no)
			(sheetname "")
		)
		(fill yes
			(thermal_gap 0.5)
			(thermal_bridge_width 0.5)
			(island_removal_mode 0)
		)
		(polygon
			(pts
				(arc
					(start 177.250598 -197.521322)
					(mid 177.265477 -197.557243)
					(end 177.301398 -197.572122)
				)
				(arc
					(start 178.700938 -197.572122)
					(mid 178.736859 -197.557243)
					(end 178.751738 -197.521322)
				)
				(arc
					(start 178.751738 -197.112382)
					(mid 178.736859 -197.076461)
					(end 178.700938 -197.061582)
				)
				(arc
					(start 177.301398 -197.061582)
					(mid 177.265477 -197.076461)
					(end 177.250598 -197.112382)
				)
			)
		)
	)
	(zone
		(layers "In1.Cu" "In2.Cu")
		(hatch none 0.5)
		(connect_pads
			(clearance 0)
		)
		(min_thickness 0.25)
		(keepout
			(tracks not_allowed)
			(vias allowed)
			(pads allowed)
			(copperpour not_allowed)
			(footprints allowed)
		)
		(placement
			(enabled no)
			(sheetname "")
		)
		(fill yes
			(thermal_gap 0.5)
			(thermal_bridge_width 0.5)
			(island_removal_mode 0)
		)
		(polygon
			(pts
				(arc
					(start 259.430266 -312.27141)
					(mid 259.445145 -312.307331)
					(end 259.481066 -312.32221)
				)
				(arc
					(start 260.880606 -312.32221)
					(mid 260.916527 -312.307331)
					(end 260.931406 -312.27141)
				)
				(arc
					(start 260.931406 -311.86247)
					(mid 260.916527 -311.826549)
					(end 260.880606 -311.81167)
				)
				(arc
					(start 259.481066 -311.81167)
					(mid 259.445145 -311.826549)
					(end 259.430266 -311.86247)
				)
			)
		)
	)
	(zone
		(layers "In1.Cu" "In2.Cu")
		(hatch none 0.5)
		(connect_pads
			(clearance 0)
		)
		(min_thickness 0.25)
		(keepout
			(tracks not_allowed)
			(vias allowed)
			(pads allowed)
			(copperpour not_allowed)
			(footprints allowed)
		)
		(placement
			(enabled no)
			(sheetname "")
		)
		(fill yes
			(thermal_gap 0.5)
			(thermal_bridge_width 0.5)
			(island_removal_mode 0)
		)
		(polygon
			(pts
				(arc
					(start 177.250598 -259.57149)
					(mid 177.265477 -259.607411)
					(end 177.301398 -259.62229)
				)
				(arc
					(start 178.700938 -259.62229)
					(mid 178.736859 -259.607411)
					(end 178.751738 -259.57149)
				)
				(arc
					(start 178.751738 -259.16255)
					(mid 178.736859 -259.126629)
					(end 178.700938 -259.11175)
				)
				(arc
					(start 177.301398 -259.11175)
					(mid 177.265477 -259.126629)
					(end 177.250598 -259.16255)
				)
			)
		)
	)
	(zone
		(layers "In1.Cu" "In2.Cu")
		(hatch none 0.5)
		(connect_pads
			(clearance 0)
		)
		(min_thickness 0.25)
		(keepout
			(tracks not_allowed)
			(vias allowed)
			(pads allowed)
			(copperpour not_allowed)
			(footprints allowed)
		)
		(placement
			(enabled no)
			(sheetname "")
		)
		(fill yes
			(thermal_gap 0.5)
			(thermal_bridge_width 0.5)
			(island_removal_mode 0)
		)
		(polygon
			(pts
				(arc
					(start 19.033998 -216.22131)
					(mid 19.048877 -216.257231)
					(end 19.084798 -216.27211)
				)
				(arc
					(start 20.484338 -216.27211)
					(mid 20.520259 -216.257231)
					(end 20.535138 -216.22131)
				)
				(arc
					(start 20.535138 -215.81237)
					(mid 20.520259 -215.776449)
					(end 20.484338 -215.76157)
				)
				(arc
					(start 19.084798 -215.76157)
					(mid 19.048877 -215.776449)
					(end 19.033998 -215.81237)
				)
			)
		)
	)
	(zone
		(layers "In1.Cu" "In2.Cu")
		(hatch none 0.5)
		(connect_pads
			(clearance 0)
		)
		(min_thickness 0.25)
		(keepout
			(tracks not_allowed)
			(vias allowed)
			(pads allowed)
			(copperpour not_allowed)
			(footprints allowed)
		)
		(placement
			(enabled no)
			(sheetname "")
		)
		(fill yes
			(thermal_gap 0.5)
			(thermal_bridge_width 0.5)
			(island_removal_mode 0)
		)
		(polygon
			(pts
				(arc
					(start 169.706798 -259.57149)
					(mid 169.721677 -259.607411)
					(end 169.757598 -259.62229)
				)
				(arc
					(start 171.157138 -259.62229)
					(mid 171.193059 -259.607411)
					(end 171.207938 -259.57149)
				)
				(arc
					(start 171.207938 -259.16255)
					(mid 171.193059 -259.126629)
					(end 171.157138 -259.11175)
				)
				(arc
					(start 169.757598 -259.11175)
					(mid 169.721677 -259.126629)
					(end 169.706798 -259.16255)
				)
			)
		)
	)
	(zone
		(layers "In1.Cu" "In2.Cu")
		(hatch none 0.5)
		(connect_pads
			(clearance 0)
		)
		(min_thickness 0.25)
		(keepout
			(tracks not_allowed)
			(vias allowed)
			(pads allowed)
			(copperpour not_allowed)
			(footprints allowed)
		)
		(placement
			(enabled no)
			(sheetname "")
		)
		(fill yes
			(thermal_gap 0.5)
			(thermal_bridge_width 0.5)
			(island_removal_mode 0)
		)
		(polygon
			(pts
				(arc
					(start 162.162998 -260.421374)
					(mid 162.177877 -260.457295)
					(end 162.213798 -260.472174)
				)
				(arc
					(start 163.613338 -260.472174)
					(mid 163.649259 -260.457295)
					(end 163.664138 -260.421374)
				)
				(arc
					(start 163.664138 -260.012434)
					(mid 163.649259 -259.976513)
					(end 163.613338 -259.961634)
				)
				(arc
					(start 162.213798 -259.961634)
					(mid 162.177877 -259.976513)
					(end 162.162998 -260.012434)
				)
			)
		)
	)
	(zone
		(layers "In1.Cu" "In2.Cu")
		(hatch none 0.5)
		(connect_pads
			(clearance 0)
		)
		(min_thickness 0.25)
		(keepout
			(tracks not_allowed)
			(vias allowed)
			(pads allowed)
			(copperpour not_allowed)
			(footprints allowed)
		)
		(placement
			(enabled no)
			(sheetname "")
		)
		(fill yes
			(thermal_gap 0.5)
			(thermal_bridge_width 0.5)
			(island_removal_mode 0)
		)
		(polygon
			(pts
				(arc
					(start 214.969598 -245.12143)
					(mid 214.984477 -245.157351)
					(end 215.020398 -245.17223)
				)
				(arc
					(start 216.419938 -245.17223)
					(mid 216.455859 -245.157351)
					(end 216.470738 -245.12143)
				)
				(arc
					(start 216.470738 -244.71249)
					(mid 216.455859 -244.676569)
					(end 216.419938 -244.66169)
				)
				(arc
					(start 215.020398 -244.66169)
					(mid 214.984477 -244.676569)
					(end 214.969598 -244.71249)
				)
			)
		)
	)
	(zone
		(layers "In1.Cu" "In2.Cu")
		(hatch none 0.5)
		(connect_pads
			(clearance 0)
		)
		(min_thickness 0.25)
		(keepout
			(tracks not_allowed)
			(vias allowed)
			(pads allowed)
			(copperpour not_allowed)
			(footprints allowed)
		)
		(placement
			(enabled no)
			(sheetname "")
		)
		(fill yes
			(thermal_gap 0.5)
			(thermal_bridge_width 0.5)
			(island_removal_mode 0)
		)
		(polygon
			(pts
				(arc
					(start 60.19673 -200.071482)
					(mid 60.211609 -200.107403)
					(end 60.24753 -200.122282)
				)
				(arc
					(start 61.64707 -200.122282)
					(mid 61.682991 -200.107403)
					(end 61.69787 -200.071482)
				)
				(arc
					(start 61.69787 -199.662542)
					(mid 61.682991 -199.626621)
					(end 61.64707 -199.611742)
				)
				(arc
					(start 60.24753 -199.611742)
					(mid 60.211609 -199.626621)
					(end 60.19673 -199.662542)
				)
			)
		)
	)
	(zone
		(layers "In1.Cu" "In2.Cu")
		(hatch none 0.5)
		(connect_pads
			(clearance 0)
		)
		(min_thickness 0.25)
		(keepout
			(tracks not_allowed)
			(vias allowed)
			(pads allowed)
			(copperpour not_allowed)
			(footprints allowed)
		)
		(placement
			(enabled no)
			(sheetname "")
		)
		(fill yes
			(thermal_gap 0.5)
			(thermal_bridge_width 0.5)
			(island_removal_mode 0)
		)
		(polygon
			(pts
				(arc
					(start 49.209198 -217.921332)
					(mid 49.224077 -217.957253)
					(end 49.259998 -217.972132)
				)
				(arc
					(start 50.659538 -217.972132)
					(mid 50.695459 -217.957253)
					(end 50.710338 -217.921332)
				)
				(arc
					(start 50.710338 -217.512392)
					(mid 50.695459 -217.476471)
					(end 50.659538 -217.461592)
				)
				(arc
					(start 49.259998 -217.461592)
					(mid 49.224077 -217.476471)
					(end 49.209198 -217.512392)
				)
			)
		)
	)
	(zone
		(layers "In1.Cu" "In2.Cu")
		(hatch none 0.5)
		(connect_pads
			(clearance 0)
		)
		(min_thickness 0.25)
		(keepout
			(tracks not_allowed)
			(vias allowed)
			(pads allowed)
			(copperpour not_allowed)
			(footprints allowed)
		)
		(placement
			(enabled no)
			(sheetname "")
		)
		(fill yes
			(thermal_gap 0.5)
			(thermal_bridge_width 0.5)
			(island_removal_mode 0)
		)
		(polygon
			(pts
				(arc
					(start 30.02153 -209.421476)
					(mid 30.036409 -209.457397)
					(end 30.07233 -209.472276)
				)
				(arc
					(start 31.47187 -209.472276)
					(mid 31.507791 -209.457397)
					(end 31.52267 -209.421476)
				)
				(arc
					(start 31.52267 -209.012536)
					(mid 31.507791 -208.976615)
					(end 31.47187 -208.961736)
				)
				(arc
					(start 30.07233 -208.961736)
					(mid 30.036409 -208.976615)
					(end 30.02153 -209.012536)
				)
			)
		)
	)
	(zone
		(layers "In1.Cu" "In2.Cu")
		(hatch none 0.5)
		(connect_pads
			(clearance 0)
		)
		(min_thickness 0.25)
		(keepout
			(tracks not_allowed)
			(vias allowed)
			(pads allowed)
			(copperpour not_allowed)
			(footprints allowed)
		)
		(placement
			(enabled no)
			(sheetname "")
		)
		(fill yes
			(thermal_gap 0.5)
			(thermal_bridge_width 0.5)
			(island_removal_mode 0)
		)
		(polygon
			(pts
				(arc
					(start 177.250598 -260.421374)
					(mid 177.265477 -260.457295)
					(end 177.301398 -260.472174)
				)
				(arc
					(start 178.700938 -260.472174)
					(mid 178.736859 -260.457295)
					(end 178.751738 -260.421374)
				)
				(arc
					(start 178.751738 -260.012434)
					(mid 178.736859 -259.976513)
					(end 178.700938 -259.961634)
				)
				(arc
					(start 177.301398 -259.961634)
					(mid 177.265477 -259.976513)
					(end 177.250598 -260.012434)
				)
			)
		)
	)
	(zone
		(layers "In1.Cu" "In2.Cu")
		(hatch none 0.5)
		(connect_pads
			(clearance 0)
		)
		(min_thickness 0.25)
		(keepout
			(tracks not_allowed)
			(vias allowed)
			(pads allowed)
			(copperpour not_allowed)
			(footprints allowed)
		)
		(placement
			(enabled no)
			(sheetname "")
		)
		(fill yes
			(thermal_gap 0.5)
			(thermal_bridge_width 0.5)
			(island_removal_mode 0)
		)
		(polygon
			(pts
				(arc
					(start 34.121598 -285.92145)
					(mid 34.136477 -285.957371)
					(end 34.172398 -285.97225)
				)
				(arc
					(start 35.571938 -285.97225)
					(mid 35.607859 -285.957371)
					(end 35.622738 -285.92145)
				)
				(arc
					(start 35.622738 -285.51251)
					(mid 35.607859 -285.476589)
					(end 35.571938 -285.46171)
				)
				(arc
					(start 34.172398 -285.46171)
					(mid 34.136477 -285.476589)
					(end 34.121598 -285.51251)
				)
			)
		)
	)
	(zone
		(layers "In1.Cu" "In2.Cu")
		(hatch none 0.5)
		(connect_pads
			(clearance 0)
		)
		(min_thickness 0.25)
		(keepout
			(tracks not_allowed)
			(vias allowed)
			(pads allowed)
			(copperpour not_allowed)
			(footprints allowed)
		)
		(placement
			(enabled no)
			(sheetname "")
		)
		(fill yes
			(thermal_gap 0.5)
			(thermal_bridge_width 0.5)
			(island_removal_mode 0)
		)
		(polygon
			(pts
				(arc
					(start 428.634398 -200.921366)
					(mid 428.649277 -200.957287)
					(end 428.685198 -200.972166)
				)
				(arc
					(start 430.084738 -200.972166)
					(mid 430.120659 -200.957287)
					(end 430.135538 -200.921366)
				)
				(arc
					(start 430.135538 -200.512426)
					(mid 430.120659 -200.476505)
					(end 430.084738 -200.461626)
				)
				(arc
					(start 428.685198 -200.461626)
					(mid 428.649277 -200.476505)
					(end 428.634398 -200.512426)
				)
			)
		)
	)
	(zone
		(layers "In1.Cu" "In2.Cu")
		(hatch none 0.5)
		(connect_pads
			(clearance 0)
		)
		(min_thickness 0.25)
		(keepout
			(tracks not_allowed)
			(vias allowed)
			(pads allowed)
			(copperpour not_allowed)
			(footprints allowed)
		)
		(placement
			(enabled no)
			(sheetname "")
		)
		(fill yes
			(thermal_gap 0.5)
			(thermal_bridge_width 0.5)
			(island_removal_mode 0)
		)
		(polygon
			(pts
				(arc
					(start 413.546798 -228.121464)
					(mid 413.561677 -228.157385)
					(end 413.597598 -228.172264)
				)
				(arc
					(start 414.997138 -228.172264)
					(mid 415.033059 -228.157385)
					(end 415.047938 -228.121464)
				)
				(arc
					(start 415.047938 -227.712524)
					(mid 415.033059 -227.676603)
					(end 414.997138 -227.661724)
				)
				(arc
					(start 413.597598 -227.661724)
					(mid 413.561677 -227.676603)
					(end 413.546798 -227.712524)
				)
			)
		)
	)
	(zone
		(layers "In1.Cu" "In2.Cu")
		(hatch none 0.5)
		(connect_pads
			(clearance 0)
		)
		(min_thickness 0.25)
		(keepout
			(tracks not_allowed)
			(vias allowed)
			(pads allowed)
			(copperpour not_allowed)
			(footprints allowed)
		)
		(placement
			(enabled no)
			(sheetname "")
		)
		(fill yes
			(thermal_gap 0.5)
			(thermal_bridge_width 0.5)
			(island_removal_mode 0)
		)
		(polygon
			(pts
				(arc
					(start 285.505398 -226.421442)
					(mid 285.520277 -226.457363)
					(end 285.556198 -226.472242)
				)
				(arc
					(start 286.955738 -226.472242)
					(mid 286.991659 -226.457363)
					(end 287.006538 -226.421442)
				)
				(arc
					(start 287.006538 -226.012502)
					(mid 286.991659 -225.976581)
					(end 286.955738 -225.961702)
				)
				(arc
					(start 285.556198 -225.961702)
					(mid 285.520277 -225.976581)
					(end 285.505398 -226.012502)
				)
			)
		)
	)
	(zone
		(layers "In1.Cu" "In2.Cu")
		(hatch none 0.5)
		(connect_pads
			(clearance 0)
		)
		(min_thickness 0.25)
		(keepout
			(tracks not_allowed)
			(vias allowed)
			(pads allowed)
			(copperpour not_allowed)
			(footprints allowed)
		)
		(placement
			(enabled no)
			(sheetname "")
		)
		(fill yes
			(thermal_gap 0.5)
			(thermal_bridge_width 0.5)
			(island_removal_mode 0)
		)
		(polygon
			(pts
				(arc
					(start 406.002998 -262.971534)
					(mid 406.017877 -263.007455)
					(end 406.053798 -263.022334)
				)
				(arc
					(start 407.453338 -263.022334)
					(mid 407.489259 -263.007455)
					(end 407.504138 -262.971534)
				)
				(arc
					(start 407.504138 -262.562594)
					(mid 407.489259 -262.526673)
					(end 407.453338 -262.511794)
				)
				(arc
					(start 406.053798 -262.511794)
					(mid 406.017877 -262.526673)
					(end 406.002998 -262.562594)
				)
			)
		)
	)
	(zone
		(layers "In1.Cu" "In2.Cu")
		(hatch none 0.5)
		(connect_pads
			(clearance 0)
		)
		(min_thickness 0.25)
		(keepout
			(tracks not_allowed)
			(vias allowed)
			(pads allowed)
			(copperpour not_allowed)
			(footprints allowed)
		)
		(placement
			(enabled no)
			(sheetname "")
		)
		(fill yes
			(thermal_gap 0.5)
			(thermal_bridge_width 0.5)
			(island_removal_mode 0)
		)
		(polygon
			(pts
				(arc
					(start 158.06293 -223.021398)
					(mid 158.077809 -223.057319)
					(end 158.11373 -223.072198)
				)
				(arc
					(start 159.51327 -223.072198)
					(mid 159.549191 -223.057319)
					(end 159.56407 -223.021398)
				)
				(arc
					(start 159.56407 -222.612458)
					(mid 159.549191 -222.576537)
					(end 159.51327 -222.561658)
				)
				(arc
					(start 158.11373 -222.561658)
					(mid 158.077809 -222.576537)
					(end 158.06293 -222.612458)
				)
			)
		)
	)
	(zone
		(layers "In1.Cu" "In2.Cu")
		(hatch none 0.5)
		(connect_pads
			(clearance 0)
		)
		(min_thickness 0.25)
		(keepout
			(tracks not_allowed)
			(vias allowed)
			(pads allowed)
			(copperpour not_allowed)
			(footprints allowed)
		)
		(placement
			(enabled no)
			(sheetname "")
		)
		(fill yes
			(thermal_gap 0.5)
			(thermal_bridge_width 0.5)
			(island_removal_mode 0)
		)
		(polygon
			(pts
				(arc
					(start 22.47773 -268.071346)
					(mid 22.492609 -268.107267)
					(end 22.52853 -268.122146)
				)
				(arc
					(start 23.92807 -268.122146)
					(mid 23.963991 -268.107267)
					(end 23.97887 -268.071346)
				)
				(arc
					(start 23.97887 -267.662406)
					(mid 23.963991 -267.626485)
					(end 23.92807 -267.611606)
				)
				(arc
					(start 22.52853 -267.611606)
					(mid 22.492609 -267.626485)
					(end 22.47773 -267.662406)
				)
			)
		)
	)
	(zone
		(layers "In1.Cu" "In2.Cu")
		(hatch none 0.5)
		(connect_pads
			(clearance 0)
		)
		(min_thickness 0.25)
		(keepout
			(tracks not_allowed)
			(vias allowed)
			(pads allowed)
			(copperpour not_allowed)
			(footprints allowed)
		)
		(placement
			(enabled no)
			(sheetname "")
		)
		(fill yes
			(thermal_gap 0.5)
			(thermal_bridge_width 0.5)
			(island_removal_mode 0)
		)
		(polygon
			(pts
				(arc
					(start 262.873998 -275.721318)
					(mid 262.888877 -275.757239)
					(end 262.924798 -275.772118)
				)
				(arc
					(start 264.324338 -275.772118)
					(mid 264.360259 -275.757239)
					(end 264.375138 -275.721318)
				)
				(arc
					(start 264.375138 -275.312378)
					(mid 264.360259 -275.276457)
					(end 264.324338 -275.261578)
				)
				(arc
					(start 262.924798 -275.261578)
					(mid 262.888877 -275.276457)
					(end 262.873998 -275.312378)
				)
			)
		)
	)
	(zone
		(layers "In1.Cu" "In2.Cu")
		(hatch none 0.5)
		(connect_pads
			(clearance 0)
		)
		(min_thickness 0.25)
		(keepout
			(tracks not_allowed)
			(vias allowed)
			(pads allowed)
			(copperpour not_allowed)
			(footprints allowed)
		)
		(placement
			(enabled no)
			(sheetname "")
		)
		(fill yes
			(thermal_gap 0.5)
			(thermal_bridge_width 0.5)
			(island_removal_mode 0)
		)
		(polygon
			(pts
				(arc
					(start 195.78193 -223.021398)
					(mid 195.796809 -223.057319)
					(end 195.83273 -223.072198)
				)
				(arc
					(start 197.23227 -223.072198)
					(mid 197.268191 -223.057319)
					(end 197.28307 -223.021398)
				)
				(arc
					(start 197.28307 -222.612458)
					(mid 197.268191 -222.576537)
					(end 197.23227 -222.561658)
				)
				(arc
					(start 195.83273 -222.561658)
					(mid 195.796809 -222.576537)
					(end 195.78193 -222.612458)
				)
			)
		)
	)
	(zone
		(layers "In1.Cu" "In2.Cu")
		(hatch none 0.5)
		(connect_pads
			(clearance 0)
		)
		(min_thickness 0.25)
		(keepout
			(tracks not_allowed)
			(vias allowed)
			(pads allowed)
			(copperpour not_allowed)
			(footprints allowed)
		)
		(placement
			(enabled no)
			(sheetname "")
		)
		(fill yes
			(thermal_gap 0.5)
			(thermal_bridge_width 0.5)
			(island_removal_mode 0)
		)
		(polygon
			(pts
				(arc
					(start 30.02153 -297.82135)
					(mid 30.036409 -297.857271)
					(end 30.07233 -297.87215)
				)
				(arc
					(start 31.47187 -297.87215)
					(mid 31.507791 -297.857271)
					(end 31.52267 -297.82135)
				)
				(arc
					(start 31.52267 -297.41241)
					(mid 31.507791 -297.376489)
					(end 31.47187 -297.36161)
				)
				(arc
					(start 30.07233 -297.36161)
					(mid 30.036409 -297.376489)
					(end 30.02153 -297.41241)
				)
			)
		)
	)
	(zone
		(layers "In1.Cu" "In2.Cu")
		(hatch none 0.5)
		(connect_pads
			(clearance 0)
		)
		(min_thickness 0.25)
		(keepout
			(tracks not_allowed)
			(vias allowed)
			(pads allowed)
			(copperpour not_allowed)
			(footprints allowed)
		)
		(placement
			(enabled no)
			(sheetname "")
		)
		(fill yes
			(thermal_gap 0.5)
			(thermal_bridge_width 0.5)
			(island_removal_mode 0)
		)
		(polygon
			(pts
				(arc
					(start 277.961598 -228.121464)
					(mid 277.976477 -228.157385)
					(end 278.012398 -228.172264)
				)
				(arc
					(start 279.411938 -228.172264)
					(mid 279.447859 -228.157385)
					(end 279.462738 -228.121464)
				)
				(arc
					(start 279.462738 -227.712524)
					(mid 279.447859 -227.676603)
					(end 279.411938 -227.661724)
				)
				(arc
					(start 278.012398 -227.661724)
					(mid 277.976477 -227.676603)
					(end 277.961598 -227.712524)
				)
			)
		)
	)
	(zone
		(layers "In1.Cu" "In2.Cu")
		(hatch none 0.5)
		(connect_pads
			(clearance 0)
		)
		(min_thickness 0.25)
		(keepout
			(tracks not_allowed)
			(vias allowed)
			(pads allowed)
			(copperpour not_allowed)
			(footprints allowed)
		)
		(placement
			(enabled no)
			(sheetname "")
		)
		(fill yes
			(thermal_gap 0.5)
			(thermal_bridge_width 0.5)
			(island_removal_mode 0)
		)
		(polygon
			(pts
				(arc
					(start 169.706798 -284.221428)
					(mid 169.721677 -284.257349)
					(end 169.757598 -284.272228)
				)
				(arc
					(start 171.157138 -284.272228)
					(mid 171.193059 -284.257349)
					(end 171.207938 -284.221428)
				)
				(arc
					(start 171.207938 -283.812488)
					(mid 171.193059 -283.776567)
					(end 171.157138 -283.761688)
				)
				(arc
					(start 169.757598 -283.761688)
					(mid 169.721677 -283.776567)
					(end 169.706798 -283.812488)
				)
			)
		)
	)
	(zone
		(layers "In1.Cu" "In2.Cu")
		(hatch none 0.5)
		(connect_pads
			(clearance 0)
		)
		(min_thickness 0.25)
		(keepout
			(tracks not_allowed)
			(vias allowed)
			(pads allowed)
			(copperpour not_allowed)
			(footprints allowed)
		)
		(placement
			(enabled no)
			(sheetname "")
		)
		(fill yes
			(thermal_gap 0.5)
			(thermal_bridge_width 0.5)
			(island_removal_mode 0)
		)
		(polygon
			(pts
				(arc
					(start 165.60673 -271.47139)
					(mid 165.621609 -271.507311)
					(end 165.65753 -271.52219)
				)
				(arc
					(start 167.05707 -271.52219)
					(mid 167.092991 -271.507311)
					(end 167.10787 -271.47139)
				)
				(arc
					(start 167.10787 -271.06245)
					(mid 167.092991 -271.026529)
					(end 167.05707 -271.01165)
				)
				(arc
					(start 165.65753 -271.01165)
					(mid 165.621609 -271.026529)
					(end 165.60673 -271.06245)
				)
			)
		)
	)
	(zone
		(layers "In1.Cu" "In2.Cu")
		(hatch none 0.5)
		(connect_pads
			(clearance 0)
		)
		(min_thickness 0.25)
		(keepout
			(tracks not_allowed)
			(vias allowed)
			(pads allowed)
			(copperpour not_allowed)
			(footprints allowed)
		)
		(placement
			(enabled no)
			(sheetname "")
		)
		(fill yes
			(thermal_gap 0.5)
			(thermal_bridge_width 0.5)
			(island_removal_mode 0)
		)
		(polygon
			(pts
				(arc
					(start 7.39013 -215.371426)
					(mid 7.405009 -215.407347)
					(end 7.44093 -215.422226)
				)
				(arc
					(start 8.84047 -215.422226)
					(mid 8.876391 -215.407347)
					(end 8.89127 -215.371426)
				)
				(arc
					(start 8.89127 -214.962486)
					(mid 8.876391 -214.926565)
					(end 8.84047 -214.911686)
				)
				(arc
					(start 7.44093 -214.911686)
					(mid 7.405009 -214.926565)
					(end 7.39013 -214.962486)
				)
			)
		)
	)
	(zone
		(layers "In1.Cu" "In2.Cu")
		(hatch none 0.5)
		(connect_pads
			(clearance 0)
		)
		(min_thickness 0.25)
		(keepout
			(tracks not_allowed)
			(vias allowed)
			(pads allowed)
			(copperpour not_allowed)
			(footprints allowed)
		)
		(placement
			(enabled no)
			(sheetname "")
		)
		(fill yes
			(thermal_gap 0.5)
			(thermal_bridge_width 0.5)
			(island_removal_mode 0)
		)
		(polygon
			(pts
				(arc
					(start 214.969598 -298.671488)
					(mid 214.984477 -298.707409)
					(end 215.020398 -298.722288)
				)
				(arc
					(start 216.419938 -298.722288)
					(mid 216.455859 -298.707409)
					(end 216.470738 -298.671488)
				)
				(arc
					(start 216.470738 -298.262548)
					(mid 216.455859 -298.226627)
					(end 216.419938 -298.211748)
				)
				(arc
					(start 215.020398 -298.211748)
					(mid 214.984477 -298.226627)
					(end 214.969598 -298.262548)
				)
			)
		)
	)
	(zone
		(layers "In1.Cu" "In2.Cu")
		(hatch none 0.5)
		(connect_pads
			(clearance 0)
		)
		(min_thickness 0.25)
		(keepout
			(tracks not_allowed)
			(vias allowed)
			(pads allowed)
			(copperpour not_allowed)
			(footprints allowed)
		)
		(placement
			(enabled no)
			(sheetname "")
		)
		(fill yes
			(thermal_gap 0.5)
			(thermal_bridge_width 0.5)
			(island_removal_mode 0)
		)
		(polygon
			(pts
				(arc
					(start 432.734466 -237.471458)
					(mid 432.749345 -237.507379)
					(end 432.785266 -237.522258)
				)
				(arc
					(start 434.184806 -237.522258)
					(mid 434.220727 -237.507379)
					(end 434.235606 -237.471458)
				)
				(arc
					(start 434.235606 -237.062518)
					(mid 434.220727 -237.026597)
					(end 434.184806 -237.011718)
				)
				(arc
					(start 432.785266 -237.011718)
					(mid 432.749345 -237.026597)
					(end 432.734466 -237.062518)
				)
			)
		)
	)
	(zone
		(layers "In1.Cu" "In2.Cu")
		(hatch none 0.5)
		(connect_pads
			(clearance 0)
		)
		(min_thickness 0.25)
		(keepout
			(tracks not_allowed)
			(vias allowed)
			(pads allowed)
			(copperpour not_allowed)
			(footprints allowed)
		)
		(placement
			(enabled no)
			(sheetname "")
		)
		(fill yes
			(thermal_gap 0.5)
			(thermal_bridge_width 0.5)
			(island_removal_mode 0)
		)
		(polygon
			(pts
				(arc
					(start 421.090598 -279.121362)
					(mid 421.105477 -279.157283)
					(end 421.141398 -279.172162)
				)
				(arc
					(start 422.540938 -279.172162)
					(mid 422.576859 -279.157283)
					(end 422.591738 -279.121362)
				)
				(arc
					(start 422.591738 -278.712422)
					(mid 422.576859 -278.676501)
					(end 422.540938 -278.661622)
				)
				(arc
					(start 421.141398 -278.661622)
					(mid 421.105477 -278.676501)
					(end 421.090598 -278.712422)
				)
			)
		)
	)
	(zone
		(layers "In1.Cu" "In2.Cu")
		(hatch none 0.5)
		(connect_pads
			(clearance 0)
		)
		(min_thickness 0.25)
		(keepout
			(tracks not_allowed)
			(vias allowed)
			(pads allowed)
			(copperpour not_allowed)
			(footprints allowed)
		)
		(placement
			(enabled no)
			(sheetname "")
		)
		(fill yes
			(thermal_gap 0.5)
			(thermal_bridge_width 0.5)
			(island_removal_mode 0)
		)
		(polygon
			(pts
				(arc
					(start 41.665398 -274.02155)
					(mid 41.680277 -274.057471)
					(end 41.716198 -274.07235)
				)
				(arc
					(start 43.115738 -274.07235)
					(mid 43.151659 -274.057471)
					(end 43.166538 -274.02155)
				)
				(arc
					(start 43.166538 -273.61261)
					(mid 43.151659 -273.576689)
					(end 43.115738 -273.56181)
				)
				(arc
					(start 41.716198 -273.56181)
					(mid 41.680277 -273.576689)
					(end 41.665398 -273.61261)
				)
			)
		)
	)
	(zone
		(layers "In1.Cu" "In2.Cu")
		(hatch none 0.5)
		(connect_pads
			(clearance 0)
		)
		(min_thickness 0.25)
		(keepout
			(tracks not_allowed)
			(vias allowed)
			(pads allowed)
			(copperpour not_allowed)
			(footprints allowed)
		)
		(placement
			(enabled no)
			(sheetname "")
		)
		(fill yes
			(thermal_gap 0.5)
			(thermal_bridge_width 0.5)
			(island_removal_mode 0)
		)
		(polygon
			(pts
				(arc
					(start 203.32573 -261.271512)
					(mid 203.340609 -261.307433)
					(end 203.37653 -261.322312)
				)
				(arc
					(start 204.77607 -261.322312)
					(mid 204.811991 -261.307433)
					(end 204.82687 -261.271512)
				)
				(arc
					(start 204.82687 -260.862572)
					(mid 204.811991 -260.826651)
					(end 204.77607 -260.811772)
				)
				(arc
					(start 203.37653 -260.811772)
					(mid 203.340609 -260.826651)
					(end 203.32573 -260.862572)
				)
			)
		)
	)
	(zone
		(layers "In1.Cu" "In2.Cu")
		(hatch none 0.5)
		(connect_pads
			(clearance 0)
		)
		(min_thickness 0.25)
		(keepout
			(tracks not_allowed)
			(vias allowed)
			(pads allowed)
			(copperpour not_allowed)
			(footprints allowed)
		)
		(placement
			(enabled no)
			(sheetname "")
		)
		(fill yes
			(thermal_gap 0.5)
			(thermal_bridge_width 0.5)
			(island_removal_mode 0)
		)
		(polygon
			(pts
				(arc
					(start 158.06293 -279.121362)
					(mid 158.077809 -279.157283)
					(end 158.11373 -279.172162)
				)
				(arc
					(start 159.51327 -279.172162)
					(mid 159.549191 -279.157283)
					(end 159.56407 -279.121362)
				)
				(arc
					(start 159.56407 -278.712422)
					(mid 159.549191 -278.676501)
					(end 159.51327 -278.661622)
				)
				(arc
					(start 158.11373 -278.661622)
					(mid 158.077809 -278.676501)
					(end 158.06293 -278.712422)
				)
			)
		)
	)
	(zone
		(layers "In1.Cu" "In2.Cu")
		(hatch none 0.5)
		(connect_pads
			(clearance 0)
		)
		(min_thickness 0.25)
		(keepout
			(tracks not_allowed)
			(vias allowed)
			(pads allowed)
			(copperpour not_allowed)
			(footprints allowed)
		)
		(placement
			(enabled no)
			(sheetname "")
		)
		(fill yes
			(thermal_gap 0.5)
			(thermal_bridge_width 0.5)
			(island_removal_mode 0)
		)
		(polygon
			(pts
				(arc
					(start 421.090598 -284.221428)
					(mid 421.105477 -284.257349)
					(end 421.141398 -284.272228)
				)
				(arc
					(start 422.540938 -284.272228)
					(mid 422.576859 -284.257349)
					(end 422.591738 -284.221428)
				)
				(arc
					(start 422.591738 -283.812488)
					(mid 422.576859 -283.776567)
					(end 422.540938 -283.761688)
				)
				(arc
					(start 421.141398 -283.761688)
					(mid 421.105477 -283.776567)
					(end 421.090598 -283.812488)
				)
			)
		)
	)
	(zone
		(layers "In1.Cu" "In2.Cu")
		(hatch none 0.5)
		(connect_pads
			(clearance 0)
		)
		(min_thickness 0.25)
		(keepout
			(tracks not_allowed)
			(vias allowed)
			(pads allowed)
			(copperpour not_allowed)
			(footprints allowed)
		)
		(placement
			(enabled no)
			(sheetname "")
		)
		(fill yes
			(thermal_gap 0.5)
			(thermal_bridge_width 0.5)
			(island_removal_mode 0)
		)
		(polygon
			(pts
				(arc
					(start 30.02153 -313.121294)
					(mid 30.036409 -313.157215)
					(end 30.07233 -313.172094)
				)
				(arc
					(start 31.47187 -313.172094)
					(mid 31.507791 -313.157215)
					(end 31.52267 -313.121294)
				)
				(arc
					(start 31.52267 -312.712354)
					(mid 31.507791 -312.676433)
					(end 31.47187 -312.661554)
				)
				(arc
					(start 30.07233 -312.661554)
					(mid 30.036409 -312.676433)
					(end 30.02153 -312.712354)
				)
			)
		)
	)
	(zone
		(layers "In1.Cu" "In2.Cu")
		(hatch none 0.5)
		(connect_pads
			(clearance 0)
		)
		(min_thickness 0.25)
		(keepout
			(tracks not_allowed)
			(vias allowed)
			(pads allowed)
			(copperpour not_allowed)
			(footprints allowed)
		)
		(placement
			(enabled no)
			(sheetname "")
		)
		(fill yes
			(thermal_gap 0.5)
			(thermal_bridge_width 0.5)
			(island_removal_mode 0)
		)
		(polygon
			(pts
				(arc
					(start 11.490198 -293.571422)
					(mid 11.505077 -293.607343)
					(end 11.540998 -293.622222)
				)
				(arc
					(start 12.940538 -293.622222)
					(mid 12.976459 -293.607343)
					(end 12.991338 -293.571422)
				)
				(arc
					(start 12.991338 -293.162482)
					(mid 12.976459 -293.126561)
					(end 12.940538 -293.111682)
				)
				(arc
					(start 11.540998 -293.111682)
					(mid 11.505077 -293.126561)
					(end 11.490198 -293.162482)
				)
			)
		)
	)
	(zone
		(layers "In1.Cu" "In2.Cu")
		(hatch none 0.5)
		(connect_pads
			(clearance 0)
		)
		(min_thickness 0.25)
		(keepout
			(tracks not_allowed)
			(vias allowed)
			(pads allowed)
			(copperpour not_allowed)
			(footprints allowed)
		)
		(placement
			(enabled no)
			(sheetname "")
		)
		(fill yes
			(thermal_gap 0.5)
			(thermal_bridge_width 0.5)
			(island_removal_mode 0)
		)
		(polygon
			(pts
				(arc
					(start 7.39013 -288.471356)
					(mid 7.405009 -288.507277)
					(end 7.44093 -288.522156)
				)
				(arc
					(start 8.84047 -288.522156)
					(mid 8.876391 -288.507277)
					(end 8.89127 -288.471356)
				)
				(arc
					(start 8.89127 -288.062416)
					(mid 8.876391 -288.026495)
					(end 8.84047 -288.011616)
				)
				(arc
					(start 7.44093 -288.011616)
					(mid 7.405009 -288.026495)
					(end 7.39013 -288.062416)
				)
			)
		)
	)
	(zone
		(layers "In1.Cu" "In2.Cu")
		(hatch none 0.5)
		(connect_pads
			(clearance 0)
		)
		(min_thickness 0.25)
		(keepout
			(tracks not_allowed)
			(vias allowed)
			(pads allowed)
			(copperpour not_allowed)
			(footprints allowed)
		)
		(placement
			(enabled no)
			(sheetname "")
		)
		(fill yes
			(thermal_gap 0.5)
			(thermal_bridge_width 0.5)
			(island_removal_mode 0)
		)
		(polygon
			(pts
				(arc
					(start 285.505398 -288.471356)
					(mid 285.520277 -288.507277)
					(end 285.556198 -288.522156)
				)
				(arc
					(start 286.955738 -288.522156)
					(mid 286.991659 -288.507277)
					(end 287.006538 -288.471356)
				)
				(arc
					(start 287.006538 -288.062416)
					(mid 286.991659 -288.026495)
					(end 286.955738 -288.011616)
				)
				(arc
					(start 285.556198 -288.011616)
					(mid 285.520277 -288.026495)
					(end 285.505398 -288.062416)
				)
			)
		)
	)
	(zone
		(layers "In1.Cu" "In2.Cu")
		(hatch none 0.5)
		(connect_pads
			(clearance 0)
		)
		(min_thickness 0.25)
		(keepout
			(tracks not_allowed)
			(vias allowed)
			(pads allowed)
			(copperpour not_allowed)
			(footprints allowed)
		)
		(placement
			(enabled no)
			(sheetname "")
		)
		(fill yes
			(thermal_gap 0.5)
			(thermal_bridge_width 0.5)
			(island_removal_mode 0)
		)
		(polygon
			(pts
				(arc
					(start 199.881998 -295.271444)
					(mid 199.896877 -295.307365)
					(end 199.932798 -295.322244)
				)
				(arc
					(start 201.332338 -295.322244)
					(mid 201.368259 -295.307365)
					(end 201.383138 -295.271444)
				)
				(arc
					(start 201.383138 -294.862504)
					(mid 201.368259 -294.826583)
					(end 201.332338 -294.811704)
				)
				(arc
					(start 199.932798 -294.811704)
					(mid 199.896877 -294.826583)
					(end 199.881998 -294.862504)
				)
			)
		)
	)
	(zone
		(layers "In1.Cu" "In2.Cu")
		(hatch none 0.5)
		(connect_pads
			(clearance 0)
		)
		(min_thickness 0.25)
		(keepout
			(tracks not_allowed)
			(vias allowed)
			(pads allowed)
			(copperpour not_allowed)
			(footprints allowed)
		)
		(placement
			(enabled no)
			(sheetname "")
		)
		(fill yes
			(thermal_gap 0.5)
			(thermal_bridge_width 0.5)
			(island_removal_mode 0)
		)
		(polygon
			(pts
				(arc
					(start 203.32573 -290.171378)
					(mid 203.340609 -290.207299)
					(end 203.37653 -290.222178)
				)
				(arc
					(start 204.77607 -290.222178)
					(mid 204.811991 -290.207299)
					(end 204.82687 -290.171378)
				)
				(arc
					(start 204.82687 -289.762438)
					(mid 204.811991 -289.726517)
					(end 204.77607 -289.711638)
				)
				(arc
					(start 203.37653 -289.711638)
					(mid 203.340609 -289.726517)
					(end 203.32573 -289.762438)
				)
			)
		)
	)
	(zone
		(layers "In1.Cu" "In2.Cu")
		(hatch none 0.5)
		(connect_pads
			(clearance 0)
		)
		(min_thickness 0.25)
		(keepout
			(tracks not_allowed)
			(vias allowed)
			(pads allowed)
			(copperpour not_allowed)
			(footprints allowed)
		)
		(placement
			(enabled no)
			(sheetname "")
		)
		(fill yes
			(thermal_gap 0.5)
			(thermal_bridge_width 0.5)
			(island_removal_mode 0)
		)
		(polygon
			(pts
				(arc
					(start 195.78193 -273.171412)
					(mid 195.796809 -273.207333)
					(end 195.83273 -273.222212)
				)
				(arc
					(start 197.23227 -273.222212)
					(mid 197.268191 -273.207333)
					(end 197.28307 -273.171412)
				)
				(arc
					(start 197.28307 -272.762472)
					(mid 197.268191 -272.726551)
					(end 197.23227 -272.711672)
				)
				(arc
					(start 195.83273 -272.711672)
					(mid 195.796809 -272.726551)
					(end 195.78193 -272.762472)
				)
			)
		)
	)
	(zone
		(layers "In1.Cu" "In2.Cu")
		(hatch none 0.5)
		(connect_pads
			(clearance 0)
		)
		(min_thickness 0.25)
		(keepout
			(tracks not_allowed)
			(vias allowed)
			(pads allowed)
			(copperpour not_allowed)
			(footprints allowed)
		)
		(placement
			(enabled no)
			(sheetname "")
		)
		(fill yes
			(thermal_gap 0.5)
			(thermal_bridge_width 0.5)
			(island_removal_mode 0)
		)
		(polygon
			(pts
				(arc
					(start 432.734466 -228.121464)
					(mid 432.749345 -228.157385)
					(end 432.785266 -228.172264)
				)
				(arc
					(start 434.184806 -228.172264)
					(mid 434.220727 -228.157385)
					(end 434.235606 -228.121464)
				)
				(arc
					(start 434.235606 -227.712524)
					(mid 434.220727 -227.676603)
					(end 434.184806 -227.661724)
				)
				(arc
					(start 432.785266 -227.661724)
					(mid 432.749345 -227.676603)
					(end 432.734466 -227.712524)
				)
			)
		)
	)
	(zone
		(layers "In1.Cu" "In2.Cu")
		(hatch none 0.5)
		(connect_pads
			(clearance 0)
		)
		(min_thickness 0.25)
		(keepout
			(tracks not_allowed)
			(vias allowed)
			(pads allowed)
			(copperpour not_allowed)
			(footprints allowed)
		)
		(placement
			(enabled no)
			(sheetname "")
		)
		(fill yes
			(thermal_gap 0.5)
			(thermal_bridge_width 0.5)
			(island_removal_mode 0)
		)
		(polygon
			(pts
				(arc
					(start 432.734466 -206.871316)
					(mid 432.749345 -206.907237)
					(end 432.785266 -206.922116)
				)
				(arc
					(start 434.184806 -206.922116)
					(mid 434.220727 -206.907237)
					(end 434.235606 -206.871316)
				)
				(arc
					(start 434.235606 -206.462376)
					(mid 434.220727 -206.426455)
					(end 434.184806 -206.411576)
				)
				(arc
					(start 432.785266 -206.411576)
					(mid 432.749345 -206.426455)
					(end 432.734466 -206.462376)
				)
			)
		)
	)
	(zone
		(layers "In1.Cu" "In2.Cu")
		(hatch none 0.5)
		(connect_pads
			(clearance 0)
		)
		(min_thickness 0.25)
		(keepout
			(tracks not_allowed)
			(vias allowed)
			(pads allowed)
			(copperpour not_allowed)
			(footprints allowed)
		)
		(placement
			(enabled no)
			(sheetname "")
		)
		(fill yes
			(thermal_gap 0.5)
			(thermal_bridge_width 0.5)
			(island_removal_mode 0)
		)
		(polygon
			(pts
				(arc
					(start 266.974066 -265.52144)
					(mid 266.988945 -265.557361)
					(end 267.024866 -265.57224)
				)
				(arc
					(start 268.424406 -265.57224)
					(mid 268.460327 -265.557361)
					(end 268.475206 -265.52144)
				)
				(arc
					(start 268.475206 -265.1125)
					(mid 268.460327 -265.076579)
					(end 268.424406 -265.0617)
				)
				(arc
					(start 267.024866 -265.0617)
					(mid 266.988945 -265.076579)
					(end 266.974066 -265.1125)
				)
			)
		)
	)
	(zone
		(layers "In1.Cu" "In2.Cu")
		(hatch none 0.5)
		(connect_pads
			(clearance 0)
		)
		(min_thickness 0.25)
		(keepout
			(tracks not_allowed)
			(vias allowed)
			(pads allowed)
			(copperpour not_allowed)
			(footprints allowed)
		)
		(placement
			(enabled no)
			(sheetname "")
		)
		(fill yes
			(thermal_gap 0.5)
			(thermal_bridge_width 0.5)
			(island_removal_mode 0)
		)
		(polygon
			(pts
				(arc
					(start 421.090598 -228.971348)
					(mid 421.105477 -229.007269)
					(end 421.141398 -229.022148)
				)
				(arc
					(start 422.540938 -229.022148)
					(mid 422.576859 -229.007269)
					(end 422.591738 -228.971348)
				)
				(arc
					(start 422.591738 -228.562408)
					(mid 422.576859 -228.526487)
					(end 422.540938 -228.511608)
				)
				(arc
					(start 421.141398 -228.511608)
					(mid 421.105477 -228.526487)
					(end 421.090598 -228.562408)
				)
			)
		)
	)
	(zone
		(layers "In1.Cu" "In2.Cu")
		(hatch none 0.5)
		(connect_pads
			(clearance 0)
		)
		(min_thickness 0.25)
		(keepout
			(tracks not_allowed)
			(vias allowed)
			(pads allowed)
			(copperpour not_allowed)
			(footprints allowed)
		)
		(placement
			(enabled no)
			(sheetname "")
		)
		(fill yes
			(thermal_gap 0.5)
			(thermal_bridge_width 0.5)
			(island_removal_mode 0)
		)
		(polygon
			(pts
				(arc
					(start 210.86953 -275.721318)
					(mid 210.884409 -275.757239)
					(end 210.92033 -275.772118)
				)
				(arc
					(start 212.31987 -275.772118)
					(mid 212.355791 -275.757239)
					(end 212.37067 -275.721318)
				)
				(arc
					(start 212.37067 -275.312378)
					(mid 212.355791 -275.276457)
					(end 212.31987 -275.261578)
				)
				(arc
					(start 210.92033 -275.261578)
					(mid 210.884409 -275.276457)
					(end 210.86953 -275.312378)
				)
			)
		)
	)
	(zone
		(layers "In1.Cu" "In2.Cu")
		(hatch none 0.5)
		(connect_pads
			(clearance 0)
		)
		(min_thickness 0.25)
		(keepout
			(tracks not_allowed)
			(vias allowed)
			(pads allowed)
			(copperpour not_allowed)
			(footprints allowed)
		)
		(placement
			(enabled no)
			(sheetname "")
		)
		(fill yes
			(thermal_gap 0.5)
			(thermal_bridge_width 0.5)
			(island_removal_mode 0)
		)
		(polygon
			(pts
				(arc
					(start 447.822066 -206.871316)
					(mid 447.836945 -206.907237)
					(end 447.872866 -206.922116)
				)
				(arc
					(start 449.272406 -206.922116)
					(mid 449.308327 -206.907237)
					(end 449.323206 -206.871316)
				)
				(arc
					(start 449.323206 -206.462376)
					(mid 449.308327 -206.426455)
					(end 449.272406 -206.411576)
				)
				(arc
					(start 447.872866 -206.411576)
					(mid 447.836945 -206.426455)
					(end 447.822066 -206.462376)
				)
			)
		)
	)
	(zone
		(layers "In1.Cu" "In2.Cu")
		(hatch none 0.5)
		(connect_pads
			(clearance 0)
		)
		(min_thickness 0.25)
		(keepout
			(tracks not_allowed)
			(vias allowed)
			(pads allowed)
			(copperpour not_allowed)
			(footprints allowed)
		)
		(placement
			(enabled no)
			(sheetname "")
		)
		(fill yes
			(thermal_gap 0.5)
			(thermal_bridge_width 0.5)
			(island_removal_mode 0)
		)
		(polygon
			(pts
				(arc
					(start 282.061666 -222.171514)
					(mid 282.076545 -222.207435)
					(end 282.112466 -222.222314)
				)
				(arc
					(start 283.512006 -222.222314)
					(mid 283.547927 -222.207435)
					(end 283.562806 -222.171514)
				)
				(arc
					(start 283.562806 -221.762574)
					(mid 283.547927 -221.726653)
					(end 283.512006 -221.711774)
				)
				(arc
					(start 282.112466 -221.711774)
					(mid 282.076545 -221.726653)
					(end 282.061666 -221.762574)
				)
			)
		)
	)
	(zone
		(layers "In1.Cu" "In2.Cu")
		(hatch none 0.5)
		(connect_pads
			(clearance 0)
		)
		(min_thickness 0.25)
		(keepout
			(tracks not_allowed)
			(vias allowed)
			(pads allowed)
			(copperpour not_allowed)
			(footprints allowed)
		)
		(placement
			(enabled no)
			(sheetname "")
		)
		(fill yes
			(thermal_gap 0.5)
			(thermal_bridge_width 0.5)
			(island_removal_mode 0)
		)
		(polygon
			(pts
				(arc
					(start 199.881998 -225.571304)
					(mid 199.896877 -225.607225)
					(end 199.932798 -225.622104)
				)
				(arc
					(start 201.332338 -225.622104)
					(mid 201.368259 -225.607225)
					(end 201.383138 -225.571304)
				)
				(arc
					(start 201.383138 -225.162364)
					(mid 201.368259 -225.126443)
					(end 201.332338 -225.111564)
				)
				(arc
					(start 199.932798 -225.111564)
					(mid 199.896877 -225.126443)
					(end 199.881998 -225.162364)
				)
			)
		)
	)
	(zone
		(layers "In1.Cu" "In2.Cu")
		(hatch none 0.5)
		(connect_pads
			(clearance 0)
		)
		(min_thickness 0.25)
		(keepout
			(tracks not_allowed)
			(vias allowed)
			(pads allowed)
			(copperpour not_allowed)
			(footprints allowed)
		)
		(placement
			(enabled no)
			(sheetname "")
		)
		(fill yes
			(thermal_gap 0.5)
			(thermal_bridge_width 0.5)
			(island_removal_mode 0)
		)
		(polygon
			(pts
				(arc
					(start 11.490198 -199.221344)
					(mid 11.505077 -199.257265)
					(end 11.540998 -199.272144)
				)
				(arc
					(start 12.940538 -199.272144)
					(mid 12.976459 -199.257265)
					(end 12.991338 -199.221344)
				)
				(arc
					(start 12.991338 -198.812404)
					(mid 12.976459 -198.776483)
					(end 12.940538 -198.761604)
				)
				(arc
					(start 11.540998 -198.761604)
					(mid 11.505077 -198.776483)
					(end 11.490198 -198.812404)
				)
			)
		)
	)
	(zone
		(layers "In1.Cu" "In2.Cu")
		(hatch none 0.5)
		(connect_pads
			(clearance 0)
		)
		(min_thickness 0.25)
		(keepout
			(tracks not_allowed)
			(vias allowed)
			(pads allowed)
			(copperpour not_allowed)
			(footprints allowed)
		)
		(placement
			(enabled no)
			(sheetname "")
		)
		(fill yes
			(thermal_gap 0.5)
			(thermal_bridge_width 0.5)
			(island_removal_mode 0)
		)
		(polygon
			(pts
				(arc
					(start 293.049198 -226.421442)
					(mid 293.064077 -226.457363)
					(end 293.099998 -226.472242)
				)
				(arc
					(start 294.499538 -226.472242)
					(mid 294.535459 -226.457363)
					(end 294.550338 -226.421442)
				)
				(arc
					(start 294.550338 -226.012502)
					(mid 294.535459 -225.976581)
					(end 294.499538 -225.961702)
				)
				(arc
					(start 293.099998 -225.961702)
					(mid 293.064077 -225.976581)
					(end 293.049198 -226.012502)
				)
			)
		)
	)
	(zone
		(layers "In1.Cu" "In2.Cu")
		(hatch none 0.5)
		(connect_pads
			(clearance 0)
		)
		(min_thickness 0.25)
		(keepout
			(tracks not_allowed)
			(vias allowed)
			(pads allowed)
			(copperpour not_allowed)
			(footprints allowed)
		)
		(placement
			(enabled no)
			(sheetname "")
		)
		(fill yes
			(thermal_gap 0.5)
			(thermal_bridge_width 0.5)
			(island_removal_mode 0)
		)
		(polygon
			(pts
				(arc
					(start 192.338198 -276.571456)
					(mid 192.353077 -276.607377)
					(end 192.388998 -276.622256)
				)
				(arc
					(start 193.788538 -276.622256)
					(mid 193.824459 -276.607377)
					(end 193.839338 -276.571456)
				)
				(arc
					(start 193.839338 -276.162516)
					(mid 193.824459 -276.126595)
					(end 193.788538 -276.111716)
				)
				(arc
					(start 192.388998 -276.111716)
					(mid 192.353077 -276.126595)
					(end 192.338198 -276.162516)
				)
			)
		)
	)
	(zone
		(layers "In1.Cu" "In2.Cu")
		(hatch none 0.5)
		(connect_pads
			(clearance 0)
		)
		(min_thickness 0.25)
		(keepout
			(tracks not_allowed)
			(vias allowed)
			(pads allowed)
			(copperpour not_allowed)
			(footprints allowed)
		)
		(placement
			(enabled no)
			(sheetname "")
		)
		(fill yes
			(thermal_gap 0.5)
			(thermal_bridge_width 0.5)
			(island_removal_mode 0)
		)
		(polygon
			(pts
				(arc
					(start 462.909666 -268.921484)
					(mid 462.924545 -268.957405)
					(end 462.960466 -268.972284)
				)
				(arc
					(start 464.360006 -268.972284)
					(mid 464.395927 -268.957405)
					(end 464.410806 -268.921484)
				)
				(arc
					(start 464.410806 -268.512544)
					(mid 464.395927 -268.476623)
					(end 464.360006 -268.461744)
				)
				(arc
					(start 462.960466 -268.461744)
					(mid 462.924545 -268.476623)
					(end 462.909666 -268.512544)
				)
			)
		)
	)
	(zone
		(layers "In1.Cu" "In2.Cu")
		(hatch none 0.5)
		(connect_pads
			(clearance 0)
		)
		(min_thickness 0.25)
		(keepout
			(tracks not_allowed)
			(vias allowed)
			(pads allowed)
			(copperpour not_allowed)
			(footprints allowed)
		)
		(placement
			(enabled no)
			(sheetname "")
		)
		(fill yes
			(thermal_gap 0.5)
			(thermal_bridge_width 0.5)
			(island_removal_mode 0)
		)
		(polygon
			(pts
				(arc
					(start 443.721998 -308.871366)
					(mid 443.736877 -308.907287)
					(end 443.772798 -308.922166)
				)
				(arc
					(start 445.172338 -308.922166)
					(mid 445.208259 -308.907287)
					(end 445.223138 -308.871366)
				)
				(arc
					(start 445.223138 -308.462426)
					(mid 445.208259 -308.426505)
					(end 445.172338 -308.411626)
				)
				(arc
					(start 443.772798 -308.411626)
					(mid 443.736877 -308.426505)
					(end 443.721998 -308.462426)
				)
			)
		)
	)
	(zone
		(layers "In1.Cu" "In2.Cu")
		(hatch none 0.5)
		(connect_pads
			(clearance 0)
		)
		(min_thickness 0.25)
		(keepout
			(tracks not_allowed)
			(vias allowed)
			(pads allowed)
			(copperpour not_allowed)
			(footprints allowed)
		)
		(placement
			(enabled no)
			(sheetname "")
		)
		(fill yes
			(thermal_gap 0.5)
			(thermal_bridge_width 0.5)
			(island_removal_mode 0)
		)
		(polygon
			(pts
				(arc
					(start 26.577798 -267.221462)
					(mid 26.592677 -267.257383)
					(end 26.628598 -267.272262)
				)
				(arc
					(start 28.028138 -267.272262)
					(mid 28.064059 -267.257383)
					(end 28.078938 -267.221462)
				)
				(arc
					(start 28.078938 -266.812522)
					(mid 28.064059 -266.776601)
					(end 28.028138 -266.761722)
				)
				(arc
					(start 26.628598 -266.761722)
					(mid 26.592677 -266.776601)
					(end 26.577798 -266.812522)
				)
			)
		)
	)
	(zone
		(layers "In1.Cu" "In2.Cu")
		(hatch none 0.5)
		(connect_pads
			(clearance 0)
		)
		(min_thickness 0.25)
		(keepout
			(tracks not_allowed)
			(vias allowed)
			(pads allowed)
			(copperpour not_allowed)
			(footprints allowed)
		)
		(placement
			(enabled no)
			(sheetname "")
		)
		(fill yes
			(thermal_gap 0.5)
			(thermal_bridge_width 0.5)
			(island_removal_mode 0)
		)
		(polygon
			(pts
				(arc
					(start 289.605466 -312.27141)
					(mid 289.620345 -312.307331)
					(end 289.656266 -312.32221)
				)
				(arc
					(start 291.055806 -312.32221)
					(mid 291.091727 -312.307331)
					(end 291.106606 -312.27141)
				)
				(arc
					(start 291.106606 -311.86247)
					(mid 291.091727 -311.826549)
					(end 291.055806 -311.81167)
				)
				(arc
					(start 289.656266 -311.81167)
					(mid 289.620345 -311.826549)
					(end 289.605466 -311.86247)
				)
			)
		)
	)
	(zone
		(layers "In1.Cu" "In2.Cu")
		(hatch none 0.5)
		(connect_pads
			(clearance 0)
		)
		(min_thickness 0.25)
		(keepout
			(tracks not_allowed)
			(vias allowed)
			(pads allowed)
			(copperpour not_allowed)
			(footprints allowed)
		)
		(placement
			(enabled no)
			(sheetname "")
		)
		(fill yes
			(thermal_gap 0.5)
			(thermal_bridge_width 0.5)
			(island_removal_mode 0)
		)
		(polygon
			(pts
				(arc
					(start 432.734466 -311.421526)
					(mid 432.749345 -311.457447)
					(end 432.785266 -311.472326)
				)
				(arc
					(start 434.184806 -311.472326)
					(mid 434.220727 -311.457447)
					(end 434.235606 -311.421526)
				)
				(arc
					(start 434.235606 -311.012586)
					(mid 434.220727 -310.976665)
					(end 434.184806 -310.961786)
				)
				(arc
					(start 432.785266 -310.961786)
					(mid 432.749345 -310.976665)
					(end 432.734466 -311.012586)
				)
			)
		)
	)
	(zone
		(layers "In1.Cu" "In2.Cu")
		(hatch none 0.5)
		(connect_pads
			(clearance 0)
		)
		(min_thickness 0.25)
		(keepout
			(tracks not_allowed)
			(vias allowed)
			(pads allowed)
			(copperpour not_allowed)
			(footprints allowed)
		)
		(placement
			(enabled no)
			(sheetname "")
		)
		(fill yes
			(thermal_gap 0.5)
			(thermal_bridge_width 0.5)
			(island_removal_mode 0)
		)
		(polygon
			(pts
				(arc
					(start 425.190666 -260.421374)
					(mid 425.205545 -260.457295)
					(end 425.241466 -260.472174)
				)
				(arc
					(start 426.641006 -260.472174)
					(mid 426.676927 -260.457295)
					(end 426.691806 -260.421374)
				)
				(arc
					(start 426.691806 -260.012434)
					(mid 426.676927 -259.976513)
					(end 426.641006 -259.961634)
				)
				(arc
					(start 425.241466 -259.961634)
					(mid 425.205545 -259.976513)
					(end 425.190666 -260.012434)
				)
			)
		)
	)
	(zone
		(layers "In1.Cu" "In2.Cu")
		(hatch none 0.5)
		(connect_pads
			(clearance 0)
		)
		(min_thickness 0.25)
		(keepout
			(tracks not_allowed)
			(vias allowed)
			(pads allowed)
			(copperpour not_allowed)
			(footprints allowed)
		)
		(placement
			(enabled no)
			(sheetname "")
		)
		(fill yes
			(thermal_gap 0.5)
			(thermal_bridge_width 0.5)
			(island_removal_mode 0)
		)
		(polygon
			(pts
				(arc
					(start 428.634398 -251.07138)
					(mid 428.649277 -251.107301)
					(end 428.685198 -251.12218)
				)
				(arc
					(start 430.084738 -251.12218)
					(mid 430.120659 -251.107301)
					(end 430.135538 -251.07138)
				)
				(arc
					(start 430.135538 -250.66244)
					(mid 430.120659 -250.626519)
					(end 430.084738 -250.61164)
				)
				(arc
					(start 428.685198 -250.61164)
					(mid 428.649277 -250.626519)
					(end 428.634398 -250.66244)
				)
			)
		)
	)
	(zone
		(layers "In1.Cu" "In2.Cu")
		(hatch none 0.5)
		(connect_pads
			(clearance 0)
		)
		(min_thickness 0.25)
		(keepout
			(tracks not_allowed)
			(vias allowed)
			(pads allowed)
			(copperpour not_allowed)
			(footprints allowed)
		)
		(placement
			(enabled no)
			(sheetname "")
		)
		(fill yes
			(thermal_gap 0.5)
			(thermal_bridge_width 0.5)
			(island_removal_mode 0)
		)
		(polygon
			(pts
				(arc
					(start 192.338198 -245.12143)
					(mid 192.353077 -245.157351)
					(end 192.388998 -245.17223)
				)
				(arc
					(start 193.788538 -245.17223)
					(mid 193.824459 -245.157351)
					(end 193.839338 -245.12143)
				)
				(arc
					(start 193.839338 -244.71249)
					(mid 193.824459 -244.676569)
					(end 193.788538 -244.66169)
				)
				(arc
					(start 192.388998 -244.66169)
					(mid 192.353077 -244.676569)
					(end 192.338198 -244.71249)
				)
			)
		)
	)
	(zone
		(layers "In1.Cu" "In2.Cu")
		(hatch none 0.5)
		(connect_pads
			(clearance 0)
		)
		(min_thickness 0.25)
		(keepout
			(tracks not_allowed)
			(vias allowed)
			(pads allowed)
			(copperpour not_allowed)
			(footprints allowed)
		)
		(placement
			(enabled no)
			(sheetname "")
		)
		(fill yes
			(thermal_gap 0.5)
			(thermal_bridge_width 0.5)
			(island_removal_mode 0)
		)
		(polygon
			(pts
				(arc
					(start 300.592998 -293.571422)
					(mid 300.607877 -293.607343)
					(end 300.643798 -293.622222)
				)
				(arc
					(start 302.043338 -293.622222)
					(mid 302.079259 -293.607343)
					(end 302.094138 -293.571422)
				)
				(arc
					(start 302.094138 -293.162482)
					(mid 302.079259 -293.126561)
					(end 302.043338 -293.111682)
				)
				(arc
					(start 300.643798 -293.111682)
					(mid 300.607877 -293.126561)
					(end 300.592998 -293.162482)
				)
			)
		)
	)
	(zone
		(layers "In1.Cu" "In2.Cu")
		(hatch none 0.5)
		(connect_pads
			(clearance 0)
		)
		(min_thickness 0.25)
		(keepout
			(tracks not_allowed)
			(vias allowed)
			(pads allowed)
			(copperpour not_allowed)
			(footprints allowed)
		)
		(placement
			(enabled no)
			(sheetname "")
		)
		(fill yes
			(thermal_gap 0.5)
			(thermal_bridge_width 0.5)
			(island_removal_mode 0)
		)
		(polygon
			(pts
				(arc
					(start 210.86953 -313.121294)
					(mid 210.884409 -313.157215)
					(end 210.92033 -313.172094)
				)
				(arc
					(start 212.31987 -313.172094)
					(mid 212.355791 -313.157215)
					(end 212.37067 -313.121294)
				)
				(arc
					(start 212.37067 -312.712354)
					(mid 212.355791 -312.676433)
					(end 212.31987 -312.661554)
				)
				(arc
					(start 210.92033 -312.661554)
					(mid 210.884409 -312.676433)
					(end 210.86953 -312.712354)
				)
			)
		)
	)
	(zone
		(layers "In1.Cu" "In2.Cu")
		(hatch none 0.5)
		(connect_pads
			(clearance 0)
		)
		(min_thickness 0.25)
		(keepout
			(tracks not_allowed)
			(vias allowed)
			(pads allowed)
			(copperpour not_allowed)
			(footprints allowed)
		)
		(placement
			(enabled no)
			(sheetname "")
		)
		(fill yes
			(thermal_gap 0.5)
			(thermal_bridge_width 0.5)
			(island_removal_mode 0)
		)
		(polygon
			(pts
				(arc
					(start 64.296798 -287.621472)
					(mid 64.311677 -287.657393)
					(end 64.347598 -287.672272)
				)
				(arc
					(start 65.747138 -287.672272)
					(mid 65.783059 -287.657393)
					(end 65.797938 -287.621472)
				)
				(arc
					(start 65.797938 -287.212532)
					(mid 65.783059 -287.176611)
					(end 65.747138 -287.161732)
				)
				(arc
					(start 64.347598 -287.161732)
					(mid 64.311677 -287.176611)
					(end 64.296798 -287.212532)
				)
			)
		)
	)
	(zone
		(layers "In1.Cu" "In2.Cu")
		(hatch none 0.5)
		(connect_pads
			(clearance 0)
		)
		(min_thickness 0.25)
		(keepout
			(tracks not_allowed)
			(vias allowed)
			(pads allowed)
			(copperpour not_allowed)
			(footprints allowed)
		)
		(placement
			(enabled no)
			(sheetname "")
		)
		(fill yes
			(thermal_gap 0.5)
			(thermal_bridge_width 0.5)
			(island_removal_mode 0)
		)
		(polygon
			(pts
				(arc
					(start 52.65293 -312.27141)
					(mid 52.667809 -312.307331)
					(end 52.70373 -312.32221)
				)
				(arc
					(start 54.10327 -312.32221)
					(mid 54.139191 -312.307331)
					(end 54.15407 -312.27141)
				)
				(arc
					(start 54.15407 -311.86247)
					(mid 54.139191 -311.826549)
					(end 54.10327 -311.81167)
				)
				(arc
					(start 52.70373 -311.81167)
					(mid 52.667809 -311.826549)
					(end 52.65293 -311.86247)
				)
			)
		)
	)
	(zone
		(layers "In1.Cu" "In2.Cu")
		(hatch none 0.5)
		(connect_pads
			(clearance 0)
		)
		(min_thickness 0.25)
		(keepout
			(tracks not_allowed)
			(vias allowed)
			(pads allowed)
			(copperpour not_allowed)
			(footprints allowed)
		)
		(placement
			(enabled no)
			(sheetname "")
		)
		(fill yes
			(thermal_gap 0.5)
			(thermal_bridge_width 0.5)
			(island_removal_mode 0)
		)
		(polygon
			(pts
				(arc
					(start 406.002998 -235.771436)
					(mid 406.017877 -235.807357)
					(end 406.053798 -235.822236)
				)
				(arc
					(start 407.453338 -235.822236)
					(mid 407.489259 -235.807357)
					(end 407.504138 -235.771436)
				)
				(arc
					(start 407.504138 -235.362496)
					(mid 407.489259 -235.326575)
					(end 407.453338 -235.311696)
				)
				(arc
					(start 406.053798 -235.311696)
					(mid 406.017877 -235.326575)
					(end 406.002998 -235.362496)
				)
			)
		)
	)
	(zone
		(layers "In1.Cu" "In2.Cu")
		(hatch none 0.5)
		(connect_pads
			(clearance 0)
		)
		(min_thickness 0.25)
		(keepout
			(tracks not_allowed)
			(vias allowed)
			(pads allowed)
			(copperpour not_allowed)
			(footprints allowed)
		)
		(placement
			(enabled no)
			(sheetname "")
		)
		(fill yes
			(thermal_gap 0.5)
			(thermal_bridge_width 0.5)
			(island_removal_mode 0)
		)
		(polygon
			(pts
				(arc
					(start 56.752998 -287.621472)
					(mid 56.767877 -287.657393)
					(end 56.803798 -287.672272)
				)
				(arc
					(start 58.203338 -287.672272)
					(mid 58.239259 -287.657393)
					(end 58.254138 -287.621472)
				)
				(arc
					(start 58.254138 -287.212532)
					(mid 58.239259 -287.176611)
					(end 58.203338 -287.161732)
				)
				(arc
					(start 56.803798 -287.161732)
					(mid 56.767877 -287.176611)
					(end 56.752998 -287.212532)
				)
			)
		)
	)
	(zone
		(layers "In1.Cu" "In2.Cu")
		(hatch none 0.5)
		(connect_pads
			(clearance 0)
		)
		(min_thickness 0.25)
		(keepout
			(tracks not_allowed)
			(vias allowed)
			(pads allowed)
			(copperpour not_allowed)
			(footprints allowed)
		)
		(placement
			(enabled no)
			(sheetname "")
		)
		(fill yes
			(thermal_gap 0.5)
			(thermal_bridge_width 0.5)
			(island_removal_mode 0)
		)
		(polygon
			(pts
				(arc
					(start 462.909666 -265.52144)
					(mid 462.924545 -265.557361)
					(end 462.960466 -265.57224)
				)
				(arc
					(start 464.360006 -265.57224)
					(mid 464.395927 -265.557361)
					(end 464.410806 -265.52144)
				)
				(arc
					(start 464.410806 -265.1125)
					(mid 464.395927 -265.076579)
					(end 464.360006 -265.0617)
				)
				(arc
					(start 462.960466 -265.0617)
					(mid 462.924545 -265.076579)
					(end 462.909666 -265.1125)
				)
			)
		)
	)
	(zone
		(layers "In1.Cu" "In2.Cu")
		(hatch none 0.5)
		(connect_pads
			(clearance 0)
		)
		(min_thickness 0.25)
		(keepout
			(tracks not_allowed)
			(vias allowed)
			(pads allowed)
			(copperpour not_allowed)
			(footprints allowed)
		)
		(placement
			(enabled no)
			(sheetname "")
		)
		(fill yes
			(thermal_gap 0.5)
			(thermal_bridge_width 0.5)
			(island_removal_mode 0)
		)
		(polygon
			(pts
				(arc
					(start 188.23813 -213.671404)
					(mid 188.253009 -213.707325)
					(end 188.28893 -213.722204)
				)
				(arc
					(start 189.68847 -213.722204)
					(mid 189.724391 -213.707325)
					(end 189.73927 -213.671404)
				)
				(arc
					(start 189.73927 -213.262464)
					(mid 189.724391 -213.226543)
					(end 189.68847 -213.211664)
				)
				(arc
					(start 188.28893 -213.211664)
					(mid 188.253009 -213.226543)
					(end 188.23813 -213.262464)
				)
			)
		)
	)
	(zone
		(layers "In1.Cu" "In2.Cu")
		(hatch none 0.5)
		(connect_pads
			(clearance 0)
		)
		(min_thickness 0.25)
		(keepout
			(tracks not_allowed)
			(vias allowed)
			(pads allowed)
			(copperpour not_allowed)
			(footprints allowed)
		)
		(placement
			(enabled no)
			(sheetname "")
		)
		(fill yes
			(thermal_gap 0.5)
			(thermal_bridge_width 0.5)
			(island_removal_mode 0)
		)
		(polygon
			(pts
				(arc
					(start 184.794398 -227.271326)
					(mid 184.809277 -227.307247)
					(end 184.845198 -227.322126)
				)
				(arc
					(start 186.244738 -227.322126)
					(mid 186.280659 -227.307247)
					(end 186.295538 -227.271326)
				)
				(arc
					(start 186.295538 -226.862386)
					(mid 186.280659 -226.826465)
					(end 186.244738 -226.811586)
				)
				(arc
					(start 184.845198 -226.811586)
					(mid 184.809277 -226.826465)
					(end 184.794398 -226.862386)
				)
			)
		)
	)
	(zone
		(layers "In1.Cu" "In2.Cu")
		(hatch none 0.5)
		(connect_pads
			(clearance 0)
		)
		(min_thickness 0.25)
		(keepout
			(tracks not_allowed)
			(vias allowed)
			(pads allowed)
			(copperpour not_allowed)
			(footprints allowed)
		)
		(placement
			(enabled no)
			(sheetname "")
		)
		(fill yes
			(thermal_gap 0.5)
			(thermal_bridge_width 0.5)
			(island_removal_mode 0)
		)
		(polygon
			(pts
				(arc
					(start 49.209198 -267.221462)
					(mid 49.224077 -267.257383)
					(end 49.259998 -267.272262)
				)
				(arc
					(start 50.659538 -267.272262)
					(mid 50.695459 -267.257383)
					(end 50.710338 -267.221462)
				)
				(arc
					(start 50.710338 -266.812522)
					(mid 50.695459 -266.776601)
					(end 50.659538 -266.761722)
				)
				(arc
					(start 49.259998 -266.761722)
					(mid 49.224077 -266.776601)
					(end 49.209198 -266.812522)
				)
			)
		)
	)
	(zone
		(layers "In1.Cu" "In2.Cu")
		(hatch none 0.5)
		(connect_pads
			(clearance 0)
		)
		(min_thickness 0.25)
		(keepout
			(tracks not_allowed)
			(vias allowed)
			(pads allowed)
			(copperpour not_allowed)
			(footprints allowed)
		)
		(placement
			(enabled no)
			(sheetname "")
		)
		(fill yes
			(thermal_gap 0.5)
			(thermal_bridge_width 0.5)
			(island_removal_mode 0)
		)
		(polygon
			(pts
				(arc
					(start 173.15053 -275.721318)
					(mid 173.165409 -275.757239)
					(end 173.20133 -275.772118)
				)
				(arc
					(start 174.60087 -275.772118)
					(mid 174.636791 -275.757239)
					(end 174.65167 -275.721318)
				)
				(arc
					(start 174.65167 -275.312378)
					(mid 174.636791 -275.276457)
					(end 174.60087 -275.261578)
				)
				(arc
					(start 173.20133 -275.261578)
					(mid 173.165409 -275.276457)
					(end 173.15053 -275.312378)
				)
			)
		)
	)
	(zone
		(layers "In1.Cu" "In2.Cu")
		(hatch none 0.5)
		(connect_pads
			(clearance 0)
		)
		(min_thickness 0.25)
		(keepout
			(tracks not_allowed)
			(vias allowed)
			(pads allowed)
			(copperpour not_allowed)
			(footprints allowed)
		)
		(placement
			(enabled no)
			(sheetname "")
		)
		(fill yes
			(thermal_gap 0.5)
			(thermal_bridge_width 0.5)
			(island_removal_mode 0)
		)
		(polygon
			(pts
				(arc
					(start 282.061666 -229.821486)
					(mid 282.076545 -229.857407)
					(end 282.112466 -229.872286)
				)
				(arc
					(start 283.512006 -229.872286)
					(mid 283.547927 -229.857407)
					(end 283.562806 -229.821486)
				)
				(arc
					(start 283.562806 -229.412546)
					(mid 283.547927 -229.376625)
					(end 283.512006 -229.361746)
				)
				(arc
					(start 282.112466 -229.361746)
					(mid 282.076545 -229.376625)
					(end 282.061666 -229.412546)
				)
			)
		)
	)
	(zone
		(layers "In1.Cu" "In2.Cu")
		(hatch none 0.5)
		(connect_pads
			(clearance 0)
		)
		(min_thickness 0.25)
		(keepout
			(tracks not_allowed)
			(vias allowed)
			(pads allowed)
			(copperpour not_allowed)
			(footprints allowed)
		)
		(placement
			(enabled no)
			(sheetname "")
		)
		(fill yes
			(thermal_gap 0.5)
			(thermal_bridge_width 0.5)
			(island_removal_mode 0)
		)
		(polygon
			(pts
				(arc
					(start 308.136798 -204.32141)
					(mid 308.151677 -204.357331)
					(end 308.187598 -204.37221)
				)
				(arc
					(start 309.587138 -204.37221)
					(mid 309.623059 -204.357331)
					(end 309.637938 -204.32141)
				)
				(arc
					(start 309.637938 -203.91247)
					(mid 309.623059 -203.876549)
					(end 309.587138 -203.86167)
				)
				(arc
					(start 308.187598 -203.86167)
					(mid 308.151677 -203.876549)
					(end 308.136798 -203.91247)
				)
			)
		)
	)
	(zone
		(layers "In1.Cu" "In2.Cu")
		(hatch none 0.5)
		(connect_pads
			(clearance 0)
		)
		(min_thickness 0.25)
		(keepout
			(tracks not_allowed)
			(vias allowed)
			(pads allowed)
			(copperpour not_allowed)
			(footprints allowed)
		)
		(placement
			(enabled no)
			(sheetname "")
		)
		(fill yes
			(thermal_gap 0.5)
			(thermal_bridge_width 0.5)
			(island_removal_mode 0)
		)
		(polygon
			(pts
				(arc
					(start 19.033998 -281.671522)
					(mid 19.048877 -281.707443)
					(end 19.084798 -281.722322)
				)
				(arc
					(start 20.484338 -281.722322)
					(mid 20.520259 -281.707443)
					(end 20.535138 -281.671522)
				)
				(arc
					(start 20.535138 -281.262582)
					(mid 20.520259 -281.226661)
					(end 20.484338 -281.211782)
				)
				(arc
					(start 19.084798 -281.211782)
					(mid 19.048877 -281.226661)
					(end 19.033998 -281.262582)
				)
			)
		)
	)
	(zone
		(layers "In1.Cu" "In2.Cu")
		(hatch none 0.5)
		(connect_pads
			(clearance 0)
		)
		(min_thickness 0.25)
		(keepout
			(tracks not_allowed)
			(vias allowed)
			(pads allowed)
			(copperpour not_allowed)
			(footprints allowed)
		)
		(placement
			(enabled no)
			(sheetname "")
		)
		(fill yes
			(thermal_gap 0.5)
			(thermal_bridge_width 0.5)
			(island_removal_mode 0)
		)
		(polygon
			(pts
				(arc
					(start 289.605466 -285.92145)
					(mid 289.620345 -285.957371)
					(end 289.656266 -285.97225)
				)
				(arc
					(start 291.055806 -285.97225)
					(mid 291.091727 -285.957371)
					(end 291.106606 -285.92145)
				)
				(arc
					(start 291.106606 -285.51251)
					(mid 291.091727 -285.476589)
					(end 291.055806 -285.46171)
				)
				(arc
					(start 289.656266 -285.46171)
					(mid 289.620345 -285.476589)
					(end 289.605466 -285.51251)
				)
			)
		)
	)
	(zone
		(layers "In1.Cu" "In2.Cu")
		(hatch none 0.5)
		(connect_pads
			(clearance 0)
		)
		(min_thickness 0.25)
		(keepout
			(tracks not_allowed)
			(vias allowed)
			(pads allowed)
			(copperpour not_allowed)
			(footprints allowed)
		)
		(placement
			(enabled no)
			(sheetname "")
		)
		(fill yes
			(thermal_gap 0.5)
			(thermal_bridge_width 0.5)
			(island_removal_mode 0)
		)
		(polygon
			(pts
				(arc
					(start 188.23813 -274.871434)
					(mid 188.253009 -274.907355)
					(end 188.28893 -274.922234)
				)
				(arc
					(start 189.68847 -274.922234)
					(mid 189.724391 -274.907355)
					(end 189.73927 -274.871434)
				)
				(arc
					(start 189.73927 -274.462494)
					(mid 189.724391 -274.426573)
					(end 189.68847 -274.411694)
				)
				(arc
					(start 188.28893 -274.411694)
					(mid 188.253009 -274.426573)
					(end 188.23813 -274.462494)
				)
			)
		)
	)
	(zone
		(layers "In1.Cu" "In2.Cu")
		(hatch none 0.5)
		(connect_pads
			(clearance 0)
		)
		(min_thickness 0.25)
		(keepout
			(tracks not_allowed)
			(vias allowed)
			(pads allowed)
			(copperpour not_allowed)
			(footprints allowed)
		)
		(placement
			(enabled no)
			(sheetname "")
		)
		(fill yes
			(thermal_gap 0.5)
			(thermal_bridge_width 0.5)
			(island_removal_mode 0)
		)
		(polygon
			(pts
				(arc
					(start 413.546798 -290.171378)
					(mid 413.561677 -290.207299)
					(end 413.597598 -290.222178)
				)
				(arc
					(start 414.997138 -290.222178)
					(mid 415.033059 -290.207299)
					(end 415.047938 -290.171378)
				)
				(arc
					(start 415.047938 -289.762438)
					(mid 415.033059 -289.726517)
					(end 414.997138 -289.711638)
				)
				(arc
					(start 413.597598 -289.711638)
					(mid 413.561677 -289.726517)
					(end 413.546798 -289.762438)
				)
			)
		)
	)
	(zone
		(layers "In1.Cu" "In2.Cu")
		(hatch none 0.5)
		(connect_pads
			(clearance 0)
		)
		(min_thickness 0.25)
		(keepout
			(tracks not_allowed)
			(vias allowed)
			(pads allowed)
			(copperpour not_allowed)
			(footprints allowed)
		)
		(placement
			(enabled no)
			(sheetname "")
		)
		(fill yes
			(thermal_gap 0.5)
			(thermal_bridge_width 0.5)
			(island_removal_mode 0)
		)
		(polygon
			(pts
				(arc
					(start 169.706798 -222.171514)
					(mid 169.721677 -222.207435)
					(end 169.757598 -222.222314)
				)
				(arc
					(start 171.157138 -222.222314)
					(mid 171.193059 -222.207435)
					(end 171.207938 -222.171514)
				)
				(arc
					(start 171.207938 -221.762574)
					(mid 171.193059 -221.726653)
					(end 171.157138 -221.711774)
				)
				(arc
					(start 169.757598 -221.711774)
					(mid 169.721677 -221.726653)
					(end 169.706798 -221.762574)
				)
			)
		)
	)
	(zone
		(layers "In1.Cu" "In2.Cu")
		(hatch none 0.5)
		(connect_pads
			(clearance 0)
		)
		(min_thickness 0.25)
		(keepout
			(tracks not_allowed)
			(vias allowed)
			(pads allowed)
			(copperpour not_allowed)
			(footprints allowed)
		)
		(placement
			(enabled no)
			(sheetname "")
		)
		(fill yes
			(thermal_gap 0.5)
			(thermal_bridge_width 0.5)
			(island_removal_mode 0)
		)
		(polygon
			(pts
				(arc
					(start 195.78193 -259.57149)
					(mid 195.796809 -259.607411)
					(end 195.83273 -259.62229)
				)
				(arc
					(start 197.23227 -259.62229)
					(mid 197.268191 -259.607411)
					(end 197.28307 -259.57149)
				)
				(arc
					(start 197.28307 -259.16255)
					(mid 197.268191 -259.126629)
					(end 197.23227 -259.11175)
				)
				(arc
					(start 195.83273 -259.11175)
					(mid 195.796809 -259.126629)
					(end 195.78193 -259.16255)
				)
			)
		)
	)
	(zone
		(layers "In1.Cu" "In2.Cu")
		(hatch none 0.5)
		(connect_pads
			(clearance 0)
		)
		(min_thickness 0.25)
		(keepout
			(tracks not_allowed)
			(vias allowed)
			(pads allowed)
			(copperpour not_allowed)
			(footprints allowed)
		)
		(placement
			(enabled no)
			(sheetname "")
		)
		(fill yes
			(thermal_gap 0.5)
			(thermal_bridge_width 0.5)
			(island_removal_mode 0)
		)
		(polygon
			(pts
				(arc
					(start 34.121598 -291.021516)
					(mid 34.136477 -291.057437)
					(end 34.172398 -291.072316)
				)
				(arc
					(start 35.571938 -291.072316)
					(mid 35.607859 -291.057437)
					(end 35.622738 -291.021516)
				)
				(arc
					(start 35.622738 -290.612576)
					(mid 35.607859 -290.576655)
					(end 35.571938 -290.561776)
				)
				(arc
					(start 34.172398 -290.561776)
					(mid 34.136477 -290.576655)
					(end 34.121598 -290.612576)
				)
			)
		)
	)
	(zone
		(layers "In1.Cu" "In2.Cu")
		(hatch none 0.5)
		(connect_pads
			(clearance 0)
		)
		(min_thickness 0.25)
		(keepout
			(tracks not_allowed)
			(vias allowed)
			(pads allowed)
			(copperpour not_allowed)
			(footprints allowed)
		)
		(placement
			(enabled no)
			(sheetname "")
		)
		(fill yes
			(thermal_gap 0.5)
			(thermal_bridge_width 0.5)
			(island_removal_mode 0)
		)
		(polygon
			(pts
				(arc
					(start 7.39013 -310.571388)
					(mid 7.405009 -310.607309)
					(end 7.44093 -310.622188)
				)
				(arc
					(start 8.84047 -310.622188)
					(mid 8.876391 -310.607309)
					(end 8.89127 -310.571388)
				)
				(arc
					(start 8.89127 -310.162448)
					(mid 8.876391 -310.126527)
					(end 8.84047 -310.111648)
				)
				(arc
					(start 7.44093 -310.111648)
					(mid 7.405009 -310.126527)
					(end 7.39013 -310.162448)
				)
			)
		)
	)
	(zone
		(layers "In1.Cu" "In2.Cu")
		(hatch none 0.5)
		(connect_pads
			(clearance 0)
		)
		(min_thickness 0.25)
		(keepout
			(tracks not_allowed)
			(vias allowed)
			(pads allowed)
			(copperpour not_allowed)
			(footprints allowed)
		)
		(placement
			(enabled no)
			(sheetname "")
		)
		(fill yes
			(thermal_gap 0.5)
			(thermal_bridge_width 0.5)
			(island_removal_mode 0)
		)
		(polygon
			(pts
				(arc
					(start 26.577798 -248.521474)
					(mid 26.592677 -248.557395)
					(end 26.628598 -248.572274)
				)
				(arc
					(start 28.028138 -248.572274)
					(mid 28.064059 -248.557395)
					(end 28.078938 -248.521474)
				)
				(arc
					(start 28.078938 -248.112534)
					(mid 28.064059 -248.076613)
					(end 28.028138 -248.061734)
				)
				(arc
					(start 26.628598 -248.061734)
					(mid 26.592677 -248.076613)
					(end 26.577798 -248.112534)
				)
			)
		)
	)
	(zone
		(layers "In1.Cu" "In2.Cu")
		(hatch none 0.5)
		(connect_pads
			(clearance 0)
		)
		(min_thickness 0.25)
		(keepout
			(tracks not_allowed)
			(vias allowed)
			(pads allowed)
			(copperpour not_allowed)
			(footprints allowed)
		)
		(placement
			(enabled no)
			(sheetname "")
		)
		(fill yes
			(thermal_gap 0.5)
			(thermal_bridge_width 0.5)
			(island_removal_mode 0)
		)
		(polygon
			(pts
				(arc
					(start 455.365866 -245.12143)
					(mid 455.380745 -245.157351)
					(end 455.416666 -245.17223)
				)
				(arc
					(start 456.816206 -245.17223)
					(mid 456.852127 -245.157351)
					(end 456.867006 -245.12143)
				)
				(arc
					(start 456.867006 -244.71249)
					(mid 456.852127 -244.676569)
					(end 456.816206 -244.66169)
				)
				(arc
					(start 455.416666 -244.66169)
					(mid 455.380745 -244.676569)
					(end 455.365866 -244.71249)
				)
			)
		)
	)
	(zone
		(layers "In1.Cu" "In2.Cu")
		(hatch none 0.5)
		(connect_pads
			(clearance 0)
		)
		(min_thickness 0.25)
		(keepout
			(tracks not_allowed)
			(vias allowed)
			(pads allowed)
			(copperpour not_allowed)
			(footprints allowed)
		)
		(placement
			(enabled no)
			(sheetname "")
		)
		(fill yes
			(thermal_gap 0.5)
			(thermal_bridge_width 0.5)
			(island_removal_mode 0)
		)
		(polygon
			(pts
				(arc
					(start 274.517866 -302.071532)
					(mid 274.532745 -302.107453)
					(end 274.568666 -302.122332)
				)
				(arc
					(start 275.968206 -302.122332)
					(mid 276.004127 -302.107453)
					(end 276.019006 -302.071532)
				)
				(arc
					(start 276.019006 -301.662592)
					(mid 276.004127 -301.626671)
					(end 275.968206 -301.611792)
				)
				(arc
					(start 274.568666 -301.611792)
					(mid 274.532745 -301.626671)
					(end 274.517866 -301.662592)
				)
			)
		)
	)
	(zone
		(layers "In1.Cu" "In2.Cu")
		(hatch none 0.5)
		(connect_pads
			(clearance 0)
		)
		(min_thickness 0.25)
		(keepout
			(tracks not_allowed)
			(vias allowed)
			(pads allowed)
			(copperpour not_allowed)
			(footprints allowed)
		)
		(placement
			(enabled no)
			(sheetname "")
		)
		(fill yes
			(thermal_gap 0.5)
			(thermal_bridge_width 0.5)
			(island_removal_mode 0)
		)
		(polygon
			(pts
				(arc
					(start 297.149266 -250.221496)
					(mid 297.164145 -250.257417)
					(end 297.200066 -250.272296)
				)
				(arc
					(start 298.599606 -250.272296)
					(mid 298.635527 -250.257417)
					(end 298.650406 -250.221496)
				)
				(arc
					(start 298.650406 -249.812556)
					(mid 298.635527 -249.776635)
					(end 298.599606 -249.761756)
				)
				(arc
					(start 297.200066 -249.761756)
					(mid 297.164145 -249.776635)
					(end 297.149266 -249.812556)
				)
			)
		)
	)
	(zone
		(layers "In1.Cu" "In2.Cu")
		(hatch none 0.5)
		(connect_pads
			(clearance 0)
		)
		(min_thickness 0.25)
		(keepout
			(tracks not_allowed)
			(vias allowed)
			(pads allowed)
			(copperpour not_allowed)
			(footprints allowed)
		)
		(placement
			(enabled no)
			(sheetname "")
		)
		(fill yes
			(thermal_gap 0.5)
			(thermal_bridge_width 0.5)
			(island_removal_mode 0)
		)
		(polygon
			(pts
				(arc
					(start 184.794398 -231.521508)
					(mid 184.809277 -231.557429)
					(end 184.845198 -231.572308)
				)
				(arc
					(start 186.244738 -231.572308)
					(mid 186.280659 -231.557429)
					(end 186.295538 -231.521508)
				)
				(arc
					(start 186.295538 -231.112568)
					(mid 186.280659 -231.076647)
					(end 186.244738 -231.061768)
				)
				(arc
					(start 184.845198 -231.061768)
					(mid 184.809277 -231.076647)
					(end 184.794398 -231.112568)
				)
			)
		)
	)
	(zone
		(layers "In1.Cu" "In2.Cu")
		(hatch none 0.5)
		(connect_pads
			(clearance 0)
		)
		(min_thickness 0.25)
		(keepout
			(tracks not_allowed)
			(vias allowed)
			(pads allowed)
			(copperpour not_allowed)
			(footprints allowed)
		)
		(placement
			(enabled no)
			(sheetname "")
		)
		(fill yes
			(thermal_gap 0.5)
			(thermal_bridge_width 0.5)
			(island_removal_mode 0)
		)
		(polygon
			(pts
				(arc
					(start 26.577798 -308.021482)
					(mid 26.592677 -308.057403)
					(end 26.628598 -308.072282)
				)
				(arc
					(start 28.028138 -308.072282)
					(mid 28.064059 -308.057403)
					(end 28.078938 -308.021482)
				)
				(arc
					(start 28.078938 -307.612542)
					(mid 28.064059 -307.576621)
					(end 28.028138 -307.561742)
				)
				(arc
					(start 26.628598 -307.561742)
					(mid 26.592677 -307.576621)
					(end 26.577798 -307.612542)
				)
			)
		)
	)
	(zone
		(layers "In1.Cu" "In2.Cu")
		(hatch none 0.5)
		(connect_pads
			(clearance 0)
		)
		(min_thickness 0.25)
		(keepout
			(tracks not_allowed)
			(vias allowed)
			(pads allowed)
			(copperpour not_allowed)
			(footprints allowed)
		)
		(placement
			(enabled no)
			(sheetname "")
		)
		(fill yes
			(thermal_gap 0.5)
			(thermal_bridge_width 0.5)
			(island_removal_mode 0)
		)
		(polygon
			(pts
				(arc
					(start 413.546798 -218.77147)
					(mid 413.561677 -218.807391)
					(end 413.597598 -218.82227)
				)
				(arc
					(start 414.997138 -218.82227)
					(mid 415.033059 -218.807391)
					(end 415.047938 -218.77147)
				)
				(arc
					(start 415.047938 -218.36253)
					(mid 415.033059 -218.326609)
					(end 414.997138 -218.31173)
				)
				(arc
					(start 413.597598 -218.31173)
					(mid 413.561677 -218.326609)
					(end 413.546798 -218.36253)
				)
			)
		)
	)
	(zone
		(layers "In1.Cu" "In2.Cu")
		(hatch none 0.5)
		(connect_pads
			(clearance 0)
		)
		(min_thickness 0.25)
		(keepout
			(tracks not_allowed)
			(vias allowed)
			(pads allowed)
			(copperpour not_allowed)
			(footprints allowed)
		)
		(placement
			(enabled no)
			(sheetname "")
		)
		(fill yes
			(thermal_gap 0.5)
			(thermal_bridge_width 0.5)
			(island_removal_mode 0)
		)
		(polygon
			(pts
				(arc
					(start 207.425798 -259.57149)
					(mid 207.440677 -259.607411)
					(end 207.476598 -259.62229)
				)
				(arc
					(start 208.876138 -259.62229)
					(mid 208.912059 -259.607411)
					(end 208.926938 -259.57149)
				)
				(arc
					(start 208.926938 -259.16255)
					(mid 208.912059 -259.126629)
					(end 208.876138 -259.11175)
				)
				(arc
					(start 207.476598 -259.11175)
					(mid 207.440677 -259.126629)
					(end 207.425798 -259.16255)
				)
			)
		)
	)
	(zone
		(layers "In1.Cu" "In2.Cu")
		(hatch none 0.5)
		(connect_pads
			(clearance 0)
		)
		(min_thickness 0.25)
		(keepout
			(tracks not_allowed)
			(vias allowed)
			(pads allowed)
			(copperpour not_allowed)
			(footprints allowed)
		)
		(placement
			(enabled no)
			(sheetname "")
		)
		(fill yes
			(thermal_gap 0.5)
			(thermal_bridge_width 0.5)
			(island_removal_mode 0)
		)
		(polygon
			(pts
				(arc
					(start 458.809598 -249.371358)
					(mid 458.824477 -249.407279)
					(end 458.860398 -249.422158)
				)
				(arc
					(start 460.259938 -249.422158)
					(mid 460.295859 -249.407279)
					(end 460.310738 -249.371358)
				)
				(arc
					(start 460.310738 -248.962418)
					(mid 460.295859 -248.926497)
					(end 460.259938 -248.911618)
				)
				(arc
					(start 458.860398 -248.911618)
					(mid 458.824477 -248.926497)
					(end 458.809598 -248.962418)
				)
			)
		)
	)
	(zone
		(layers "In1.Cu" "In2.Cu")
		(hatch none 0.5)
		(connect_pads
			(clearance 0)
		)
		(min_thickness 0.25)
		(keepout
			(tracks not_allowed)
			(vias allowed)
			(pads allowed)
			(copperpour not_allowed)
			(footprints allowed)
		)
		(placement
			(enabled no)
			(sheetname "")
		)
		(fill yes
			(thermal_gap 0.5)
			(thermal_bridge_width 0.5)
			(island_removal_mode 0)
		)
		(polygon
			(pts
				(arc
					(start 432.734466 -233.22153)
					(mid 432.749345 -233.257451)
					(end 432.785266 -233.27233)
				)
				(arc
					(start 434.184806 -233.27233)
					(mid 434.220727 -233.257451)
					(end 434.235606 -233.22153)
				)
				(arc
					(start 434.235606 -232.81259)
					(mid 434.220727 -232.776669)
					(end 434.184806 -232.76179)
				)
				(arc
					(start 432.785266 -232.76179)
					(mid 432.749345 -232.776669)
					(end 432.734466 -232.81259)
				)
			)
		)
	)
	(zone
		(layers "In1.Cu" "In2.Cu")
		(hatch none 0.5)
		(connect_pads
			(clearance 0)
		)
		(min_thickness 0.25)
		(keepout
			(tracks not_allowed)
			(vias allowed)
			(pads allowed)
			(copperpour not_allowed)
			(footprints allowed)
		)
		(placement
			(enabled no)
			(sheetname "")
		)
		(fill yes
			(thermal_gap 0.5)
			(thermal_bridge_width 0.5)
			(island_removal_mode 0)
		)
		(polygon
			(pts
				(arc
					(start 41.665398 -197.521322)
					(mid 41.680277 -197.557243)
					(end 41.716198 -197.572122)
				)
				(arc
					(start 43.115738 -197.572122)
					(mid 43.151659 -197.557243)
					(end 43.166538 -197.521322)
				)
				(arc
					(start 43.166538 -197.112382)
					(mid 43.151659 -197.076461)
					(end 43.115738 -197.061582)
				)
				(arc
					(start 41.716198 -197.061582)
					(mid 41.680277 -197.076461)
					(end 41.665398 -197.112382)
				)
			)
		)
	)
	(zone
		(layers "In1.Cu" "In2.Cu")
		(hatch none 0.5)
		(connect_pads
			(clearance 0)
		)
		(min_thickness 0.25)
		(keepout
			(tracks not_allowed)
			(vias allowed)
			(pads allowed)
			(copperpour not_allowed)
			(footprints allowed)
		)
		(placement
			(enabled no)
			(sheetname "")
		)
		(fill yes
			(thermal_gap 0.5)
			(thermal_bridge_width 0.5)
			(island_removal_mode 0)
		)
		(polygon
			(pts
				(arc
					(start 180.69433 -211.971382)
					(mid 180.709209 -212.007303)
					(end 180.74513 -212.022182)
				)
				(arc
					(start 182.14467 -212.022182)
					(mid 182.180591 -212.007303)
					(end 182.19547 -211.971382)
				)
				(arc
					(start 182.19547 -211.562442)
					(mid 182.180591 -211.526521)
					(end 182.14467 -211.511642)
				)
				(arc
					(start 180.74513 -211.511642)
					(mid 180.709209 -211.526521)
					(end 180.69433 -211.562442)
				)
			)
		)
	)
	(zone
		(layers "In1.Cu" "In2.Cu")
		(hatch none 0.5)
		(connect_pads
			(clearance 0)
		)
		(min_thickness 0.25)
		(keepout
			(tracks not_allowed)
			(vias allowed)
			(pads allowed)
			(copperpour not_allowed)
			(footprints allowed)
		)
		(placement
			(enabled no)
			(sheetname "")
		)
		(fill yes
			(thermal_gap 0.5)
			(thermal_bridge_width 0.5)
			(island_removal_mode 0)
		)
		(polygon
			(pts
				(arc
					(start 11.490198 -208.571338)
					(mid 11.505077 -208.607259)
					(end 11.540998 -208.622138)
				)
				(arc
					(start 12.940538 -208.622138)
					(mid 12.976459 -208.607259)
					(end 12.991338 -208.571338)
				)
				(arc
					(start 12.991338 -208.162398)
					(mid 12.976459 -208.126477)
					(end 12.940538 -208.111598)
				)
				(arc
					(start 11.540998 -208.111598)
					(mid 11.505077 -208.126477)
					(end 11.490198 -208.162398)
				)
			)
		)
	)
	(zone
		(layers "In1.Cu" "In2.Cu")
		(hatch none 0.5)
		(connect_pads
			(clearance 0)
		)
		(min_thickness 0.25)
		(keepout
			(tracks not_allowed)
			(vias allowed)
			(pads allowed)
			(copperpour not_allowed)
			(footprints allowed)
		)
		(placement
			(enabled no)
			(sheetname "")
		)
		(fill yes
			(thermal_gap 0.5)
			(thermal_bridge_width 0.5)
			(island_removal_mode 0)
		)
		(polygon
			(pts
				(arc
					(start 297.149266 -268.921484)
					(mid 297.164145 -268.957405)
					(end 297.200066 -268.972284)
				)
				(arc
					(start 298.599606 -268.972284)
					(mid 298.635527 -268.957405)
					(end 298.650406 -268.921484)
				)
				(arc
					(start 298.650406 -268.512544)
					(mid 298.635527 -268.476623)
					(end 298.599606 -268.461744)
				)
				(arc
					(start 297.200066 -268.461744)
					(mid 297.164145 -268.476623)
					(end 297.149266 -268.512544)
				)
			)
		)
	)
	(zone
		(layers "In1.Cu" "In2.Cu")
		(hatch none 0.5)
		(connect_pads
			(clearance 0)
		)
		(min_thickness 0.25)
		(keepout
			(tracks not_allowed)
			(vias allowed)
			(pads allowed)
			(copperpour not_allowed)
			(footprints allowed)
		)
		(placement
			(enabled no)
			(sheetname "")
		)
		(fill yes
			(thermal_gap 0.5)
			(thermal_bridge_width 0.5)
			(island_removal_mode 0)
		)
		(polygon
			(pts
				(arc
					(start 270.417798 -215.371426)
					(mid 270.432677 -215.407347)
					(end 270.468598 -215.422226)
				)
				(arc
					(start 271.868138 -215.422226)
					(mid 271.904059 -215.407347)
					(end 271.918938 -215.371426)
				)
				(arc
					(start 271.918938 -214.962486)
					(mid 271.904059 -214.926565)
					(end 271.868138 -214.911686)
				)
				(arc
					(start 270.468598 -214.911686)
					(mid 270.432677 -214.926565)
					(end 270.417798 -214.962486)
				)
			)
		)
	)
	(zone
		(layers "In1.Cu" "In2.Cu")
		(hatch none 0.5)
		(connect_pads
			(clearance 0)
		)
		(min_thickness 0.25)
		(keepout
			(tracks not_allowed)
			(vias allowed)
			(pads allowed)
			(copperpour not_allowed)
			(footprints allowed)
		)
		(placement
			(enabled no)
			(sheetname "")
		)
		(fill yes
			(thermal_gap 0.5)
			(thermal_bridge_width 0.5)
			(island_removal_mode 0)
		)
		(polygon
			(pts
				(arc
					(start 45.10913 -218.77147)
					(mid 45.124009 -218.807391)
					(end 45.15993 -218.82227)
				)
				(arc
					(start 46.55947 -218.82227)
					(mid 46.595391 -218.807391)
					(end 46.61027 -218.77147)
				)
				(arc
					(start 46.61027 -218.36253)
					(mid 46.595391 -218.326609)
					(end 46.55947 -218.31173)
				)
				(arc
					(start 45.15993 -218.31173)
					(mid 45.124009 -218.326609)
					(end 45.10913 -218.36253)
				)
			)
		)
	)
	(zone
		(layers "In1.Cu" "In2.Cu")
		(hatch none 0.5)
		(connect_pads
			(clearance 0)
		)
		(min_thickness 0.25)
		(keepout
			(tracks not_allowed)
			(vias allowed)
			(pads allowed)
			(copperpour not_allowed)
			(footprints allowed)
		)
		(placement
			(enabled no)
			(sheetname "")
		)
		(fill yes
			(thermal_gap 0.5)
			(thermal_bridge_width 0.5)
			(island_removal_mode 0)
		)
		(polygon
			(pts
				(arc
					(start 308.136798 -252.771402)
					(mid 308.151677 -252.807323)
					(end 308.187598 -252.822202)
				)
				(arc
					(start 309.587138 -252.822202)
					(mid 309.623059 -252.807323)
					(end 309.637938 -252.771402)
				)
				(arc
					(start 309.637938 -252.362462)
					(mid 309.623059 -252.326541)
					(end 309.587138 -252.311662)
				)
				(arc
					(start 308.187598 -252.311662)
					(mid 308.151677 -252.326541)
					(end 308.136798 -252.362462)
				)
			)
		)
	)
	(zone
		(layers "In1.Cu" "In2.Cu")
		(hatch none 0.5)
		(connect_pads
			(clearance 0)
		)
		(min_thickness 0.25)
		(keepout
			(tracks not_allowed)
			(vias allowed)
			(pads allowed)
			(copperpour not_allowed)
			(footprints allowed)
		)
		(placement
			(enabled no)
			(sheetname "")
		)
		(fill yes
			(thermal_gap 0.5)
			(thermal_bridge_width 0.5)
			(island_removal_mode 0)
		)
		(polygon
			(pts
				(arc
					(start 165.60673 -293.571422)
					(mid 165.621609 -293.607343)
					(end 165.65753 -293.622222)
				)
				(arc
					(start 167.05707 -293.622222)
					(mid 167.092991 -293.607343)
					(end 167.10787 -293.571422)
				)
				(arc
					(start 167.10787 -293.162482)
					(mid 167.092991 -293.126561)
					(end 167.05707 -293.111682)
				)
				(arc
					(start 165.65753 -293.111682)
					(mid 165.621609 -293.126561)
					(end 165.60673 -293.162482)
				)
			)
		)
	)
	(zone
		(layers "In1.Cu" "In2.Cu")
		(hatch none 0.5)
		(connect_pads
			(clearance 0)
		)
		(min_thickness 0.25)
		(keepout
			(tracks not_allowed)
			(vias allowed)
			(pads allowed)
			(copperpour not_allowed)
			(footprints allowed)
		)
		(placement
			(enabled no)
			(sheetname "")
		)
		(fill yes
			(thermal_gap 0.5)
			(thermal_bridge_width 0.5)
			(island_removal_mode 0)
		)
		(polygon
			(pts
				(arc
					(start 203.32573 -286.771334)
					(mid 203.340609 -286.807255)
					(end 203.37653 -286.822134)
				)
				(arc
					(start 204.77607 -286.822134)
					(mid 204.811991 -286.807255)
					(end 204.82687 -286.771334)
				)
				(arc
					(start 204.82687 -286.362394)
					(mid 204.811991 -286.326473)
					(end 204.77607 -286.311594)
				)
				(arc
					(start 203.37653 -286.311594)
					(mid 203.340609 -286.326473)
					(end 203.32573 -286.362394)
				)
			)
		)
	)
	(zone
		(layers "In1.Cu" "In2.Cu")
		(hatch none 0.5)
		(connect_pads
			(clearance 0)
		)
		(min_thickness 0.25)
		(keepout
			(tracks not_allowed)
			(vias allowed)
			(pads allowed)
			(copperpour not_allowed)
			(footprints allowed)
		)
		(placement
			(enabled no)
			(sheetname "")
		)
		(fill yes
			(thermal_gap 0.5)
			(thermal_bridge_width 0.5)
			(island_removal_mode 0)
		)
		(polygon
			(pts
				(arc
					(start 421.090598 -305.471322)
					(mid 421.105477 -305.507243)
					(end 421.141398 -305.522122)
				)
				(arc
					(start 422.540938 -305.522122)
					(mid 422.576859 -305.507243)
					(end 422.591738 -305.471322)
				)
				(arc
					(start 422.591738 -305.062382)
					(mid 422.576859 -305.026461)
					(end 422.540938 -305.011582)
				)
				(arc
					(start 421.141398 -305.011582)
					(mid 421.105477 -305.026461)
					(end 421.090598 -305.062382)
				)
			)
		)
	)
	(zone
		(layers "In1.Cu" "In2.Cu")
		(hatch none 0.5)
		(connect_pads
			(clearance 0)
		)
		(min_thickness 0.25)
		(keepout
			(tracks not_allowed)
			(vias allowed)
			(pads allowed)
			(copperpour not_allowed)
			(footprints allowed)
		)
		(placement
			(enabled no)
			(sheetname "")
		)
		(fill yes
			(thermal_gap 0.5)
			(thermal_bridge_width 0.5)
			(island_removal_mode 0)
		)
		(polygon
			(pts
				(arc
					(start 282.061666 -263.821418)
					(mid 282.076545 -263.857339)
					(end 282.112466 -263.872218)
				)
				(arc
					(start 283.512006 -263.872218)
					(mid 283.547927 -263.857339)
					(end 283.562806 -263.821418)
				)
				(arc
					(start 283.562806 -263.412478)
					(mid 283.547927 -263.376557)
					(end 283.512006 -263.361678)
				)
				(arc
					(start 282.112466 -263.361678)
					(mid 282.076545 -263.376557)
					(end 282.061666 -263.412478)
				)
			)
		)
	)
	(zone
		(layers "In1.Cu" "In2.Cu")
		(hatch none 0.5)
		(connect_pads
			(clearance 0)
		)
		(min_thickness 0.25)
		(keepout
			(tracks not_allowed)
			(vias allowed)
			(pads allowed)
			(copperpour not_allowed)
			(footprints allowed)
		)
		(placement
			(enabled no)
			(sheetname "")
		)
		(fill yes
			(thermal_gap 0.5)
			(thermal_bridge_width 0.5)
			(island_removal_mode 0)
		)
		(polygon
			(pts
				(arc
					(start 184.794398 -220.471492)
					(mid 184.809277 -220.507413)
					(end 184.845198 -220.522292)
				)
				(arc
					(start 186.244738 -220.522292)
					(mid 186.280659 -220.507413)
					(end 186.295538 -220.471492)
				)
				(arc
					(start 186.295538 -220.062552)
					(mid 186.280659 -220.026631)
					(end 186.244738 -220.011752)
				)
				(arc
					(start 184.845198 -220.011752)
					(mid 184.809277 -220.026631)
					(end 184.794398 -220.062552)
				)
			)
		)
	)
	(zone
		(layers "In1.Cu" "In2.Cu")
		(hatch none 0.5)
		(connect_pads
			(clearance 0)
		)
		(min_thickness 0.25)
		(keepout
			(tracks not_allowed)
			(vias allowed)
			(pads allowed)
			(copperpour not_allowed)
			(footprints allowed)
		)
		(placement
			(enabled no)
			(sheetname "")
		)
		(fill yes
			(thermal_gap 0.5)
			(thermal_bridge_width 0.5)
			(island_removal_mode 0)
		)
		(polygon
			(pts
				(arc
					(start 289.605466 -208.571338)
					(mid 289.620345 -208.607259)
					(end 289.656266 -208.622138)
				)
				(arc
					(start 291.055806 -208.622138)
					(mid 291.091727 -208.607259)
					(end 291.106606 -208.571338)
				)
				(arc
					(start 291.106606 -208.162398)
					(mid 291.091727 -208.126477)
					(end 291.055806 -208.111598)
				)
				(arc
					(start 289.656266 -208.111598)
					(mid 289.620345 -208.126477)
					(end 289.605466 -208.162398)
				)
			)
		)
	)
	(zone
		(layers "In1.Cu" "In2.Cu")
		(hatch none 0.5)
		(connect_pads
			(clearance 0)
		)
		(min_thickness 0.25)
		(keepout
			(tracks not_allowed)
			(vias allowed)
			(pads allowed)
			(copperpour not_allowed)
			(footprints allowed)
		)
		(placement
			(enabled no)
			(sheetname "")
		)
		(fill yes
			(thermal_gap 0.5)
			(thermal_bridge_width 0.5)
			(island_removal_mode 0)
		)
		(polygon
			(pts
				(arc
					(start 297.149266 -298.671488)
					(mid 297.164145 -298.707409)
					(end 297.200066 -298.722288)
				)
				(arc
					(start 298.599606 -298.722288)
					(mid 298.635527 -298.707409)
					(end 298.650406 -298.671488)
				)
				(arc
					(start 298.650406 -298.262548)
					(mid 298.635527 -298.226627)
					(end 298.599606 -298.211748)
				)
				(arc
					(start 297.200066 -298.211748)
					(mid 297.164145 -298.226627)
					(end 297.149266 -298.262548)
				)
			)
		)
	)
	(zone
		(layers "In1.Cu" "In2.Cu")
		(hatch none 0.5)
		(connect_pads
			(clearance 0)
		)
		(min_thickness 0.25)
		(keepout
			(tracks not_allowed)
			(vias allowed)
			(pads allowed)
			(copperpour not_allowed)
			(footprints allowed)
		)
		(placement
			(enabled no)
			(sheetname "")
		)
		(fill yes
			(thermal_gap 0.5)
			(thermal_bridge_width 0.5)
			(island_removal_mode 0)
		)
		(polygon
			(pts
				(arc
					(start 282.061666 -302.921416)
					(mid 282.076545 -302.957337)
					(end 282.112466 -302.972216)
				)
				(arc
					(start 283.512006 -302.972216)
					(mid 283.547927 -302.957337)
					(end 283.562806 -302.921416)
				)
				(arc
					(start 283.562806 -302.512476)
					(mid 283.547927 -302.476555)
					(end 283.512006 -302.461676)
				)
				(arc
					(start 282.112466 -302.461676)
					(mid 282.076545 -302.476555)
					(end 282.061666 -302.512476)
				)
			)
		)
	)
	(zone
		(layers "In1.Cu" "In2.Cu")
		(hatch none 0.5)
		(connect_pads
			(clearance 0)
		)
		(min_thickness 0.25)
		(keepout
			(tracks not_allowed)
			(vias allowed)
			(pads allowed)
			(copperpour not_allowed)
			(footprints allowed)
		)
		(placement
			(enabled no)
			(sheetname "")
		)
		(fill yes
			(thermal_gap 0.5)
			(thermal_bridge_width 0.5)
			(island_removal_mode 0)
		)
		(polygon
			(pts
				(arc
					(start 262.873998 -269.771368)
					(mid 262.888877 -269.807289)
					(end 262.924798 -269.822168)
				)
				(arc
					(start 264.324338 -269.822168)
					(mid 264.360259 -269.807289)
					(end 264.375138 -269.771368)
				)
				(arc
					(start 264.375138 -269.362428)
					(mid 264.360259 -269.326507)
					(end 264.324338 -269.311628)
				)
				(arc
					(start 262.924798 -269.311628)
					(mid 262.888877 -269.326507)
					(end 262.873998 -269.362428)
				)
			)
		)
	)
	(zone
		(layers "In1.Cu" "In2.Cu")
		(hatch none 0.5)
		(connect_pads
			(clearance 0)
		)
		(min_thickness 0.25)
		(keepout
			(tracks not_allowed)
			(vias allowed)
			(pads allowed)
			(copperpour not_allowed)
			(footprints allowed)
		)
		(placement
			(enabled no)
			(sheetname "")
		)
		(fill yes
			(thermal_gap 0.5)
			(thermal_bridge_width 0.5)
			(island_removal_mode 0)
		)
		(polygon
			(pts
				(arc
					(start 406.002998 -217.071448)
					(mid 406.017877 -217.107369)
					(end 406.053798 -217.122248)
				)
				(arc
					(start 407.453338 -217.122248)
					(mid 407.489259 -217.107369)
					(end 407.504138 -217.071448)
				)
				(arc
					(start 407.504138 -216.662508)
					(mid 407.489259 -216.626587)
					(end 407.453338 -216.611708)
				)
				(arc
					(start 406.053798 -216.611708)
					(mid 406.017877 -216.626587)
					(end 406.002998 -216.662508)
				)
			)
		)
	)
	(zone
		(layers "In1.Cu" "In2.Cu")
		(hatch none 0.5)
		(connect_pads
			(clearance 0)
		)
		(min_thickness 0.25)
		(keepout
			(tracks not_allowed)
			(vias allowed)
			(pads allowed)
			(copperpour not_allowed)
			(footprints allowed)
		)
		(placement
			(enabled no)
			(sheetname "")
		)
		(fill yes
			(thermal_gap 0.5)
			(thermal_bridge_width 0.5)
			(island_removal_mode 0)
		)
		(polygon
			(pts
				(arc
					(start 297.149266 -251.921518)
					(mid 297.164145 -251.957439)
					(end 297.200066 -251.972318)
				)
				(arc
					(start 298.599606 -251.972318)
					(mid 298.635527 -251.957439)
					(end 298.650406 -251.921518)
				)
				(arc
					(start 298.650406 -251.512578)
					(mid 298.635527 -251.476657)
					(end 298.599606 -251.461778)
				)
				(arc
					(start 297.200066 -251.461778)
					(mid 297.164145 -251.476657)
					(end 297.149266 -251.512578)
				)
			)
		)
	)
	(zone
		(layers "In1.Cu" "In2.Cu")
		(hatch none 0.5)
		(connect_pads
			(clearance 0)
		)
		(min_thickness 0.25)
		(keepout
			(tracks not_allowed)
			(vias allowed)
			(pads allowed)
			(copperpour not_allowed)
			(footprints allowed)
		)
		(placement
			(enabled no)
			(sheetname "")
		)
		(fill yes
			(thermal_gap 0.5)
			(thermal_bridge_width 0.5)
			(island_removal_mode 0)
		)
		(polygon
			(pts
				(arc
					(start 56.752998 -217.921332)
					(mid 56.767877 -217.957253)
					(end 56.803798 -217.972132)
				)
				(arc
					(start 58.203338 -217.972132)
					(mid 58.239259 -217.957253)
					(end 58.254138 -217.921332)
				)
				(arc
					(start 58.254138 -217.512392)
					(mid 58.239259 -217.476471)
					(end 58.203338 -217.461592)
				)
				(arc
					(start 56.803798 -217.461592)
					(mid 56.767877 -217.476471)
					(end 56.752998 -217.512392)
				)
			)
		)
	)
	(zone
		(layers "In1.Cu" "In2.Cu")
		(hatch none 0.5)
		(connect_pads
			(clearance 0)
		)
		(min_thickness 0.25)
		(keepout
			(tracks not_allowed)
			(vias allowed)
			(pads allowed)
			(copperpour not_allowed)
			(footprints allowed)
		)
		(placement
			(enabled no)
			(sheetname "")
		)
		(fill yes
			(thermal_gap 0.5)
			(thermal_bridge_width 0.5)
			(island_removal_mode 0)
		)
		(polygon
			(pts
				(arc
					(start 262.873998 -288.471356)
					(mid 262.888877 -288.507277)
					(end 262.924798 -288.522156)
				)
				(arc
					(start 264.324338 -288.522156)
					(mid 264.360259 -288.507277)
					(end 264.375138 -288.471356)
				)
				(arc
					(start 264.375138 -288.062416)
					(mid 264.360259 -288.026495)
					(end 264.324338 -288.011616)
				)
				(arc
					(start 262.924798 -288.011616)
					(mid 262.888877 -288.026495)
					(end 262.873998 -288.062416)
				)
			)
		)
	)
	(zone
		(layers "In1.Cu" "In2.Cu")
		(hatch none 0.5)
		(connect_pads
			(clearance 0)
		)
		(min_thickness 0.25)
		(keepout
			(tracks not_allowed)
			(vias allowed)
			(pads allowed)
			(copperpour not_allowed)
			(footprints allowed)
		)
		(placement
			(enabled no)
			(sheetname "")
		)
		(fill yes
			(thermal_gap 0.5)
			(thermal_bridge_width 0.5)
			(island_removal_mode 0)
		)
		(polygon
			(pts
				(arc
					(start 184.794398 -259.57149)
					(mid 184.809277 -259.607411)
					(end 184.845198 -259.62229)
				)
				(arc
					(start 186.244738 -259.62229)
					(mid 186.280659 -259.607411)
					(end 186.295538 -259.57149)
				)
				(arc
					(start 186.295538 -259.16255)
					(mid 186.280659 -259.126629)
					(end 186.244738 -259.11175)
				)
				(arc
					(start 184.845198 -259.11175)
					(mid 184.809277 -259.126629)
					(end 184.794398 -259.16255)
				)
			)
		)
	)
	(zone
		(layers "In1.Cu" "In2.Cu")
		(hatch none 0.5)
		(connect_pads
			(clearance 0)
		)
		(min_thickness 0.25)
		(keepout
			(tracks not_allowed)
			(vias allowed)
			(pads allowed)
			(copperpour not_allowed)
			(footprints allowed)
		)
		(placement
			(enabled no)
			(sheetname "")
		)
		(fill yes
			(thermal_gap 0.5)
			(thermal_bridge_width 0.5)
			(island_removal_mode 0)
		)
		(polygon
			(pts
				(arc
					(start 56.752998 -208.571338)
					(mid 56.767877 -208.607259)
					(end 56.803798 -208.622138)
				)
				(arc
					(start 58.203338 -208.622138)
					(mid 58.239259 -208.607259)
					(end 58.254138 -208.571338)
				)
				(arc
					(start 58.254138 -208.162398)
					(mid 58.239259 -208.126477)
					(end 58.203338 -208.111598)
				)
				(arc
					(start 56.803798 -208.111598)
					(mid 56.767877 -208.126477)
					(end 56.752998 -208.162398)
				)
			)
		)
	)
	(zone
		(layers "In1.Cu" "In2.Cu")
		(hatch none 0.5)
		(connect_pads
			(clearance 0)
		)
		(min_thickness 0.25)
		(keepout
			(tracks not_allowed)
			(vias allowed)
			(pads allowed)
			(copperpour not_allowed)
			(footprints allowed)
		)
		(placement
			(enabled no)
			(sheetname "")
		)
		(fill yes
			(thermal_gap 0.5)
			(thermal_bridge_width 0.5)
			(island_removal_mode 0)
		)
		(polygon
			(pts
				(arc
					(start 282.061666 -236.62132)
					(mid 282.076545 -236.657241)
					(end 282.112466 -236.67212)
				)
				(arc
					(start 283.512006 -236.67212)
					(mid 283.547927 -236.657241)
					(end 283.562806 -236.62132)
				)
				(arc
					(start 283.562806 -236.21238)
					(mid 283.547927 -236.176459)
					(end 283.512006 -236.16158)
				)
				(arc
					(start 282.112466 -236.16158)
					(mid 282.076545 -236.176459)
					(end 282.061666 -236.21238)
				)
			)
		)
	)
	(zone
		(layers "In1.Cu" "In2.Cu")
		(hatch none 0.5)
		(connect_pads
			(clearance 0)
		)
		(min_thickness 0.25)
		(keepout
			(tracks not_allowed)
			(vias allowed)
			(pads allowed)
			(copperpour not_allowed)
			(footprints allowed)
		)
		(placement
			(enabled no)
			(sheetname "")
		)
		(fill yes
			(thermal_gap 0.5)
			(thermal_bridge_width 0.5)
			(island_removal_mode 0)
		)
		(polygon
			(pts
				(arc
					(start 165.60673 -261.271512)
					(mid 165.621609 -261.307433)
					(end 165.65753 -261.322312)
				)
				(arc
					(start 167.05707 -261.322312)
					(mid 167.092991 -261.307433)
					(end 167.10787 -261.271512)
				)
				(arc
					(start 167.10787 -260.862572)
					(mid 167.092991 -260.826651)
					(end 167.05707 -260.811772)
				)
				(arc
					(start 165.65753 -260.811772)
					(mid 165.621609 -260.826651)
					(end 165.60673 -260.862572)
				)
			)
		)
	)
	(zone
		(layers "In1.Cu" "In2.Cu")
		(hatch none 0.5)
		(connect_pads
			(clearance 0)
		)
		(min_thickness 0.25)
		(keepout
			(tracks not_allowed)
			(vias allowed)
			(pads allowed)
			(copperpour not_allowed)
			(footprints allowed)
		)
		(placement
			(enabled no)
			(sheetname "")
		)
		(fill yes
			(thermal_gap 0.5)
			(thermal_bridge_width 0.5)
			(island_removal_mode 0)
		)
		(polygon
			(pts
				(arc
					(start 425.190666 -225.571304)
					(mid 425.205545 -225.607225)
					(end 425.241466 -225.622104)
				)
				(arc
					(start 426.641006 -225.622104)
					(mid 426.676927 -225.607225)
					(end 426.691806 -225.571304)
				)
				(arc
					(start 426.691806 -225.162364)
					(mid 426.676927 -225.126443)
					(end 426.641006 -225.111564)
				)
				(arc
					(start 425.241466 -225.111564)
					(mid 425.205545 -225.126443)
					(end 425.190666 -225.162364)
				)
			)
		)
	)
	(zone
		(layers "In1.Cu" "In2.Cu")
		(hatch none 0.5)
		(connect_pads
			(clearance 0)
		)
		(min_thickness 0.25)
		(keepout
			(tracks not_allowed)
			(vias allowed)
			(pads allowed)
			(copperpour not_allowed)
			(footprints allowed)
		)
		(placement
			(enabled no)
			(sheetname "")
		)
		(fill yes
			(thermal_gap 0.5)
			(thermal_bridge_width 0.5)
			(island_removal_mode 0)
		)
		(polygon
			(pts
				(arc
					(start 52.65293 -268.071346)
					(mid 52.667809 -268.107267)
					(end 52.70373 -268.122146)
				)
				(arc
					(start 54.10327 -268.122146)
					(mid 54.139191 -268.107267)
					(end 54.15407 -268.071346)
				)
				(arc
					(start 54.15407 -267.662406)
					(mid 54.139191 -267.626485)
					(end 54.10327 -267.611606)
				)
				(arc
					(start 52.70373 -267.611606)
					(mid 52.667809 -267.626485)
					(end 52.65293 -267.662406)
				)
			)
		)
	)
	(zone
		(layers "In1.Cu" "In2.Cu")
		(hatch none 0.5)
		(connect_pads
			(clearance 0)
		)
		(min_thickness 0.25)
		(keepout
			(tracks not_allowed)
			(vias allowed)
			(pads allowed)
			(copperpour not_allowed)
			(footprints allowed)
		)
		(placement
			(enabled no)
			(sheetname "")
		)
		(fill yes
			(thermal_gap 0.5)
			(thermal_bridge_width 0.5)
			(island_removal_mode 0)
		)
		(polygon
			(pts
				(arc
					(start 289.605466 -195.821554)
					(mid 289.620345 -195.857475)
					(end 289.656266 -195.872354)
				)
				(arc
					(start 291.055806 -195.872354)
					(mid 291.091727 -195.857475)
					(end 291.106606 -195.821554)
				)
				(arc
					(start 291.106606 -195.412614)
					(mid 291.091727 -195.376693)
					(end 291.055806 -195.361814)
				)
				(arc
					(start 289.656266 -195.361814)
					(mid 289.620345 -195.376693)
					(end 289.605466 -195.412614)
				)
			)
		)
	)
	(zone
		(layers "In1.Cu" "In2.Cu")
		(hatch none 0.5)
		(connect_pads
			(clearance 0)
		)
		(min_thickness 0.25)
		(keepout
			(tracks not_allowed)
			(vias allowed)
			(pads allowed)
			(copperpour not_allowed)
			(footprints allowed)
		)
		(placement
			(enabled no)
			(sheetname "")
		)
		(fill yes
			(thermal_gap 0.5)
			(thermal_bridge_width 0.5)
			(island_removal_mode 0)
		)
		(polygon
			(pts
				(arc
					(start 180.69433 -273.171412)
					(mid 180.709209 -273.207333)
					(end 180.74513 -273.222212)
				)
				(arc
					(start 182.14467 -273.222212)
					(mid 182.180591 -273.207333)
					(end 182.19547 -273.171412)
				)
				(arc
					(start 182.19547 -272.762472)
					(mid 182.180591 -272.726551)
					(end 182.14467 -272.711672)
				)
				(arc
					(start 180.74513 -272.711672)
					(mid 180.709209 -272.726551)
					(end 180.69433 -272.762472)
				)
			)
		)
	)
	(zone
		(layers "In1.Cu" "In2.Cu")
		(hatch none 0.5)
		(connect_pads
			(clearance 0)
		)
		(min_thickness 0.25)
		(keepout
			(tracks not_allowed)
			(vias allowed)
			(pads allowed)
			(copperpour not_allowed)
			(footprints allowed)
		)
		(placement
			(enabled no)
			(sheetname "")
		)
		(fill yes
			(thermal_gap 0.5)
			(thermal_bridge_width 0.5)
			(island_removal_mode 0)
		)
		(polygon
			(pts
				(arc
					(start 413.546798 -299.521372)
					(mid 413.561677 -299.557293)
					(end 413.597598 -299.572172)
				)
				(arc
					(start 414.997138 -299.572172)
					(mid 415.033059 -299.557293)
					(end 415.047938 -299.521372)
				)
				(arc
					(start 415.047938 -299.112432)
					(mid 415.033059 -299.076511)
					(end 414.997138 -299.061632)
				)
				(arc
					(start 413.597598 -299.061632)
					(mid 413.561677 -299.076511)
					(end 413.546798 -299.112432)
				)
			)
		)
	)
	(zone
		(layers "In1.Cu" "In2.Cu")
		(hatch none 0.5)
		(connect_pads
			(clearance 0)
		)
		(min_thickness 0.25)
		(keepout
			(tracks not_allowed)
			(vias allowed)
			(pads allowed)
			(copperpour not_allowed)
			(footprints allowed)
		)
		(placement
			(enabled no)
			(sheetname "")
		)
		(fill yes
			(thermal_gap 0.5)
			(thermal_bridge_width 0.5)
			(island_removal_mode 0)
		)
		(polygon
			(pts
				(arc
					(start 41.665398 -220.471492)
					(mid 41.680277 -220.507413)
					(end 41.716198 -220.522292)
				)
				(arc
					(start 43.115738 -220.522292)
					(mid 43.151659 -220.507413)
					(end 43.166538 -220.471492)
				)
				(arc
					(start 43.166538 -220.062552)
					(mid 43.151659 -220.026631)
					(end 43.115738 -220.011752)
				)
				(arc
					(start 41.716198 -220.011752)
					(mid 41.680277 -220.026631)
					(end 41.665398 -220.062552)
				)
			)
		)
	)
	(zone
		(layers "In1.Cu" "In2.Cu")
		(hatch none 0.5)
		(connect_pads
			(clearance 0)
		)
		(min_thickness 0.25)
		(keepout
			(tracks not_allowed)
			(vias allowed)
			(pads allowed)
			(copperpour not_allowed)
			(footprints allowed)
		)
		(placement
			(enabled no)
			(sheetname "")
		)
		(fill yes
			(thermal_gap 0.5)
			(thermal_bridge_width 0.5)
			(island_removal_mode 0)
		)
		(polygon
			(pts
				(arc
					(start 180.69433 -234.071414)
					(mid 180.709209 -234.107335)
					(end 180.74513 -234.122214)
				)
				(arc
					(start 182.14467 -234.122214)
					(mid 182.180591 -234.107335)
					(end 182.19547 -234.071414)
				)
				(arc
					(start 182.19547 -233.662474)
					(mid 182.180591 -233.626553)
					(end 182.14467 -233.611674)
				)
				(arc
					(start 180.74513 -233.611674)
					(mid 180.709209 -233.626553)
					(end 180.69433 -233.662474)
				)
			)
		)
	)
	(zone
		(layers "In1.Cu" "In2.Cu")
		(hatch none 0.5)
		(connect_pads
			(clearance 0)
		)
		(min_thickness 0.25)
		(keepout
			(tracks not_allowed)
			(vias allowed)
			(pads allowed)
			(copperpour not_allowed)
			(footprints allowed)
		)
		(placement
			(enabled no)
			(sheetname "")
		)
		(fill yes
			(thermal_gap 0.5)
			(thermal_bridge_width 0.5)
			(island_removal_mode 0)
		)
		(polygon
			(pts
				(arc
					(start 158.06293 -238.321342)
					(mid 158.077809 -238.357263)
					(end 158.11373 -238.372142)
				)
				(arc
					(start 159.51327 -238.372142)
					(mid 159.549191 -238.357263)
					(end 159.56407 -238.321342)
				)
				(arc
					(start 159.56407 -237.912402)
					(mid 159.549191 -237.876481)
					(end 159.51327 -237.861602)
				)
				(arc
					(start 158.11373 -237.861602)
					(mid 158.077809 -237.876481)
					(end 158.06293 -237.912402)
				)
			)
		)
	)
	(zone
		(layers "In1.Cu" "In2.Cu")
		(hatch none 0.5)
		(connect_pads
			(clearance 0)
		)
		(min_thickness 0.25)
		(keepout
			(tracks not_allowed)
			(vias allowed)
			(pads allowed)
			(copperpour not_allowed)
			(footprints allowed)
		)
		(placement
			(enabled no)
			(sheetname "")
		)
		(fill yes
			(thermal_gap 0.5)
			(thermal_bridge_width 0.5)
			(island_removal_mode 0)
		)
		(polygon
			(pts
				(arc
					(start 440.278266 -306.32146)
					(mid 440.293145 -306.357381)
					(end 440.329066 -306.37226)
				)
				(arc
					(start 441.728606 -306.37226)
					(mid 441.764527 -306.357381)
					(end 441.779406 -306.32146)
				)
				(arc
					(start 441.779406 -305.91252)
					(mid 441.764527 -305.876599)
					(end 441.728606 -305.86172)
				)
				(arc
					(start 440.329066 -305.86172)
					(mid 440.293145 -305.876599)
					(end 440.278266 -305.91252)
				)
			)
		)
	)
	(zone
		(layers "In1.Cu" "In2.Cu")
		(hatch none 0.5)
		(connect_pads
			(clearance 0)
		)
		(min_thickness 0.25)
		(keepout
			(tracks not_allowed)
			(vias allowed)
			(pads allowed)
			(copperpour not_allowed)
			(footprints allowed)
		)
		(placement
			(enabled no)
			(sheetname "")
		)
		(fill yes
			(thermal_gap 0.5)
			(thermal_bridge_width 0.5)
			(island_removal_mode 0)
		)
		(polygon
			(pts
				(arc
					(start 308.136798 -293.571422)
					(mid 308.151677 -293.607343)
					(end 308.187598 -293.622222)
				)
				(arc
					(start 309.587138 -293.622222)
					(mid 309.623059 -293.607343)
					(end 309.637938 -293.571422)
				)
				(arc
					(start 309.637938 -293.162482)
					(mid 309.623059 -293.126561)
					(end 309.587138 -293.111682)
				)
				(arc
					(start 308.187598 -293.111682)
					(mid 308.151677 -293.126561)
					(end 308.136798 -293.162482)
				)
			)
		)
	)
	(zone
		(layers "In1.Cu" "In2.Cu")
		(hatch none 0.5)
		(connect_pads
			(clearance 0)
		)
		(min_thickness 0.25)
		(keepout
			(tracks not_allowed)
			(vias allowed)
			(pads allowed)
			(copperpour not_allowed)
			(footprints allowed)
		)
		(placement
			(enabled no)
			(sheetname "")
		)
		(fill yes
			(thermal_gap 0.5)
			(thermal_bridge_width 0.5)
			(island_removal_mode 0)
		)
		(polygon
			(pts
				(arc
					(start 440.278266 -304.621438)
					(mid 440.293145 -304.657359)
					(end 440.329066 -304.672238)
				)
				(arc
					(start 441.728606 -304.672238)
					(mid 441.764527 -304.657359)
					(end 441.779406 -304.621438)
				)
				(arc
					(start 441.779406 -304.212498)
					(mid 441.764527 -304.176577)
					(end 441.728606 -304.161698)
				)
				(arc
					(start 440.329066 -304.161698)
					(mid 440.293145 -304.176577)
					(end 440.278266 -304.212498)
				)
			)
		)
	)
	(zone
		(layers "In1.Cu" "In2.Cu")
		(hatch none 0.5)
		(connect_pads
			(clearance 0)
		)
		(min_thickness 0.25)
		(keepout
			(tracks not_allowed)
			(vias allowed)
			(pads allowed)
			(copperpour not_allowed)
			(footprints allowed)
		)
		(placement
			(enabled no)
			(sheetname "")
		)
		(fill yes
			(thermal_gap 0.5)
			(thermal_bridge_width 0.5)
			(island_removal_mode 0)
		)
		(polygon
			(pts
				(arc
					(start 277.961598 -200.071482)
					(mid 277.976477 -200.107403)
					(end 278.012398 -200.122282)
				)
				(arc
					(start 279.411938 -200.122282)
					(mid 279.447859 -200.107403)
					(end 279.462738 -200.071482)
				)
				(arc
					(start 279.462738 -199.662542)
					(mid 279.447859 -199.626621)
					(end 279.411938 -199.611742)
				)
				(arc
					(start 278.012398 -199.611742)
					(mid 277.976477 -199.626621)
					(end 277.961598 -199.662542)
				)
			)
		)
	)
	(zone
		(layers "In1.Cu" "In2.Cu")
		(hatch none 0.5)
		(connect_pads
			(clearance 0)
		)
		(min_thickness 0.25)
		(keepout
			(tracks not_allowed)
			(vias allowed)
			(pads allowed)
			(copperpour not_allowed)
			(footprints allowed)
		)
		(placement
			(enabled no)
			(sheetname "")
		)
		(fill yes
			(thermal_gap 0.5)
			(thermal_bridge_width 0.5)
			(island_removal_mode 0)
		)
		(polygon
			(pts
				(arc
					(start 410.103066 -296.971466)
					(mid 410.117945 -297.007387)
					(end 410.153866 -297.022266)
				)
				(arc
					(start 411.553406 -297.022266)
					(mid 411.589327 -297.007387)
					(end 411.604206 -296.971466)
				)
				(arc
					(start 411.604206 -296.562526)
					(mid 411.589327 -296.526605)
					(end 411.553406 -296.511726)
				)
				(arc
					(start 410.153866 -296.511726)
					(mid 410.117945 -296.526605)
					(end 410.103066 -296.562526)
				)
			)
		)
	)
	(zone
		(layers "In1.Cu" "In2.Cu")
		(hatch none 0.5)
		(connect_pads
			(clearance 0)
		)
		(min_thickness 0.25)
		(keepout
			(tracks not_allowed)
			(vias allowed)
			(pads allowed)
			(copperpour not_allowed)
			(footprints allowed)
		)
		(placement
			(enabled no)
			(sheetname "")
		)
		(fill yes
			(thermal_gap 0.5)
			(thermal_bridge_width 0.5)
			(island_removal_mode 0)
		)
		(polygon
			(pts
				(arc
					(start 188.23813 -310.571388)
					(mid 188.253009 -310.607309)
					(end 188.28893 -310.622188)
				)
				(arc
					(start 189.68847 -310.622188)
					(mid 189.724391 -310.607309)
					(end 189.73927 -310.571388)
				)
				(arc
					(start 189.73927 -310.162448)
					(mid 189.724391 -310.126527)
					(end 189.68847 -310.111648)
				)
				(arc
					(start 188.28893 -310.111648)
					(mid 188.253009 -310.126527)
					(end 188.23813 -310.162448)
				)
			)
		)
	)
	(zone
		(layers "In1.Cu" "In2.Cu")
		(hatch none 0.5)
		(connect_pads
			(clearance 0)
		)
		(min_thickness 0.25)
		(keepout
			(tracks not_allowed)
			(vias allowed)
			(pads allowed)
			(copperpour not_allowed)
			(footprints allowed)
		)
		(placement
			(enabled no)
			(sheetname "")
		)
		(fill yes
			(thermal_gap 0.5)
			(thermal_bridge_width 0.5)
			(island_removal_mode 0)
		)
		(polygon
			(pts
				(arc
					(start 30.02153 -230.67137)
					(mid 30.036409 -230.707291)
					(end 30.07233 -230.72217)
				)
				(arc
					(start 31.47187 -230.72217)
					(mid 31.507791 -230.707291)
					(end 31.52267 -230.67137)
				)
				(arc
					(start 31.52267 -230.26243)
					(mid 31.507791 -230.226509)
					(end 31.47187 -230.21163)
				)
				(arc
					(start 30.07233 -230.21163)
					(mid 30.036409 -230.226509)
					(end 30.02153 -230.26243)
				)
			)
		)
	)
	(zone
		(layers "In1.Cu" "In2.Cu")
		(hatch none 0.5)
		(connect_pads
			(clearance 0)
		)
		(min_thickness 0.25)
		(keepout
			(tracks not_allowed)
			(vias allowed)
			(pads allowed)
			(copperpour not_allowed)
			(footprints allowed)
		)
		(placement
			(enabled no)
			(sheetname "")
		)
		(fill yes
			(thermal_gap 0.5)
			(thermal_bridge_width 0.5)
			(island_removal_mode 0)
		)
		(polygon
			(pts
				(arc
					(start 406.002998 -266.371324)
					(mid 406.017877 -266.407245)
					(end 406.053798 -266.422124)
				)
				(arc
					(start 407.453338 -266.422124)
					(mid 407.489259 -266.407245)
					(end 407.504138 -266.371324)
				)
				(arc
					(start 407.504138 -265.962384)
					(mid 407.489259 -265.926463)
					(end 407.453338 -265.911584)
				)
				(arc
					(start 406.053798 -265.911584)
					(mid 406.017877 -265.926463)
					(end 406.002998 -265.962384)
				)
			)
		)
	)
	(zone
		(layers "In1.Cu" "In2.Cu")
		(hatch none 0.5)
		(connect_pads
			(clearance 0)
		)
		(min_thickness 0.25)
		(keepout
			(tracks not_allowed)
			(vias allowed)
			(pads allowed)
			(copperpour not_allowed)
			(footprints allowed)
		)
		(placement
			(enabled no)
			(sheetname "")
		)
		(fill yes
			(thermal_gap 0.5)
			(thermal_bridge_width 0.5)
			(island_removal_mode 0)
		)
		(polygon
			(pts
				(arc
					(start 203.32573 -198.37146)
					(mid 203.340609 -198.407381)
					(end 203.37653 -198.42226)
				)
				(arc
					(start 204.77607 -198.42226)
					(mid 204.811991 -198.407381)
					(end 204.82687 -198.37146)
				)
				(arc
					(start 204.82687 -197.96252)
					(mid 204.811991 -197.926599)
					(end 204.77607 -197.91172)
				)
				(arc
					(start 203.37653 -197.91172)
					(mid 203.340609 -197.926599)
					(end 203.32573 -197.96252)
				)
			)
		)
	)
	(zone
		(layers "In1.Cu" "In2.Cu")
		(hatch none 0.5)
		(connect_pads
			(clearance 0)
		)
		(min_thickness 0.25)
		(keepout
			(tracks not_allowed)
			(vias allowed)
			(pads allowed)
			(copperpour not_allowed)
			(footprints allowed)
		)
		(placement
			(enabled no)
			(sheetname "")
		)
		(fill yes
			(thermal_gap 0.5)
			(thermal_bridge_width 0.5)
			(island_removal_mode 0)
		)
		(polygon
			(pts
				(arc
					(start 266.974066 -231.521508)
					(mid 266.988945 -231.557429)
					(end 267.024866 -231.572308)
				)
				(arc
					(start 268.424406 -231.572308)
					(mid 268.460327 -231.557429)
					(end 268.475206 -231.521508)
				)
				(arc
					(start 268.475206 -231.112568)
					(mid 268.460327 -231.076647)
					(end 268.424406 -231.061768)
				)
				(arc
					(start 267.024866 -231.061768)
					(mid 266.988945 -231.076647)
					(end 266.974066 -231.112568)
				)
			)
		)
	)
	(zone
		(layers "In1.Cu" "In2.Cu")
		(hatch none 0.5)
		(connect_pads
			(clearance 0)
		)
		(min_thickness 0.25)
		(keepout
			(tracks not_allowed)
			(vias allowed)
			(pads allowed)
			(copperpour not_allowed)
			(footprints allowed)
		)
		(placement
			(enabled no)
			(sheetname "")
		)
		(fill yes
			(thermal_gap 0.5)
			(thermal_bridge_width 0.5)
			(island_removal_mode 0)
		)
		(polygon
			(pts
				(arc
					(start 297.149266 -240.871502)
					(mid 297.164145 -240.907423)
					(end 297.200066 -240.922302)
				)
				(arc
					(start 298.599606 -240.922302)
					(mid 298.635527 -240.907423)
					(end 298.650406 -240.871502)
				)
				(arc
					(start 298.650406 -240.462562)
					(mid 298.635527 -240.426641)
					(end 298.599606 -240.411762)
				)
				(arc
					(start 297.200066 -240.411762)
					(mid 297.164145 -240.426641)
					(end 297.149266 -240.462562)
				)
			)
		)
	)
	(zone
		(layers "In1.Cu" "In2.Cu")
		(hatch none 0.5)
		(connect_pads
			(clearance 0)
		)
		(min_thickness 0.25)
		(keepout
			(tracks not_allowed)
			(vias allowed)
			(pads allowed)
			(copperpour not_allowed)
			(footprints allowed)
		)
		(placement
			(enabled no)
			(sheetname "")
		)
		(fill yes
			(thermal_gap 0.5)
			(thermal_bridge_width 0.5)
			(island_removal_mode 0)
		)
		(polygon
			(pts
				(arc
					(start 293.049198 -273.171412)
					(mid 293.064077 -273.207333)
					(end 293.099998 -273.222212)
				)
				(arc
					(start 294.499538 -273.222212)
					(mid 294.535459 -273.207333)
					(end 294.550338 -273.171412)
				)
				(arc
					(start 294.550338 -272.762472)
					(mid 294.535459 -272.726551)
					(end 294.499538 -272.711672)
				)
				(arc
					(start 293.099998 -272.711672)
					(mid 293.064077 -272.726551)
					(end 293.049198 -272.762472)
				)
			)
		)
	)
	(zone
		(layers "In1.Cu" "In2.Cu")
		(hatch none 0.5)
		(connect_pads
			(clearance 0)
		)
		(min_thickness 0.25)
		(keepout
			(tracks not_allowed)
			(vias allowed)
			(pads allowed)
			(copperpour not_allowed)
			(footprints allowed)
		)
		(placement
			(enabled no)
			(sheetname "")
		)
		(fill yes
			(thermal_gap 0.5)
			(thermal_bridge_width 0.5)
			(island_removal_mode 0)
		)
		(polygon
			(pts
				(arc
					(start 45.10913 -249.371358)
					(mid 45.124009 -249.407279)
					(end 45.15993 -249.422158)
				)
				(arc
					(start 46.55947 -249.422158)
					(mid 46.595391 -249.407279)
					(end 46.61027 -249.371358)
				)
				(arc
					(start 46.61027 -248.962418)
					(mid 46.595391 -248.926497)
					(end 46.55947 -248.911618)
				)
				(arc
					(start 45.15993 -248.911618)
					(mid 45.124009 -248.926497)
					(end 45.10913 -248.962418)
				)
			)
		)
	)
	(zone
		(layers "In1.Cu" "In2.Cu")
		(hatch none 0.5)
		(connect_pads
			(clearance 0)
		)
		(min_thickness 0.25)
		(keepout
			(tracks not_allowed)
			(vias allowed)
			(pads allowed)
			(copperpour not_allowed)
			(footprints allowed)
		)
		(placement
			(enabled no)
			(sheetname "")
		)
		(fill yes
			(thermal_gap 0.5)
			(thermal_bridge_width 0.5)
			(island_removal_mode 0)
		)
		(polygon
			(pts
				(arc
					(start 7.39013 -291.8714)
					(mid 7.405009 -291.907321)
					(end 7.44093 -291.9222)
				)
				(arc
					(start 8.84047 -291.9222)
					(mid 8.876391 -291.907321)
					(end 8.89127 -291.8714)
				)
				(arc
					(start 8.89127 -291.46246)
					(mid 8.876391 -291.426539)
					(end 8.84047 -291.41166)
				)
				(arc
					(start 7.44093 -291.41166)
					(mid 7.405009 -291.426539)
					(end 7.39013 -291.46246)
				)
			)
		)
	)
	(zone
		(layers "In1.Cu" "In2.Cu")
		(hatch none 0.5)
		(connect_pads
			(clearance 0)
		)
		(min_thickness 0.25)
		(keepout
			(tracks not_allowed)
			(vias allowed)
			(pads allowed)
			(copperpour not_allowed)
			(footprints allowed)
		)
		(placement
			(enabled no)
			(sheetname "")
		)
		(fill yes
			(thermal_gap 0.5)
			(thermal_bridge_width 0.5)
			(island_removal_mode 0)
		)
		(polygon
			(pts
				(arc
					(start 455.365866 -251.921518)
					(mid 455.380745 -251.957439)
					(end 455.416666 -251.972318)
				)
				(arc
					(start 456.816206 -251.972318)
					(mid 456.852127 -251.957439)
					(end 456.867006 -251.921518)
				)
				(arc
					(start 456.867006 -251.512578)
					(mid 456.852127 -251.476657)
					(end 456.816206 -251.461778)
				)
				(arc
					(start 455.416666 -251.461778)
					(mid 455.380745 -251.476657)
					(end 455.365866 -251.512578)
				)
			)
		)
	)
	(zone
		(layers "In1.Cu" "In2.Cu")
		(hatch none 0.5)
		(connect_pads
			(clearance 0)
		)
		(min_thickness 0.25)
		(keepout
			(tracks not_allowed)
			(vias allowed)
			(pads allowed)
			(copperpour not_allowed)
			(footprints allowed)
		)
		(placement
			(enabled no)
			(sheetname "")
		)
		(fill yes
			(thermal_gap 0.5)
			(thermal_bridge_width 0.5)
			(island_removal_mode 0)
		)
		(polygon
			(pts
				(arc
					(start 14.93393 -207.721454)
					(mid 14.948809 -207.757375)
					(end 14.98473 -207.772254)
				)
				(arc
					(start 16.38427 -207.772254)
					(mid 16.420191 -207.757375)
					(end 16.43507 -207.721454)
				)
				(arc
					(start 16.43507 -207.312514)
					(mid 16.420191 -207.276593)
					(end 16.38427 -207.261714)
				)
				(arc
					(start 14.98473 -207.261714)
					(mid 14.948809 -207.276593)
					(end 14.93393 -207.312514)
				)
			)
		)
	)
	(zone
		(layers "In1.Cu" "In2.Cu")
		(hatch none 0.5)
		(connect_pads
			(clearance 0)
		)
		(min_thickness 0.25)
		(keepout
			(tracks not_allowed)
			(vias allowed)
			(pads allowed)
			(copperpour not_allowed)
			(footprints allowed)
		)
		(placement
			(enabled no)
			(sheetname "")
		)
		(fill yes
			(thermal_gap 0.5)
			(thermal_bridge_width 0.5)
			(island_removal_mode 0)
		)
		(polygon
			(pts
				(arc
					(start 308.136798 -259.57149)
					(mid 308.151677 -259.607411)
					(end 308.187598 -259.62229)
				)
				(arc
					(start 309.587138 -259.62229)
					(mid 309.623059 -259.607411)
					(end 309.637938 -259.57149)
				)
				(arc
					(start 309.637938 -259.16255)
					(mid 309.623059 -259.126629)
					(end 309.587138 -259.11175)
				)
				(arc
					(start 308.187598 -259.11175)
					(mid 308.151677 -259.126629)
					(end 308.136798 -259.16255)
				)
			)
		)
	)
	(zone
		(layers "In1.Cu" "In2.Cu")
		(hatch none 0.5)
		(connect_pads
			(clearance 0)
		)
		(min_thickness 0.25)
		(keepout
			(tracks not_allowed)
			(vias allowed)
			(pads allowed)
			(copperpour not_allowed)
			(footprints allowed)
		)
		(placement
			(enabled no)
			(sheetname "")
		)
		(fill yes
			(thermal_gap 0.5)
			(thermal_bridge_width 0.5)
			(island_removal_mode 0)
		)
		(polygon
			(pts
				(arc
					(start 413.546798 -264.671302)
					(mid 413.561677 -264.707223)
					(end 413.597598 -264.722102)
				)
				(arc
					(start 414.997138 -264.722102)
					(mid 415.033059 -264.707223)
					(end 415.047938 -264.671302)
				)
				(arc
					(start 415.047938 -264.262362)
					(mid 415.033059 -264.226441)
					(end 414.997138 -264.211562)
				)
				(arc
					(start 413.597598 -264.211562)
					(mid 413.561677 -264.226441)
					(end 413.546798 -264.262362)
				)
			)
		)
	)
	(zone
		(layers "In1.Cu" "In2.Cu")
		(hatch none 0.5)
		(connect_pads
			(clearance 0)
		)
		(min_thickness 0.25)
		(keepout
			(tracks not_allowed)
			(vias allowed)
			(pads allowed)
			(copperpour not_allowed)
			(footprints allowed)
		)
		(placement
			(enabled no)
			(sheetname "")
		)
		(fill yes
			(thermal_gap 0.5)
			(thermal_bridge_width 0.5)
			(island_removal_mode 0)
		)
		(polygon
			(pts
				(arc
					(start 266.974066 -211.121498)
					(mid 266.988945 -211.157419)
					(end 267.024866 -211.172298)
				)
				(arc
					(start 268.424406 -211.172298)
					(mid 268.460327 -211.157419)
					(end 268.475206 -211.121498)
				)
				(arc
					(start 268.475206 -210.712558)
					(mid 268.460327 -210.676637)
					(end 268.424406 -210.661758)
				)
				(arc
					(start 267.024866 -210.661758)
					(mid 266.988945 -210.676637)
					(end 266.974066 -210.712558)
				)
			)
		)
	)
	(zone
		(layers "In1.Cu" "In2.Cu")
		(hatch none 0.5)
		(connect_pads
			(clearance 0)
		)
		(min_thickness 0.25)
		(keepout
			(tracks not_allowed)
			(vias allowed)
			(pads allowed)
			(copperpour not_allowed)
			(footprints allowed)
		)
		(placement
			(enabled no)
			(sheetname "")
		)
		(fill yes
			(thermal_gap 0.5)
			(thermal_bridge_width 0.5)
			(island_removal_mode 0)
		)
		(polygon
			(pts
				(arc
					(start 210.86953 -206.021432)
					(mid 210.884409 -206.057353)
					(end 210.92033 -206.072232)
				)
				(arc
					(start 212.31987 -206.072232)
					(mid 212.355791 -206.057353)
					(end 212.37067 -206.021432)
				)
				(arc
					(start 212.37067 -205.612492)
					(mid 212.355791 -205.576571)
					(end 212.31987 -205.561692)
				)
				(arc
					(start 210.92033 -205.561692)
					(mid 210.884409 -205.576571)
					(end 210.86953 -205.612492)
				)
			)
		)
	)
	(zone
		(layers "In1.Cu" "In2.Cu")
		(hatch none 0.5)
		(connect_pads
			(clearance 0)
		)
		(min_thickness 0.25)
		(keepout
			(tracks not_allowed)
			(vias allowed)
			(pads allowed)
			(copperpour not_allowed)
			(footprints allowed)
		)
		(placement
			(enabled no)
			(sheetname "")
		)
		(fill yes
			(thermal_gap 0.5)
			(thermal_bridge_width 0.5)
			(island_removal_mode 0)
		)
		(polygon
			(pts
				(arc
					(start 462.909666 -229.821486)
					(mid 462.924545 -229.857407)
					(end 462.960466 -229.872286)
				)
				(arc
					(start 464.360006 -229.872286)
					(mid 464.395927 -229.857407)
					(end 464.410806 -229.821486)
				)
				(arc
					(start 464.410806 -229.412546)
					(mid 464.395927 -229.376625)
					(end 464.360006 -229.361746)
				)
				(arc
					(start 462.960466 -229.361746)
					(mid 462.924545 -229.376625)
					(end 462.909666 -229.412546)
				)
			)
		)
	)
	(zone
		(layers "In1.Cu" "In2.Cu")
		(hatch none 0.5)
		(connect_pads
			(clearance 0)
		)
		(min_thickness 0.25)
		(keepout
			(tracks not_allowed)
			(vias allowed)
			(pads allowed)
			(copperpour not_allowed)
			(footprints allowed)
		)
		(placement
			(enabled no)
			(sheetname "")
		)
		(fill yes
			(thermal_gap 0.5)
			(thermal_bridge_width 0.5)
			(island_removal_mode 0)
		)
		(polygon
			(pts
				(arc
					(start 195.78193 -224.72142)
					(mid 195.796809 -224.757341)
					(end 195.83273 -224.77222)
				)
				(arc
					(start 197.23227 -224.77222)
					(mid 197.268191 -224.757341)
					(end 197.28307 -224.72142)
				)
				(arc
					(start 197.28307 -224.31248)
					(mid 197.268191 -224.276559)
					(end 197.23227 -224.26168)
				)
				(arc
					(start 195.83273 -224.26168)
					(mid 195.796809 -224.276559)
					(end 195.78193 -224.31248)
				)
			)
		)
	)
	(zone
		(layers "In1.Cu" "In2.Cu")
		(hatch none 0.5)
		(connect_pads
			(clearance 0)
		)
		(min_thickness 0.25)
		(keepout
			(tracks not_allowed)
			(vias allowed)
			(pads allowed)
			(copperpour not_allowed)
			(footprints allowed)
		)
		(placement
			(enabled no)
			(sheetname "")
		)
		(fill yes
			(thermal_gap 0.5)
			(thermal_bridge_width 0.5)
			(island_removal_mode 0)
		)
		(polygon
			(pts
				(arc
					(start 417.646866 -308.021482)
					(mid 417.661745 -308.057403)
					(end 417.697666 -308.072282)
				)
				(arc
					(start 419.097206 -308.072282)
					(mid 419.133127 -308.057403)
					(end 419.148006 -308.021482)
				)
				(arc
					(start 419.148006 -307.612542)
					(mid 419.133127 -307.576621)
					(end 419.097206 -307.561742)
				)
				(arc
					(start 417.697666 -307.561742)
					(mid 417.661745 -307.576621)
					(end 417.646866 -307.612542)
				)
			)
		)
	)
	(zone
		(layers "In1.Cu" "In2.Cu")
		(hatch none 0.5)
		(connect_pads
			(clearance 0)
		)
		(min_thickness 0.25)
		(keepout
			(tracks not_allowed)
			(vias allowed)
			(pads allowed)
			(copperpour not_allowed)
			(footprints allowed)
		)
		(placement
			(enabled no)
			(sheetname "")
		)
		(fill yes
			(thermal_gap 0.5)
			(thermal_bridge_width 0.5)
			(island_removal_mode 0)
		)
		(polygon
			(pts
				(arc
					(start 462.909666 -223.871536)
					(mid 462.924545 -223.907457)
					(end 462.960466 -223.922336)
				)
				(arc
					(start 464.360006 -223.922336)
					(mid 464.395927 -223.907457)
					(end 464.410806 -223.871536)
				)
				(arc
					(start 464.410806 -223.462596)
					(mid 464.395927 -223.426675)
					(end 464.360006 -223.411796)
				)
				(arc
					(start 462.960466 -223.411796)
					(mid 462.924545 -223.426675)
					(end 462.909666 -223.462596)
				)
			)
		)
	)
	(zone
		(layers "In1.Cu" "In2.Cu")
		(hatch none 0.5)
		(connect_pads
			(clearance 0)
		)
		(min_thickness 0.25)
		(keepout
			(tracks not_allowed)
			(vias allowed)
			(pads allowed)
			(copperpour not_allowed)
			(footprints allowed)
		)
		(placement
			(enabled no)
			(sheetname "")
		)
		(fill yes
			(thermal_gap 0.5)
			(thermal_bridge_width 0.5)
			(island_removal_mode 0)
		)
		(polygon
			(pts
				(arc
					(start 421.090598 -209.421476)
					(mid 421.105477 -209.457397)
					(end 421.141398 -209.472276)
				)
				(arc
					(start 422.540938 -209.472276)
					(mid 422.576859 -209.457397)
					(end 422.591738 -209.421476)
				)
				(arc
					(start 422.591738 -209.012536)
					(mid 422.576859 -208.976615)
					(end 422.540938 -208.961736)
				)
				(arc
					(start 421.141398 -208.961736)
					(mid 421.105477 -208.976615)
					(end 421.090598 -209.012536)
				)
			)
		)
	)
	(zone
		(layers "In1.Cu" "In2.Cu")
		(hatch none 0.5)
		(connect_pads
			(clearance 0)
		)
		(min_thickness 0.25)
		(keepout
			(tracks not_allowed)
			(vias allowed)
			(pads allowed)
			(copperpour not_allowed)
			(footprints allowed)
		)
		(placement
			(enabled no)
			(sheetname "")
		)
		(fill yes
			(thermal_gap 0.5)
			(thermal_bridge_width 0.5)
			(island_removal_mode 0)
		)
		(polygon
			(pts
				(arc
					(start 165.60673 -280.821384)
					(mid 165.621609 -280.857305)
					(end 165.65753 -280.872184)
				)
				(arc
					(start 167.05707 -280.872184)
					(mid 167.092991 -280.857305)
					(end 167.10787 -280.821384)
				)
				(arc
					(start 167.10787 -280.412444)
					(mid 167.092991 -280.376523)
					(end 167.05707 -280.361644)
				)
				(arc
					(start 165.65753 -280.361644)
					(mid 165.621609 -280.376523)
					(end 165.60673 -280.412444)
				)
			)
		)
	)
	(zone
		(layers "In1.Cu" "In2.Cu")
		(hatch none 0.5)
		(connect_pads
			(clearance 0)
		)
		(min_thickness 0.25)
		(keepout
			(tracks not_allowed)
			(vias allowed)
			(pads allowed)
			(copperpour not_allowed)
			(footprints allowed)
		)
		(placement
			(enabled no)
			(sheetname "")
		)
		(fill yes
			(thermal_gap 0.5)
			(thermal_bridge_width 0.5)
			(island_removal_mode 0)
		)
		(polygon
			(pts
				(arc
					(start 440.278266 -285.92145)
					(mid 440.293145 -285.957371)
					(end 440.329066 -285.97225)
				)
				(arc
					(start 441.728606 -285.97225)
					(mid 441.764527 -285.957371)
					(end 441.779406 -285.92145)
				)
				(arc
					(start 441.779406 -285.51251)
					(mid 441.764527 -285.476589)
					(end 441.728606 -285.46171)
				)
				(arc
					(start 440.329066 -285.46171)
					(mid 440.293145 -285.476589)
					(end 440.278266 -285.51251)
				)
			)
		)
	)
	(zone
		(layers "In1.Cu" "In2.Cu")
		(hatch none 0.5)
		(connect_pads
			(clearance 0)
		)
		(min_thickness 0.25)
		(keepout
			(tracks not_allowed)
			(vias allowed)
			(pads allowed)
			(copperpour not_allowed)
			(footprints allowed)
		)
		(placement
			(enabled no)
			(sheetname "")
		)
		(fill yes
			(thermal_gap 0.5)
			(thermal_bridge_width 0.5)
			(island_removal_mode 0)
		)
		(polygon
			(pts
				(arc
					(start 45.10913 -266.371324)
					(mid 45.124009 -266.407245)
					(end 45.15993 -266.422124)
				)
				(arc
					(start 46.55947 -266.422124)
					(mid 46.595391 -266.407245)
					(end 46.61027 -266.371324)
				)
				(arc
					(start 46.61027 -265.962384)
					(mid 46.595391 -265.926463)
					(end 46.55947 -265.911584)
				)
				(arc
					(start 45.15993 -265.911584)
					(mid 45.124009 -265.926463)
					(end 45.10913 -265.962384)
				)
			)
		)
	)
	(zone
		(layers "In1.Cu" "In2.Cu")
		(hatch none 0.5)
		(connect_pads
			(clearance 0)
		)
		(min_thickness 0.25)
		(keepout
			(tracks not_allowed)
			(vias allowed)
			(pads allowed)
			(copperpour not_allowed)
			(footprints allowed)
		)
		(placement
			(enabled no)
			(sheetname "")
		)
		(fill yes
			(thermal_gap 0.5)
			(thermal_bridge_width 0.5)
			(island_removal_mode 0)
		)
		(polygon
			(pts
				(arc
					(start 425.190666 -259.57149)
					(mid 425.205545 -259.607411)
					(end 425.241466 -259.62229)
				)
				(arc
					(start 426.641006 -259.62229)
					(mid 426.676927 -259.607411)
					(end 426.691806 -259.57149)
				)
				(arc
					(start 426.691806 -259.16255)
					(mid 426.676927 -259.126629)
					(end 426.641006 -259.11175)
				)
				(arc
					(start 425.241466 -259.11175)
					(mid 425.205545 -259.126629)
					(end 425.190666 -259.16255)
				)
			)
		)
	)
	(zone
		(layers "In1.Cu" "In2.Cu")
		(hatch none 0.5)
		(connect_pads
			(clearance 0)
		)
		(min_thickness 0.25)
		(keepout
			(tracks not_allowed)
			(vias allowed)
			(pads allowed)
			(copperpour not_allowed)
			(footprints allowed)
		)
		(placement
			(enabled no)
			(sheetname "")
		)
		(fill yes
			(thermal_gap 0.5)
			(thermal_bridge_width 0.5)
			(island_removal_mode 0)
		)
		(polygon
			(pts
				(arc
					(start 158.06293 -206.021432)
					(mid 158.077809 -206.057353)
					(end 158.11373 -206.072232)
				)
				(arc
					(start 159.51327 -206.072232)
					(mid 159.549191 -206.057353)
					(end 159.56407 -206.021432)
				)
				(arc
					(start 159.56407 -205.612492)
					(mid 159.549191 -205.576571)
					(end 159.51327 -205.561692)
				)
				(arc
					(start 158.11373 -205.561692)
					(mid 158.077809 -205.576571)
					(end 158.06293 -205.612492)
				)
			)
		)
	)
	(zone
		(layers "In1.Cu" "In2.Cu")
		(hatch none 0.5)
		(connect_pads
			(clearance 0)
		)
		(min_thickness 0.25)
		(keepout
			(tracks not_allowed)
			(vias allowed)
			(pads allowed)
			(copperpour not_allowed)
			(footprints allowed)
		)
		(placement
			(enabled no)
			(sheetname "")
		)
		(fill yes
			(thermal_gap 0.5)
			(thermal_bridge_width 0.5)
			(island_removal_mode 0)
		)
		(polygon
			(pts
				(arc
					(start 417.646866 -236.62132)
					(mid 417.661745 -236.657241)
					(end 417.697666 -236.67212)
				)
				(arc
					(start 419.097206 -236.67212)
					(mid 419.133127 -236.657241)
					(end 419.148006 -236.62132)
				)
				(arc
					(start 419.148006 -236.21238)
					(mid 419.133127 -236.176459)
					(end 419.097206 -236.16158)
				)
				(arc
					(start 417.697666 -236.16158)
					(mid 417.661745 -236.176459)
					(end 417.646866 -236.21238)
				)
			)
		)
	)
	(zone
		(layers "In1.Cu" "In2.Cu")
		(hatch none 0.5)
		(connect_pads
			(clearance 0)
		)
		(min_thickness 0.25)
		(keepout
			(tracks not_allowed)
			(vias allowed)
			(pads allowed)
			(copperpour not_allowed)
			(footprints allowed)
		)
		(placement
			(enabled no)
			(sheetname "")
		)
		(fill yes
			(thermal_gap 0.5)
			(thermal_bridge_width 0.5)
			(island_removal_mode 0)
		)
		(polygon
			(pts
				(arc
					(start 30.02153 -210.27136)
					(mid 30.036409 -210.307281)
					(end 30.07233 -210.32216)
				)
				(arc
					(start 31.47187 -210.32216)
					(mid 31.507791 -210.307281)
					(end 31.52267 -210.27136)
				)
				(arc
					(start 31.52267 -209.86242)
					(mid 31.507791 -209.826499)
					(end 31.47187 -209.81162)
				)
				(arc
					(start 30.07233 -209.81162)
					(mid 30.036409 -209.826499)
					(end 30.02153 -209.86242)
				)
			)
		)
	)
	(zone
		(layers "In1.Cu" "In2.Cu")
		(hatch none 0.5)
		(connect_pads
			(clearance 0)
		)
		(min_thickness 0.25)
		(keepout
			(tracks not_allowed)
			(vias allowed)
			(pads allowed)
			(copperpour not_allowed)
			(footprints allowed)
		)
		(placement
			(enabled no)
			(sheetname "")
		)
		(fill yes
			(thermal_gap 0.5)
			(thermal_bridge_width 0.5)
			(island_removal_mode 0)
		)
		(polygon
			(pts
				(arc
					(start 428.634398 -282.521406)
					(mid 428.649277 -282.557327)
					(end 428.685198 -282.572206)
				)
				(arc
					(start 430.084738 -282.572206)
					(mid 430.120659 -282.557327)
					(end 430.135538 -282.521406)
				)
				(arc
					(start 430.135538 -282.112466)
					(mid 430.120659 -282.076545)
					(end 430.084738 -282.061666)
				)
				(arc
					(start 428.685198 -282.061666)
					(mid 428.649277 -282.076545)
					(end 428.634398 -282.112466)
				)
			)
		)
	)
	(zone
		(layers "In1.Cu" "In2.Cu")
		(hatch none 0.5)
		(connect_pads
			(clearance 0)
		)
		(min_thickness 0.25)
		(keepout
			(tracks not_allowed)
			(vias allowed)
			(pads allowed)
			(copperpour not_allowed)
			(footprints allowed)
		)
		(placement
			(enabled no)
			(sheetname "")
		)
		(fill yes
			(thermal_gap 0.5)
			(thermal_bridge_width 0.5)
			(island_removal_mode 0)
		)
		(polygon
			(pts
				(arc
					(start 192.338198 -218.77147)
					(mid 192.353077 -218.807391)
					(end 192.388998 -218.82227)
				)
				(arc
					(start 193.788538 -218.82227)
					(mid 193.824459 -218.807391)
					(end 193.839338 -218.77147)
				)
				(arc
					(start 193.839338 -218.36253)
					(mid 193.824459 -218.326609)
					(end 193.788538 -218.31173)
				)
				(arc
					(start 192.388998 -218.31173)
					(mid 192.353077 -218.326609)
					(end 192.338198 -218.36253)
				)
			)
		)
	)
	(zone
		(layers "In1.Cu" "In2.Cu")
		(hatch none 0.5)
		(connect_pads
			(clearance 0)
		)
		(min_thickness 0.25)
		(keepout
			(tracks not_allowed)
			(vias allowed)
			(pads allowed)
			(copperpour not_allowed)
			(footprints allowed)
		)
		(placement
			(enabled no)
			(sheetname "")
		)
		(fill yes
			(thermal_gap 0.5)
			(thermal_bridge_width 0.5)
			(island_removal_mode 0)
		)
		(polygon
			(pts
				(arc
					(start 14.93393 -285.071312)
					(mid 14.948809 -285.107233)
					(end 14.98473 -285.122112)
				)
				(arc
					(start 16.38427 -285.122112)
					(mid 16.420191 -285.107233)
					(end 16.43507 -285.071312)
				)
				(arc
					(start 16.43507 -284.662372)
					(mid 16.420191 -284.626451)
					(end 16.38427 -284.611572)
				)
				(arc
					(start 14.98473 -284.611572)
					(mid 14.948809 -284.626451)
					(end 14.93393 -284.662372)
				)
			)
		)
	)
	(zone
		(layers "In1.Cu" "In2.Cu")
		(hatch none 0.5)
		(connect_pads
			(clearance 0)
		)
		(min_thickness 0.25)
		(keepout
			(tracks not_allowed)
			(vias allowed)
			(pads allowed)
			(copperpour not_allowed)
			(footprints allowed)
		)
		(placement
			(enabled no)
			(sheetname "")
		)
		(fill yes
			(thermal_gap 0.5)
			(thermal_bridge_width 0.5)
			(island_removal_mode 0)
		)
		(polygon
			(pts
				(arc
					(start 11.490198 -233.22153)
					(mid 11.505077 -233.257451)
					(end 11.540998 -233.27233)
				)
				(arc
					(start 12.940538 -233.27233)
					(mid 12.976459 -233.257451)
					(end 12.991338 -233.22153)
				)
				(arc
					(start 12.991338 -232.81259)
					(mid 12.976459 -232.776669)
					(end 12.940538 -232.76179)
				)
				(arc
					(start 11.540998 -232.76179)
					(mid 11.505077 -232.776669)
					(end 11.490198 -232.81259)
				)
			)
		)
	)
	(zone
		(layers "In1.Cu" "In2.Cu")
		(hatch none 0.5)
		(connect_pads
			(clearance 0)
		)
		(min_thickness 0.25)
		(keepout
			(tracks not_allowed)
			(vias allowed)
			(pads allowed)
			(copperpour not_allowed)
			(footprints allowed)
		)
		(placement
			(enabled no)
			(sheetname "")
		)
		(fill yes
			(thermal_gap 0.5)
			(thermal_bridge_width 0.5)
			(island_removal_mode 0)
		)
		(polygon
			(pts
				(arc
					(start 312.236866 -246.821452)
					(mid 312.251745 -246.857373)
					(end 312.287666 -246.872252)
				)
				(arc
					(start 313.687206 -246.872252)
					(mid 313.723127 -246.857373)
					(end 313.738006 -246.821452)
				)
				(arc
					(start 313.738006 -246.412512)
					(mid 313.723127 -246.376591)
					(end 313.687206 -246.361712)
				)
				(arc
					(start 312.287666 -246.361712)
					(mid 312.251745 -246.376591)
					(end 312.236866 -246.412512)
				)
			)
		)
	)
	(zone
		(layers "In1.Cu" "In2.Cu")
		(hatch none 0.5)
		(connect_pads
			(clearance 0)
		)
		(min_thickness 0.25)
		(keepout
			(tracks not_allowed)
			(vias allowed)
			(pads allowed)
			(copperpour not_allowed)
			(footprints allowed)
		)
		(placement
			(enabled no)
			(sheetname "")
		)
		(fill yes
			(thermal_gap 0.5)
			(thermal_bridge_width 0.5)
			(island_removal_mode 0)
		)
		(polygon
			(pts
				(arc
					(start 30.02153 -282.521406)
					(mid 30.036409 -282.557327)
					(end 30.07233 -282.572206)
				)
				(arc
					(start 31.47187 -282.572206)
					(mid 31.507791 -282.557327)
					(end 31.52267 -282.521406)
				)
				(arc
					(start 31.52267 -282.112466)
					(mid 31.507791 -282.076545)
					(end 31.47187 -282.061666)
				)
				(arc
					(start 30.07233 -282.061666)
					(mid 30.036409 -282.076545)
					(end 30.02153 -282.112466)
				)
			)
		)
	)
	(zone
		(layers "In1.Cu" "In2.Cu")
		(hatch none 0.5)
		(connect_pads
			(clearance 0)
		)
		(min_thickness 0.25)
		(keepout
			(tracks not_allowed)
			(vias allowed)
			(pads allowed)
			(copperpour not_allowed)
			(footprints allowed)
		)
		(placement
			(enabled no)
			(sheetname "")
		)
		(fill yes
			(thermal_gap 0.5)
			(thermal_bridge_width 0.5)
			(island_removal_mode 0)
		)
		(polygon
			(pts
				(arc
					(start 26.577798 -211.121498)
					(mid 26.592677 -211.157419)
					(end 26.628598 -211.172298)
				)
				(arc
					(start 28.028138 -211.172298)
					(mid 28.064059 -211.157419)
					(end 28.078938 -211.121498)
				)
				(arc
					(start 28.078938 -210.712558)
					(mid 28.064059 -210.676637)
					(end 28.028138 -210.661758)
				)
				(arc
					(start 26.628598 -210.661758)
					(mid 26.592677 -210.676637)
					(end 26.577798 -210.712558)
				)
			)
		)
	)
	(zone
		(layers "In1.Cu" "In2.Cu")
		(hatch none 0.5)
		(connect_pads
			(clearance 0)
		)
		(min_thickness 0.25)
		(keepout
			(tracks not_allowed)
			(vias allowed)
			(pads allowed)
			(copperpour not_allowed)
			(footprints allowed)
		)
		(placement
			(enabled no)
			(sheetname "")
		)
		(fill yes
			(thermal_gap 0.5)
			(thermal_bridge_width 0.5)
			(island_removal_mode 0)
		)
		(polygon
			(pts
				(arc
					(start 266.974066 -218.77147)
					(mid 266.988945 -218.807391)
					(end 267.024866 -218.82227)
				)
				(arc
					(start 268.424406 -218.82227)
					(mid 268.460327 -218.807391)
					(end 268.475206 -218.77147)
				)
				(arc
					(start 268.475206 -218.36253)
					(mid 268.460327 -218.326609)
					(end 268.424406 -218.31173)
				)
				(arc
					(start 267.024866 -218.31173)
					(mid 266.988945 -218.326609)
					(end 266.974066 -218.36253)
				)
			)
		)
	)
	(zone
		(layers "In1.Cu" "In2.Cu")
		(hatch none 0.5)
		(connect_pads
			(clearance 0)
		)
		(min_thickness 0.25)
		(keepout
			(tracks not_allowed)
			(vias allowed)
			(pads allowed)
			(copperpour not_allowed)
			(footprints allowed)
		)
		(placement
			(enabled no)
			(sheetname "")
		)
		(fill yes
			(thermal_gap 0.5)
			(thermal_bridge_width 0.5)
			(island_removal_mode 0)
		)
		(polygon
			(pts
				(arc
					(start 60.19673 -243.421408)
					(mid 60.211609 -243.457329)
					(end 60.24753 -243.472208)
				)
				(arc
					(start 61.64707 -243.472208)
					(mid 61.682991 -243.457329)
					(end 61.69787 -243.421408)
				)
				(arc
					(start 61.69787 -243.012468)
					(mid 61.682991 -242.976547)
					(end 61.64707 -242.961668)
				)
				(arc
					(start 60.24753 -242.961668)
					(mid 60.211609 -242.976547)
					(end 60.19673 -243.012468)
				)
			)
		)
	)
	(zone
		(layers "In1.Cu" "In2.Cu")
		(hatch none 0.5)
		(connect_pads
			(clearance 0)
		)
		(min_thickness 0.25)
		(keepout
			(tracks not_allowed)
			(vias allowed)
			(pads allowed)
			(copperpour not_allowed)
			(footprints allowed)
		)
		(placement
			(enabled no)
			(sheetname "")
		)
		(fill yes
			(thermal_gap 0.5)
			(thermal_bridge_width 0.5)
			(island_removal_mode 0)
		)
		(polygon
			(pts
				(arc
					(start 158.06293 -218.77147)
					(mid 158.077809 -218.807391)
					(end 158.11373 -218.82227)
				)
				(arc
					(start 159.51327 -218.82227)
					(mid 159.549191 -218.807391)
					(end 159.56407 -218.77147)
				)
				(arc
					(start 159.56407 -218.36253)
					(mid 159.549191 -218.326609)
					(end 159.51327 -218.31173)
				)
				(arc
					(start 158.11373 -218.31173)
					(mid 158.077809 -218.326609)
					(end 158.06293 -218.36253)
				)
			)
		)
	)
	(zone
		(layers "In1.Cu" "In2.Cu")
		(hatch none 0.5)
		(connect_pads
			(clearance 0)
		)
		(min_thickness 0.25)
		(keepout
			(tracks not_allowed)
			(vias allowed)
			(pads allowed)
			(copperpour not_allowed)
			(footprints allowed)
		)
		(placement
			(enabled no)
			(sheetname "")
		)
		(fill yes
			(thermal_gap 0.5)
			(thermal_bridge_width 0.5)
			(island_removal_mode 0)
		)
		(polygon
			(pts
				(arc
					(start 443.721998 -305.471322)
					(mid 443.736877 -305.507243)
					(end 443.772798 -305.522122)
				)
				(arc
					(start 445.172338 -305.522122)
					(mid 445.208259 -305.507243)
					(end 445.223138 -305.471322)
				)
				(arc
					(start 445.223138 -305.062382)
					(mid 445.208259 -305.026461)
					(end 445.172338 -305.011582)
				)
				(arc
					(start 443.772798 -305.011582)
					(mid 443.736877 -305.026461)
					(end 443.721998 -305.062382)
				)
			)
		)
	)
	(zone
		(layers "In1.Cu" "In2.Cu")
		(hatch none 0.5)
		(connect_pads
			(clearance 0)
		)
		(min_thickness 0.25)
		(keepout
			(tracks not_allowed)
			(vias allowed)
			(pads allowed)
			(copperpour not_allowed)
			(footprints allowed)
		)
		(placement
			(enabled no)
			(sheetname "")
		)
		(fill yes
			(thermal_gap 0.5)
			(thermal_bridge_width 0.5)
			(island_removal_mode 0)
		)
		(polygon
			(pts
				(arc
					(start 443.721998 -275.721318)
					(mid 443.736877 -275.757239)
					(end 443.772798 -275.772118)
				)
				(arc
					(start 445.172338 -275.772118)
					(mid 445.208259 -275.757239)
					(end 445.223138 -275.721318)
				)
				(arc
					(start 445.223138 -275.312378)
					(mid 445.208259 -275.276457)
					(end 445.172338 -275.261578)
				)
				(arc
					(start 443.772798 -275.261578)
					(mid 443.736877 -275.276457)
					(end 443.721998 -275.312378)
				)
			)
		)
	)
	(zone
		(layers "In1.Cu" "In2.Cu")
		(hatch none 0.5)
		(connect_pads
			(clearance 0)
		)
		(min_thickness 0.25)
		(keepout
			(tracks not_allowed)
			(vias allowed)
			(pads allowed)
			(copperpour not_allowed)
			(footprints allowed)
		)
		(placement
			(enabled no)
			(sheetname "")
		)
		(fill yes
			(thermal_gap 0.5)
			(thermal_bridge_width 0.5)
			(island_removal_mode 0)
		)
		(polygon
			(pts
				(arc
					(start 173.15053 -277.42134)
					(mid 173.165409 -277.457261)
					(end 173.20133 -277.47214)
				)
				(arc
					(start 174.60087 -277.47214)
					(mid 174.636791 -277.457261)
					(end 174.65167 -277.42134)
				)
				(arc
					(start 174.65167 -277.0124)
					(mid 174.636791 -276.976479)
					(end 174.60087 -276.9616)
				)
				(arc
					(start 173.20133 -276.9616)
					(mid 173.165409 -276.976479)
					(end 173.15053 -277.0124)
				)
			)
		)
	)
	(zone
		(layers "In1.Cu" "In2.Cu")
		(hatch none 0.5)
		(connect_pads
			(clearance 0)
		)
		(min_thickness 0.25)
		(keepout
			(tracks not_allowed)
			(vias allowed)
			(pads allowed)
			(copperpour not_allowed)
			(footprints allowed)
		)
		(placement
			(enabled no)
			(sheetname "")
		)
		(fill yes
			(thermal_gap 0.5)
			(thermal_bridge_width 0.5)
			(island_removal_mode 0)
		)
		(polygon
			(pts
				(arc
					(start 45.10913 -293.571422)
					(mid 45.124009 -293.607343)
					(end 45.15993 -293.622222)
				)
				(arc
					(start 46.55947 -293.622222)
					(mid 46.595391 -293.607343)
					(end 46.61027 -293.571422)
				)
				(arc
					(start 46.61027 -293.162482)
					(mid 46.595391 -293.126561)
					(end 46.55947 -293.111682)
				)
				(arc
					(start 45.15993 -293.111682)
					(mid 45.124009 -293.126561)
					(end 45.10913 -293.162482)
				)
			)
		)
	)
	(zone
		(layers "In1.Cu" "In2.Cu")
		(hatch none 0.5)
		(connect_pads
			(clearance 0)
		)
		(min_thickness 0.25)
		(keepout
			(tracks not_allowed)
			(vias allowed)
			(pads allowed)
			(copperpour not_allowed)
			(footprints allowed)
		)
		(placement
			(enabled no)
			(sheetname "")
		)
		(fill yes
			(thermal_gap 0.5)
			(thermal_bridge_width 0.5)
			(island_removal_mode 0)
		)
		(polygon
			(pts
				(arc
					(start 293.049198 -313.121294)
					(mid 293.064077 -313.157215)
					(end 293.099998 -313.172094)
				)
				(arc
					(start 294.499538 -313.172094)
					(mid 294.535459 -313.157215)
					(end 294.550338 -313.121294)
				)
				(arc
					(start 294.550338 -312.712354)
					(mid 294.535459 -312.676433)
					(end 294.499538 -312.661554)
				)
				(arc
					(start 293.099998 -312.661554)
					(mid 293.064077 -312.676433)
					(end 293.049198 -312.712354)
				)
			)
		)
	)
	(zone
		(layers "In1.Cu" "In2.Cu")
		(hatch none 0.5)
		(connect_pads
			(clearance 0)
		)
		(min_thickness 0.25)
		(keepout
			(tracks not_allowed)
			(vias allowed)
			(pads allowed)
			(copperpour not_allowed)
			(footprints allowed)
		)
		(placement
			(enabled no)
			(sheetname "")
		)
		(fill yes
			(thermal_gap 0.5)
			(thermal_bridge_width 0.5)
			(island_removal_mode 0)
		)
		(polygon
			(pts
				(arc
					(start 14.93393 -218.77147)
					(mid 14.948809 -218.807391)
					(end 14.98473 -218.82227)
				)
				(arc
					(start 16.38427 -218.82227)
					(mid 16.420191 -218.807391)
					(end 16.43507 -218.77147)
				)
				(arc
					(start 16.43507 -218.36253)
					(mid 16.420191 -218.326609)
					(end 16.38427 -218.31173)
				)
				(arc
					(start 14.98473 -218.31173)
					(mid 14.948809 -218.326609)
					(end 14.93393 -218.36253)
				)
			)
		)
	)
	(zone
		(layers "In1.Cu" "In2.Cu")
		(hatch none 0.5)
		(connect_pads
			(clearance 0)
		)
		(min_thickness 0.25)
		(keepout
			(tracks not_allowed)
			(vias allowed)
			(pads allowed)
			(copperpour not_allowed)
			(footprints allowed)
		)
		(placement
			(enabled no)
			(sheetname "")
		)
		(fill yes
			(thermal_gap 0.5)
			(thermal_bridge_width 0.5)
			(island_removal_mode 0)
		)
		(polygon
			(pts
				(arc
					(start 192.338198 -298.671488)
					(mid 192.353077 -298.707409)
					(end 192.388998 -298.722288)
				)
				(arc
					(start 193.788538 -298.722288)
					(mid 193.824459 -298.707409)
					(end 193.839338 -298.671488)
				)
				(arc
					(start 193.839338 -298.262548)
					(mid 193.824459 -298.226627)
					(end 193.788538 -298.211748)
				)
				(arc
					(start 192.388998 -298.211748)
					(mid 192.353077 -298.226627)
					(end 192.338198 -298.262548)
				)
			)
		)
	)
	(zone
		(layers "In1.Cu" "In2.Cu")
		(hatch none 0.5)
		(connect_pads
			(clearance 0)
		)
		(min_thickness 0.25)
		(keepout
			(tracks not_allowed)
			(vias allowed)
			(pads allowed)
			(copperpour not_allowed)
			(footprints allowed)
		)
		(placement
			(enabled no)
			(sheetname "")
		)
		(fill yes
			(thermal_gap 0.5)
			(thermal_bridge_width 0.5)
			(island_removal_mode 0)
		)
		(polygon
			(pts
				(arc
					(start 26.577798 -313.971432)
					(mid 26.592677 -314.007353)
					(end 26.628598 -314.022232)
				)
				(arc
					(start 28.028138 -314.022232)
					(mid 28.064059 -314.007353)
					(end 28.078938 -313.971432)
				)
				(arc
					(start 28.078938 -313.562492)
					(mid 28.064059 -313.526571)
					(end 28.028138 -313.511692)
				)
				(arc
					(start 26.628598 -313.511692)
					(mid 26.592677 -313.526571)
					(end 26.577798 -313.562492)
				)
			)
		)
	)
	(zone
		(layers "In1.Cu" "In2.Cu")
		(hatch none 0.5)
		(connect_pads
			(clearance 0)
		)
		(min_thickness 0.25)
		(keepout
			(tracks not_allowed)
			(vias allowed)
			(pads allowed)
			(copperpour not_allowed)
			(footprints allowed)
		)
		(placement
			(enabled no)
			(sheetname "")
		)
		(fill yes
			(thermal_gap 0.5)
			(thermal_bridge_width 0.5)
			(island_removal_mode 0)
		)
		(polygon
			(pts
				(arc
					(start 277.961598 -284.221428)
					(mid 277.976477 -284.257349)
					(end 278.012398 -284.272228)
				)
				(arc
					(start 279.411938 -284.272228)
					(mid 279.447859 -284.257349)
					(end 279.462738 -284.221428)
				)
				(arc
					(start 279.462738 -283.812488)
					(mid 279.447859 -283.776567)
					(end 279.411938 -283.761688)
				)
				(arc
					(start 278.012398 -283.761688)
					(mid 277.976477 -283.776567)
					(end 277.961598 -283.812488)
				)
			)
		)
	)
	(zone
		(layers "In1.Cu" "In2.Cu")
		(hatch none 0.5)
		(connect_pads
			(clearance 0)
		)
		(min_thickness 0.25)
		(keepout
			(tracks not_allowed)
			(vias allowed)
			(pads allowed)
			(copperpour not_allowed)
			(footprints allowed)
		)
		(placement
			(enabled no)
			(sheetname "")
		)
		(fill yes
			(thermal_gap 0.5)
			(thermal_bridge_width 0.5)
			(island_removal_mode 0)
		)
		(polygon
			(pts
				(arc
					(start 14.93393 -310.571388)
					(mid 14.948809 -310.607309)
					(end 14.98473 -310.622188)
				)
				(arc
					(start 16.38427 -310.622188)
					(mid 16.420191 -310.607309)
					(end 16.43507 -310.571388)
				)
				(arc
					(start 16.43507 -310.162448)
					(mid 16.420191 -310.126527)
					(end 16.38427 -310.111648)
				)
				(arc
					(start 14.98473 -310.111648)
					(mid 14.948809 -310.126527)
					(end 14.93393 -310.162448)
				)
			)
		)
	)
	(zone
		(layers "In1.Cu" "In2.Cu")
		(hatch none 0.5)
		(connect_pads
			(clearance 0)
		)
		(min_thickness 0.25)
		(keepout
			(tracks not_allowed)
			(vias allowed)
			(pads allowed)
			(copperpour not_allowed)
			(footprints allowed)
		)
		(placement
			(enabled no)
			(sheetname "")
		)
		(fill yes
			(thermal_gap 0.5)
			(thermal_bridge_width 0.5)
			(island_removal_mode 0)
		)
		(polygon
			(pts
				(arc
					(start 270.417798 -232.371392)
					(mid 270.432677 -232.407313)
					(end 270.468598 -232.422192)
				)
				(arc
					(start 271.868138 -232.422192)
					(mid 271.904059 -232.407313)
					(end 271.918938 -232.371392)
				)
				(arc
					(start 271.918938 -231.962452)
					(mid 271.904059 -231.926531)
					(end 271.868138 -231.911652)
				)
				(arc
					(start 270.468598 -231.911652)
					(mid 270.432677 -231.926531)
					(end 270.417798 -231.962452)
				)
			)
		)
	)
	(zone
		(layers "In1.Cu" "In2.Cu")
		(hatch none 0.5)
		(connect_pads
			(clearance 0)
		)
		(min_thickness 0.25)
		(keepout
			(tracks not_allowed)
			(vias allowed)
			(pads allowed)
			(copperpour not_allowed)
			(footprints allowed)
		)
		(placement
			(enabled no)
			(sheetname "")
		)
		(fill yes
			(thermal_gap 0.5)
			(thermal_bridge_width 0.5)
			(island_removal_mode 0)
		)
		(polygon
			(pts
				(arc
					(start 41.665398 -206.871316)
					(mid 41.680277 -206.907237)
					(end 41.716198 -206.922116)
				)
				(arc
					(start 43.115738 -206.922116)
					(mid 43.151659 -206.907237)
					(end 43.166538 -206.871316)
				)
				(arc
					(start 43.166538 -206.462376)
					(mid 43.151659 -206.426455)
					(end 43.115738 -206.411576)
				)
				(arc
					(start 41.716198 -206.411576)
					(mid 41.680277 -206.426455)
					(end 41.665398 -206.462376)
				)
			)
		)
	)
	(zone
		(layers "In1.Cu" "In2.Cu")
		(hatch none 0.5)
		(connect_pads
			(clearance 0)
		)
		(min_thickness 0.25)
		(keepout
			(tracks not_allowed)
			(vias allowed)
			(pads allowed)
			(copperpour not_allowed)
			(footprints allowed)
		)
		(placement
			(enabled no)
			(sheetname "")
		)
		(fill yes
			(thermal_gap 0.5)
			(thermal_bridge_width 0.5)
			(island_removal_mode 0)
		)
		(polygon
			(pts
				(arc
					(start 26.577798 -200.071482)
					(mid 26.592677 -200.107403)
					(end 26.628598 -200.122282)
				)
				(arc
					(start 28.028138 -200.122282)
					(mid 28.064059 -200.107403)
					(end 28.078938 -200.071482)
				)
				(arc
					(start 28.078938 -199.662542)
					(mid 28.064059 -199.626621)
					(end 28.028138 -199.611742)
				)
				(arc
					(start 26.628598 -199.611742)
					(mid 26.592677 -199.626621)
					(end 26.577798 -199.662542)
				)
			)
		)
	)
	(zone
		(layers "In1.Cu" "In2.Cu")
		(hatch none 0.5)
		(connect_pads
			(clearance 0)
		)
		(min_thickness 0.25)
		(keepout
			(tracks not_allowed)
			(vias allowed)
			(pads allowed)
			(copperpour not_allowed)
			(footprints allowed)
		)
		(placement
			(enabled no)
			(sheetname "")
		)
		(fill yes
			(thermal_gap 0.5)
			(thermal_bridge_width 0.5)
			(island_removal_mode 0)
		)
		(polygon
			(pts
				(arc
					(start 195.78193 -247.671336)
					(mid 195.796809 -247.707257)
					(end 195.83273 -247.722136)
				)
				(arc
					(start 197.23227 -247.722136)
					(mid 197.268191 -247.707257)
					(end 197.28307 -247.671336)
				)
				(arc
					(start 197.28307 -247.262396)
					(mid 197.268191 -247.226475)
					(end 197.23227 -247.211596)
				)
				(arc
					(start 195.83273 -247.211596)
					(mid 195.796809 -247.226475)
					(end 195.78193 -247.262396)
				)
			)
		)
	)
	(zone
		(layers "In1.Cu" "In2.Cu")
		(hatch none 0.5)
		(connect_pads
			(clearance 0)
		)
		(min_thickness 0.25)
		(keepout
			(tracks not_allowed)
			(vias allowed)
			(pads allowed)
			(copperpour not_allowed)
			(footprints allowed)
		)
		(placement
			(enabled no)
			(sheetname "")
		)
		(fill yes
			(thermal_gap 0.5)
			(thermal_bridge_width 0.5)
			(island_removal_mode 0)
		)
		(polygon
			(pts
				(arc
					(start 14.93393 -261.271512)
					(mid 14.948809 -261.307433)
					(end 14.98473 -261.322312)
				)
				(arc
					(start 16.38427 -261.322312)
					(mid 16.420191 -261.307433)
					(end 16.43507 -261.271512)
				)
				(arc
					(start 16.43507 -260.862572)
					(mid 16.420191 -260.826651)
					(end 16.38427 -260.811772)
				)
				(arc
					(start 14.98473 -260.811772)
					(mid 14.948809 -260.826651)
					(end 14.93393 -260.862572)
				)
			)
		)
	)
	(zone
		(layers "In1.Cu" "In2.Cu")
		(hatch none 0.5)
		(connect_pads
			(clearance 0)
		)
		(min_thickness 0.25)
		(keepout
			(tracks not_allowed)
			(vias allowed)
			(pads allowed)
			(copperpour not_allowed)
			(footprints allowed)
		)
		(placement
			(enabled no)
			(sheetname "")
		)
		(fill yes
			(thermal_gap 0.5)
			(thermal_bridge_width 0.5)
			(island_removal_mode 0)
		)
		(polygon
			(pts
				(arc
					(start 406.002998 -200.921366)
					(mid 406.017877 -200.957287)
					(end 406.053798 -200.972166)
				)
				(arc
					(start 407.453338 -200.972166)
					(mid 407.489259 -200.957287)
					(end 407.504138 -200.921366)
				)
				(arc
					(start 407.504138 -200.512426)
					(mid 407.489259 -200.476505)
					(end 407.453338 -200.461626)
				)
				(arc
					(start 406.053798 -200.461626)
					(mid 406.017877 -200.476505)
					(end 406.002998 -200.512426)
				)
			)
		)
	)
	(zone
		(layers "In1.Cu" "In2.Cu")
		(hatch none 0.5)
		(connect_pads
			(clearance 0)
		)
		(min_thickness 0.25)
		(keepout
			(tracks not_allowed)
			(vias allowed)
			(pads allowed)
			(copperpour not_allowed)
			(footprints allowed)
		)
		(placement
			(enabled no)
			(sheetname "")
		)
		(fill yes
			(thermal_gap 0.5)
			(thermal_bridge_width 0.5)
			(island_removal_mode 0)
		)
		(polygon
			(pts
				(arc
					(start 169.706798 -272.321528)
					(mid 169.721677 -272.357449)
					(end 169.757598 -272.372328)
				)
				(arc
					(start 171.157138 -272.372328)
					(mid 171.193059 -272.357449)
					(end 171.207938 -272.321528)
				)
				(arc
					(start 171.207938 -271.912588)
					(mid 171.193059 -271.876667)
					(end 171.157138 -271.861788)
				)
				(arc
					(start 169.757598 -271.861788)
					(mid 169.721677 -271.876667)
					(end 169.706798 -271.912588)
				)
			)
		)
	)
	(zone
		(layers "In1.Cu" "In2.Cu")
		(hatch none 0.5)
		(connect_pads
			(clearance 0)
		)
		(min_thickness 0.25)
		(keepout
			(tracks not_allowed)
			(vias allowed)
			(pads allowed)
			(copperpour not_allowed)
			(footprints allowed)
		)
		(placement
			(enabled no)
			(sheetname "")
		)
		(fill yes
			(thermal_gap 0.5)
			(thermal_bridge_width 0.5)
			(island_removal_mode 0)
		)
		(polygon
			(pts
				(arc
					(start 458.809598 -282.521406)
					(mid 458.824477 -282.557327)
					(end 458.860398 -282.572206)
				)
				(arc
					(start 460.259938 -282.572206)
					(mid 460.295859 -282.557327)
					(end 460.310738 -282.521406)
				)
				(arc
					(start 460.310738 -282.112466)
					(mid 460.295859 -282.076545)
					(end 460.259938 -282.061666)
				)
				(arc
					(start 458.860398 -282.061666)
					(mid 458.824477 -282.076545)
					(end 458.809598 -282.112466)
				)
			)
		)
	)
	(zone
		(layers "In1.Cu" "In2.Cu")
		(hatch none 0.5)
		(connect_pads
			(clearance 0)
		)
		(min_thickness 0.25)
		(keepout
			(tracks not_allowed)
			(vias allowed)
			(pads allowed)
			(copperpour not_allowed)
			(footprints allowed)
		)
		(placement
			(enabled no)
			(sheetname "")
		)
		(fill yes
			(thermal_gap 0.5)
			(thermal_bridge_width 0.5)
			(island_removal_mode 0)
		)
		(polygon
			(pts
				(arc
					(start 266.974066 -306.32146)
					(mid 266.988945 -306.357381)
					(end 267.024866 -306.37226)
				)
				(arc
					(start 268.424406 -306.37226)
					(mid 268.460327 -306.357381)
					(end 268.475206 -306.32146)
				)
				(arc
					(start 268.475206 -305.91252)
					(mid 268.460327 -305.876599)
					(end 268.424406 -305.86172)
				)
				(arc
					(start 267.024866 -305.86172)
					(mid 266.988945 -305.876599)
					(end 266.974066 -305.91252)
				)
			)
		)
	)
	(zone
		(layers "In1.Cu" "In2.Cu")
		(hatch none 0.5)
		(connect_pads
			(clearance 0)
		)
		(min_thickness 0.25)
		(keepout
			(tracks not_allowed)
			(vias allowed)
			(pads allowed)
			(copperpour not_allowed)
			(footprints allowed)
		)
		(placement
			(enabled no)
			(sheetname "")
		)
		(fill yes
			(thermal_gap 0.5)
			(thermal_bridge_width 0.5)
			(island_removal_mode 0)
		)
		(polygon
			(pts
				(arc
					(start 41.665398 -214.521542)
					(mid 41.680277 -214.557463)
					(end 41.716198 -214.572342)
				)
				(arc
					(start 43.115738 -214.572342)
					(mid 43.151659 -214.557463)
					(end 43.166538 -214.521542)
				)
				(arc
					(start 43.166538 -214.112602)
					(mid 43.151659 -214.076681)
					(end 43.115738 -214.061802)
				)
				(arc
					(start 41.716198 -214.061802)
					(mid 41.680277 -214.076681)
					(end 41.665398 -214.112602)
				)
			)
		)
	)
	(zone
		(layers "In1.Cu" "In2.Cu")
		(hatch none 0.5)
		(connect_pads
			(clearance 0)
		)
		(min_thickness 0.25)
		(keepout
			(tracks not_allowed)
			(vias allowed)
			(pads allowed)
			(copperpour not_allowed)
			(footprints allowed)
		)
		(placement
			(enabled no)
			(sheetname "")
		)
		(fill yes
			(thermal_gap 0.5)
			(thermal_bridge_width 0.5)
			(island_removal_mode 0)
		)
		(polygon
			(pts
				(arc
					(start 207.425798 -250.221496)
					(mid 207.440677 -250.257417)
					(end 207.476598 -250.272296)
				)
				(arc
					(start 208.876138 -250.272296)
					(mid 208.912059 -250.257417)
					(end 208.926938 -250.221496)
				)
				(arc
					(start 208.926938 -249.812556)
					(mid 208.912059 -249.776635)
					(end 208.876138 -249.761756)
				)
				(arc
					(start 207.476598 -249.761756)
					(mid 207.440677 -249.776635)
					(end 207.425798 -249.812556)
				)
			)
		)
	)
	(zone
		(layers "In1.Cu" "In2.Cu")
		(hatch none 0.5)
		(connect_pads
			(clearance 0)
		)
		(min_thickness 0.25)
		(keepout
			(tracks not_allowed)
			(vias allowed)
			(pads allowed)
			(copperpour not_allowed)
			(footprints allowed)
		)
		(placement
			(enabled no)
			(sheetname "")
		)
		(fill yes
			(thermal_gap 0.5)
			(thermal_bridge_width 0.5)
			(island_removal_mode 0)
		)
		(polygon
			(pts
				(arc
					(start 410.103066 -218.77147)
					(mid 410.117945 -218.807391)
					(end 410.153866 -218.82227)
				)
				(arc
					(start 411.553406 -218.82227)
					(mid 411.589327 -218.807391)
					(end 411.604206 -218.77147)
				)
				(arc
					(start 411.604206 -218.36253)
					(mid 411.589327 -218.326609)
					(end 411.553406 -218.31173)
				)
				(arc
					(start 410.153866 -218.31173)
					(mid 410.117945 -218.326609)
					(end 410.103066 -218.36253)
				)
			)
		)
	)
	(zone
		(layers "In1.Cu" "In2.Cu")
		(hatch none 0.5)
		(connect_pads
			(clearance 0)
		)
		(min_thickness 0.25)
		(keepout
			(tracks not_allowed)
			(vias allowed)
			(pads allowed)
			(copperpour not_allowed)
			(footprints allowed)
		)
		(placement
			(enabled no)
			(sheetname "")
		)
		(fill yes
			(thermal_gap 0.5)
			(thermal_bridge_width 0.5)
			(island_removal_mode 0)
		)
		(polygon
			(pts
				(arc
					(start 293.049198 -252.771402)
					(mid 293.064077 -252.807323)
					(end 293.099998 -252.822202)
				)
				(arc
					(start 294.499538 -252.822202)
					(mid 294.535459 -252.807323)
					(end 294.550338 -252.771402)
				)
				(arc
					(start 294.550338 -252.362462)
					(mid 294.535459 -252.326541)
					(end 294.499538 -252.311662)
				)
				(arc
					(start 293.099998 -252.311662)
					(mid 293.064077 -252.326541)
					(end 293.049198 -252.362462)
				)
			)
		)
	)
	(zone
		(layers "In1.Cu" "In2.Cu")
		(hatch none 0.5)
		(connect_pads
			(clearance 0)
		)
		(min_thickness 0.25)
		(keepout
			(tracks not_allowed)
			(vias allowed)
			(pads allowed)
			(copperpour not_allowed)
			(footprints allowed)
		)
		(placement
			(enabled no)
			(sheetname "")
		)
		(fill yes
			(thermal_gap 0.5)
			(thermal_bridge_width 0.5)
			(island_removal_mode 0)
		)
		(polygon
			(pts
				(arc
					(start 312.236866 -287.621472)
					(mid 312.251745 -287.657393)
					(end 312.287666 -287.672272)
				)
				(arc
					(start 313.687206 -287.672272)
					(mid 313.723127 -287.657393)
					(end 313.738006 -287.621472)
				)
				(arc
					(start 313.738006 -287.212532)
					(mid 313.723127 -287.176611)
					(end 313.687206 -287.161732)
				)
				(arc
					(start 312.287666 -287.161732)
					(mid 312.251745 -287.176611)
					(end 312.236866 -287.212532)
				)
			)
		)
	)
	(zone
		(layers "In1.Cu" "In2.Cu")
		(hatch none 0.5)
		(connect_pads
			(clearance 0)
		)
		(min_thickness 0.25)
		(keepout
			(tracks not_allowed)
			(vias allowed)
			(pads allowed)
			(copperpour not_allowed)
			(footprints allowed)
		)
		(placement
			(enabled no)
			(sheetname "")
		)
		(fill yes
			(thermal_gap 0.5)
			(thermal_bridge_width 0.5)
			(island_removal_mode 0)
		)
		(polygon
			(pts
				(arc
					(start 19.033998 -309.721504)
					(mid 19.048877 -309.757425)
					(end 19.084798 -309.772304)
				)
				(arc
					(start 20.484338 -309.772304)
					(mid 20.520259 -309.757425)
					(end 20.535138 -309.721504)
				)
				(arc
					(start 20.535138 -309.312564)
					(mid 20.520259 -309.276643)
					(end 20.484338 -309.261764)
				)
				(arc
					(start 19.084798 -309.261764)
					(mid 19.048877 -309.276643)
					(end 19.033998 -309.312564)
				)
			)
		)
	)
	(zone
		(layers "In1.Cu" "In2.Cu")
		(hatch none 0.5)
		(connect_pads
			(clearance 0)
		)
		(min_thickness 0.25)
		(keepout
			(tracks not_allowed)
			(vias allowed)
			(pads allowed)
			(copperpour not_allowed)
			(footprints allowed)
		)
		(placement
			(enabled no)
			(sheetname "")
		)
		(fill yes
			(thermal_gap 0.5)
			(thermal_bridge_width 0.5)
			(island_removal_mode 0)
		)
		(polygon
			(pts
				(arc
					(start 7.39013 -202.621388)
					(mid 7.405009 -202.657309)
					(end 7.44093 -202.672188)
				)
				(arc
					(start 8.84047 -202.672188)
					(mid 8.876391 -202.657309)
					(end 8.89127 -202.621388)
				)
				(arc
					(start 8.89127 -202.212448)
					(mid 8.876391 -202.176527)
					(end 8.84047 -202.161648)
				)
				(arc
					(start 7.44093 -202.161648)
					(mid 7.405009 -202.176527)
					(end 7.39013 -202.212448)
				)
			)
		)
	)
	(zone
		(layers "In1.Cu" "In2.Cu")
		(hatch none 0.5)
		(connect_pads
			(clearance 0)
		)
		(min_thickness 0.25)
		(keepout
			(tracks not_allowed)
			(vias allowed)
			(pads allowed)
			(copperpour not_allowed)
			(footprints allowed)
		)
		(placement
			(enabled no)
			(sheetname "")
		)
		(fill yes
			(thermal_gap 0.5)
			(thermal_bridge_width 0.5)
			(island_removal_mode 0)
		)
		(polygon
			(pts
				(arc
					(start 443.721998 -296.121328)
					(mid 443.736877 -296.157249)
					(end 443.772798 -296.172128)
				)
				(arc
					(start 445.172338 -296.172128)
					(mid 445.208259 -296.157249)
					(end 445.223138 -296.121328)
				)
				(arc
					(start 445.223138 -295.712388)
					(mid 445.208259 -295.676467)
					(end 445.172338 -295.661588)
				)
				(arc
					(start 443.772798 -295.661588)
					(mid 443.736877 -295.676467)
					(end 443.721998 -295.712388)
				)
			)
		)
	)
	(zone
		(layers "In1.Cu" "In2.Cu")
		(hatch none 0.5)
		(connect_pads
			(clearance 0)
		)
		(min_thickness 0.25)
		(keepout
			(tracks not_allowed)
			(vias allowed)
			(pads allowed)
			(copperpour not_allowed)
			(footprints allowed)
		)
		(placement
			(enabled no)
			(sheetname "")
		)
		(fill yes
			(thermal_gap 0.5)
			(thermal_bridge_width 0.5)
			(island_removal_mode 0)
		)
		(polygon
			(pts
				(arc
					(start 26.577798 -227.271326)
					(mid 26.592677 -227.307247)
					(end 26.628598 -227.322126)
				)
				(arc
					(start 28.028138 -227.322126)
					(mid 28.064059 -227.307247)
					(end 28.078938 -227.271326)
				)
				(arc
					(start 28.078938 -226.862386)
					(mid 28.064059 -226.826465)
					(end 28.028138 -226.811586)
				)
				(arc
					(start 26.628598 -226.811586)
					(mid 26.592677 -226.826465)
					(end 26.577798 -226.862386)
				)
			)
		)
	)
	(zone
		(layers "In1.Cu" "In2.Cu")
		(hatch none 0.5)
		(connect_pads
			(clearance 0)
		)
		(min_thickness 0.25)
		(keepout
			(tracks not_allowed)
			(vias allowed)
			(pads allowed)
			(copperpour not_allowed)
			(footprints allowed)
		)
		(placement
			(enabled no)
			(sheetname "")
		)
		(fill yes
			(thermal_gap 0.5)
			(thermal_bridge_width 0.5)
			(island_removal_mode 0)
		)
		(polygon
			(pts
				(arc
					(start 192.338198 -233.22153)
					(mid 192.353077 -233.257451)
					(end 192.388998 -233.27233)
				)
				(arc
					(start 193.788538 -233.27233)
					(mid 193.824459 -233.257451)
					(end 193.839338 -233.22153)
				)
				(arc
					(start 193.839338 -232.81259)
					(mid 193.824459 -232.776669)
					(end 193.788538 -232.76179)
				)
				(arc
					(start 192.388998 -232.76179)
					(mid 192.353077 -232.776669)
					(end 192.338198 -232.81259)
				)
			)
		)
	)
	(zone
		(layers "In1.Cu" "In2.Cu")
		(hatch none 0.5)
		(connect_pads
			(clearance 0)
		)
		(min_thickness 0.25)
		(keepout
			(tracks not_allowed)
			(vias allowed)
			(pads allowed)
			(copperpour not_allowed)
			(footprints allowed)
		)
		(placement
			(enabled no)
			(sheetname "")
		)
		(fill yes
			(thermal_gap 0.5)
			(thermal_bridge_width 0.5)
			(island_removal_mode 0)
		)
		(polygon
			(pts
				(arc
					(start 274.517866 -283.371544)
					(mid 274.532745 -283.407465)
					(end 274.568666 -283.422344)
				)
				(arc
					(start 275.968206 -283.422344)
					(mid 276.004127 -283.407465)
					(end 276.019006 -283.371544)
				)
				(arc
					(start 276.019006 -282.962604)
					(mid 276.004127 -282.926683)
					(end 275.968206 -282.911804)
				)
				(arc
					(start 274.568666 -282.911804)
					(mid 274.532745 -282.926683)
					(end 274.517866 -282.962604)
				)
			)
		)
	)
	(zone
		(layers "In1.Cu" "In2.Cu")
		(hatch none 0.5)
		(connect_pads
			(clearance 0)
		)
		(min_thickness 0.25)
		(keepout
			(tracks not_allowed)
			(vias allowed)
			(pads allowed)
			(copperpour not_allowed)
			(footprints allowed)
		)
		(placement
			(enabled no)
			(sheetname "")
		)
		(fill yes
			(thermal_gap 0.5)
			(thermal_bridge_width 0.5)
			(island_removal_mode 0)
		)
		(polygon
			(pts
				(arc
					(start 184.794398 -200.071482)
					(mid 184.809277 -200.107403)
					(end 184.845198 -200.122282)
				)
				(arc
					(start 186.244738 -200.122282)
					(mid 186.280659 -200.107403)
					(end 186.295538 -200.071482)
				)
				(arc
					(start 186.295538 -199.662542)
					(mid 186.280659 -199.626621)
					(end 186.244738 -199.611742)
				)
				(arc
					(start 184.845198 -199.611742)
					(mid 184.809277 -199.626621)
					(end 184.794398 -199.662542)
				)
			)
		)
	)
	(zone
		(layers "In1.Cu" "In2.Cu")
		(hatch none 0.5)
		(connect_pads
			(clearance 0)
		)
		(min_thickness 0.25)
		(keepout
			(tracks not_allowed)
			(vias allowed)
			(pads allowed)
			(copperpour not_allowed)
			(footprints allowed)
		)
		(placement
			(enabled no)
			(sheetname "")
		)
		(fill yes
			(thermal_gap 0.5)
			(thermal_bridge_width 0.5)
			(island_removal_mode 0)
		)
		(polygon
			(pts
				(arc
					(start 60.19673 -241.721386)
					(mid 60.211609 -241.757307)
					(end 60.24753 -241.772186)
				)
				(arc
					(start 61.64707 -241.772186)
					(mid 61.682991 -241.757307)
					(end 61.69787 -241.721386)
				)
				(arc
					(start 61.69787 -241.312446)
					(mid 61.682991 -241.276525)
					(end 61.64707 -241.261646)
				)
				(arc
					(start 60.24753 -241.261646)
					(mid 60.211609 -241.276525)
					(end 60.19673 -241.312446)
				)
			)
		)
	)
	(zone
		(layers "In1.Cu" "In2.Cu")
		(hatch none 0.5)
		(connect_pads
			(clearance 0)
		)
		(min_thickness 0.25)
		(keepout
			(tracks not_allowed)
			(vias allowed)
			(pads allowed)
			(copperpour not_allowed)
			(footprints allowed)
		)
		(placement
			(enabled no)
			(sheetname "")
		)
		(fill yes
			(thermal_gap 0.5)
			(thermal_bridge_width 0.5)
			(island_removal_mode 0)
		)
		(polygon
			(pts
				(arc
					(start 440.278266 -227.271326)
					(mid 440.293145 -227.307247)
					(end 440.329066 -227.322126)
				)
				(arc
					(start 441.728606 -227.322126)
					(mid 441.764527 -227.307247)
					(end 441.779406 -227.271326)
				)
				(arc
					(start 441.779406 -226.862386)
					(mid 441.764527 -226.826465)
					(end 441.728606 -226.811586)
				)
				(arc
					(start 440.329066 -226.811586)
					(mid 440.293145 -226.826465)
					(end 440.278266 -226.862386)
				)
			)
		)
	)
	(zone
		(layers "In1.Cu" "In2.Cu")
		(hatch none 0.5)
		(connect_pads
			(clearance 0)
		)
		(min_thickness 0.25)
		(keepout
			(tracks not_allowed)
			(vias allowed)
			(pads allowed)
			(copperpour not_allowed)
			(footprints allowed)
		)
		(placement
			(enabled no)
			(sheetname "")
		)
		(fill yes
			(thermal_gap 0.5)
			(thermal_bridge_width 0.5)
			(island_removal_mode 0)
		)
		(polygon
			(pts
				(arc
					(start 52.65293 -308.871366)
					(mid 52.667809 -308.907287)
					(end 52.70373 -308.922166)
				)
				(arc
					(start 54.10327 -308.922166)
					(mid 54.139191 -308.907287)
					(end 54.15407 -308.871366)
				)
				(arc
					(start 54.15407 -308.462426)
					(mid 54.139191 -308.426505)
					(end 54.10327 -308.411626)
				)
				(arc
					(start 52.70373 -308.411626)
					(mid 52.667809 -308.426505)
					(end 52.65293 -308.462426)
				)
			)
		)
	)
	(zone
		(layers "In1.Cu" "In2.Cu")
		(hatch none 0.5)
		(connect_pads
			(clearance 0)
		)
		(min_thickness 0.25)
		(keepout
			(tracks not_allowed)
			(vias allowed)
			(pads allowed)
			(copperpour not_allowed)
			(footprints allowed)
		)
		(placement
			(enabled no)
			(sheetname "")
		)
		(fill yes
			(thermal_gap 0.5)
			(thermal_bridge_width 0.5)
			(island_removal_mode 0)
		)
		(polygon
			(pts
				(arc
					(start 199.881998 -311.421526)
					(mid 199.896877 -311.457447)
					(end 199.932798 -311.472326)
				)
				(arc
					(start 201.332338 -311.472326)
					(mid 201.368259 -311.457447)
					(end 201.383138 -311.421526)
				)
				(arc
					(start 201.383138 -311.012586)
					(mid 201.368259 -310.976665)
					(end 201.332338 -310.961786)
				)
				(arc
					(start 199.932798 -310.961786)
					(mid 199.896877 -310.976665)
					(end 199.881998 -311.012586)
				)
			)
		)
	)
	(zone
		(layers "In1.Cu" "In2.Cu")
		(hatch none 0.5)
		(connect_pads
			(clearance 0)
		)
		(min_thickness 0.25)
		(keepout
			(tracks not_allowed)
			(vias allowed)
			(pads allowed)
			(copperpour not_allowed)
			(footprints allowed)
		)
		(placement
			(enabled no)
			(sheetname "")
		)
		(fill yes
			(thermal_gap 0.5)
			(thermal_bridge_width 0.5)
			(island_removal_mode 0)
		)
		(polygon
			(pts
				(arc
					(start 64.296798 -292.721538)
					(mid 64.311677 -292.757459)
					(end 64.347598 -292.772338)
				)
				(arc
					(start 65.747138 -292.772338)
					(mid 65.783059 -292.757459)
					(end 65.797938 -292.721538)
				)
				(arc
					(start 65.797938 -292.312598)
					(mid 65.783059 -292.276677)
					(end 65.747138 -292.261798)
				)
				(arc
					(start 64.347598 -292.261798)
					(mid 64.311677 -292.276677)
					(end 64.296798 -292.312598)
				)
			)
		)
	)
	(zone
		(layers "In1.Cu" "In2.Cu")
		(hatch none 0.5)
		(connect_pads
			(clearance 0)
		)
		(min_thickness 0.25)
		(keepout
			(tracks not_allowed)
			(vias allowed)
			(pads allowed)
			(copperpour not_allowed)
			(footprints allowed)
		)
		(placement
			(enabled no)
			(sheetname "")
		)
		(fill yes
			(thermal_gap 0.5)
			(thermal_bridge_width 0.5)
			(island_removal_mode 0)
		)
		(polygon
			(pts
				(arc
					(start 195.78193 -218.77147)
					(mid 195.796809 -218.807391)
					(end 195.83273 -218.82227)
				)
				(arc
					(start 197.23227 -218.82227)
					(mid 197.268191 -218.807391)
					(end 197.28307 -218.77147)
				)
				(arc
					(start 197.28307 -218.36253)
					(mid 197.268191 -218.326609)
					(end 197.23227 -218.31173)
				)
				(arc
					(start 195.83273 -218.31173)
					(mid 195.796809 -218.326609)
					(end 195.78193 -218.36253)
				)
			)
		)
	)
	(zone
		(layers "In1.Cu" "In2.Cu")
		(hatch none 0.5)
		(connect_pads
			(clearance 0)
		)
		(min_thickness 0.25)
		(keepout
			(tracks not_allowed)
			(vias allowed)
			(pads allowed)
			(copperpour not_allowed)
			(footprints allowed)
		)
		(placement
			(enabled no)
			(sheetname "")
		)
		(fill yes
			(thermal_gap 0.5)
			(thermal_bridge_width 0.5)
			(island_removal_mode 0)
		)
		(polygon
			(pts
				(arc
					(start 188.23813 -269.771368)
					(mid 188.253009 -269.807289)
					(end 188.28893 -269.822168)
				)
				(arc
					(start 189.68847 -269.822168)
					(mid 189.724391 -269.807289)
					(end 189.73927 -269.771368)
				)
				(arc
					(start 189.73927 -269.362428)
					(mid 189.724391 -269.326507)
					(end 189.68847 -269.311628)
				)
				(arc
					(start 188.28893 -269.311628)
					(mid 188.253009 -269.326507)
					(end 188.23813 -269.362428)
				)
			)
		)
	)
	(zone
		(layers "In1.Cu" "In2.Cu")
		(hatch none 0.5)
		(connect_pads
			(clearance 0)
		)
		(min_thickness 0.25)
		(keepout
			(tracks not_allowed)
			(vias allowed)
			(pads allowed)
			(copperpour not_allowed)
			(footprints allowed)
		)
		(placement
			(enabled no)
			(sheetname "")
		)
		(fill yes
			(thermal_gap 0.5)
			(thermal_bridge_width 0.5)
			(island_removal_mode 0)
		)
		(polygon
			(pts
				(arc
					(start 207.425798 -272.321528)
					(mid 207.440677 -272.357449)
					(end 207.476598 -272.372328)
				)
				(arc
					(start 208.876138 -272.372328)
					(mid 208.912059 -272.357449)
					(end 208.926938 -272.321528)
				)
				(arc
					(start 208.926938 -271.912588)
					(mid 208.912059 -271.876667)
					(end 208.876138 -271.861788)
				)
				(arc
					(start 207.476598 -271.861788)
					(mid 207.440677 -271.876667)
					(end 207.425798 -271.912588)
				)
			)
		)
	)
	(zone
		(layers "In1.Cu" "In2.Cu")
		(hatch none 0.5)
		(connect_pads
			(clearance 0)
		)
		(min_thickness 0.25)
		(keepout
			(tracks not_allowed)
			(vias allowed)
			(pads allowed)
			(copperpour not_allowed)
			(footprints allowed)
		)
		(placement
			(enabled no)
			(sheetname "")
		)
		(fill yes
			(thermal_gap 0.5)
			(thermal_bridge_width 0.5)
			(island_removal_mode 0)
		)
		(polygon
			(pts
				(arc
					(start 421.090598 -251.07138)
					(mid 421.105477 -251.107301)
					(end 421.141398 -251.12218)
				)
				(arc
					(start 422.540938 -251.12218)
					(mid 422.576859 -251.107301)
					(end 422.591738 -251.07138)
				)
				(arc
					(start 422.591738 -250.66244)
					(mid 422.576859 -250.626519)
					(end 422.540938 -250.61164)
				)
				(arc
					(start 421.141398 -250.61164)
					(mid 421.105477 -250.626519)
					(end 421.090598 -250.66244)
				)
			)
		)
	)
	(zone
		(layers "In1.Cu" "In2.Cu")
		(hatch none 0.5)
		(connect_pads
			(clearance 0)
		)
		(min_thickness 0.25)
		(keepout
			(tracks not_allowed)
			(vias allowed)
			(pads allowed)
			(copperpour not_allowed)
			(footprints allowed)
		)
		(placement
			(enabled no)
			(sheetname "")
		)
		(fill yes
			(thermal_gap 0.5)
			(thermal_bridge_width 0.5)
			(island_removal_mode 0)
		)
		(polygon
			(pts
				(arc
					(start 11.490198 -302.921416)
					(mid 11.505077 -302.957337)
					(end 11.540998 -302.972216)
				)
				(arc
					(start 12.940538 -302.972216)
					(mid 12.976459 -302.957337)
					(end 12.991338 -302.921416)
				)
				(arc
					(start 12.991338 -302.512476)
					(mid 12.976459 -302.476555)
					(end 12.940538 -302.461676)
				)
				(arc
					(start 11.540998 -302.461676)
					(mid 11.505077 -302.476555)
					(end 11.490198 -302.512476)
				)
			)
		)
	)
	(zone
		(layers "In1.Cu" "In2.Cu")
		(hatch none 0.5)
		(connect_pads
			(clearance 0)
		)
		(min_thickness 0.25)
		(keepout
			(tracks not_allowed)
			(vias allowed)
			(pads allowed)
			(copperpour not_allowed)
			(footprints allowed)
		)
		(placement
			(enabled no)
			(sheetname "")
		)
		(fill yes
			(thermal_gap 0.5)
			(thermal_bridge_width 0.5)
			(island_removal_mode 0)
		)
		(polygon
			(pts
				(arc
					(start 425.190666 -302.071532)
					(mid 425.205545 -302.107453)
					(end 425.241466 -302.122332)
				)
				(arc
					(start 426.641006 -302.122332)
					(mid 426.676927 -302.107453)
					(end 426.691806 -302.071532)
				)
				(arc
					(start 426.691806 -301.662592)
					(mid 426.676927 -301.626671)
					(end 426.641006 -301.611792)
				)
				(arc
					(start 425.241466 -301.611792)
					(mid 425.205545 -301.626671)
					(end 425.190666 -301.662592)
				)
			)
		)
	)
	(zone
		(layers "In1.Cu" "In2.Cu")
		(hatch none 0.5)
		(connect_pads
			(clearance 0)
		)
		(min_thickness 0.25)
		(keepout
			(tracks not_allowed)
			(vias allowed)
			(pads allowed)
			(copperpour not_allowed)
			(footprints allowed)
		)
		(placement
			(enabled no)
			(sheetname "")
		)
		(fill yes
			(thermal_gap 0.5)
			(thermal_bridge_width 0.5)
			(island_removal_mode 0)
		)
		(polygon
			(pts
				(arc
					(start 11.490198 -250.221496)
					(mid 11.505077 -250.257417)
					(end 11.540998 -250.272296)
				)
				(arc
					(start 12.940538 -250.272296)
					(mid 12.976459 -250.257417)
					(end 12.991338 -250.221496)
				)
				(arc
					(start 12.991338 -249.812556)
					(mid 12.976459 -249.776635)
					(end 12.940538 -249.761756)
				)
				(arc
					(start 11.540998 -249.761756)
					(mid 11.505077 -249.776635)
					(end 11.490198 -249.812556)
				)
			)
		)
	)
	(zone
		(layers "In1.Cu" "In2.Cu")
		(hatch none 0.5)
		(connect_pads
			(clearance 0)
		)
		(min_thickness 0.25)
		(keepout
			(tracks not_allowed)
			(vias allowed)
			(pads allowed)
			(copperpour not_allowed)
			(footprints allowed)
		)
		(placement
			(enabled no)
			(sheetname "")
		)
		(fill yes
			(thermal_gap 0.5)
			(thermal_bridge_width 0.5)
			(island_removal_mode 0)
		)
		(polygon
			(pts
				(arc
					(start 207.425798 -283.371544)
					(mid 207.440677 -283.407465)
					(end 207.476598 -283.422344)
				)
				(arc
					(start 208.876138 -283.422344)
					(mid 208.912059 -283.407465)
					(end 208.926938 -283.371544)
				)
				(arc
					(start 208.926938 -282.962604)
					(mid 208.912059 -282.926683)
					(end 208.876138 -282.911804)
				)
				(arc
					(start 207.476598 -282.911804)
					(mid 207.440677 -282.926683)
					(end 207.425798 -282.962604)
				)
			)
		)
	)
	(zone
		(layers "In1.Cu" "In2.Cu")
		(hatch none 0.5)
		(connect_pads
			(clearance 0)
		)
		(min_thickness 0.25)
		(keepout
			(tracks not_allowed)
			(vias allowed)
			(pads allowed)
			(copperpour not_allowed)
			(footprints allowed)
		)
		(placement
			(enabled no)
			(sheetname "")
		)
		(fill yes
			(thermal_gap 0.5)
			(thermal_bridge_width 0.5)
			(island_removal_mode 0)
		)
		(polygon
			(pts
				(arc
					(start 462.909666 -208.571338)
					(mid 462.924545 -208.607259)
					(end 462.960466 -208.622138)
				)
				(arc
					(start 464.360006 -208.622138)
					(mid 464.395927 -208.607259)
					(end 464.410806 -208.571338)
				)
				(arc
					(start 464.410806 -208.162398)
					(mid 464.395927 -208.126477)
					(end 464.360006 -208.111598)
				)
				(arc
					(start 462.960466 -208.111598)
					(mid 462.924545 -208.126477)
					(end 462.909666 -208.162398)
				)
			)
		)
	)
	(zone
		(layers "In1.Cu" "In2.Cu")
		(hatch none 0.5)
		(connect_pads
			(clearance 0)
		)
		(min_thickness 0.25)
		(keepout
			(tracks not_allowed)
			(vias allowed)
			(pads allowed)
			(copperpour not_allowed)
			(footprints allowed)
		)
		(placement
			(enabled no)
			(sheetname "")
		)
		(fill yes
			(thermal_gap 0.5)
			(thermal_bridge_width 0.5)
			(island_removal_mode 0)
		)
		(polygon
			(pts
				(arc
					(start 289.605466 -240.871502)
					(mid 289.620345 -240.907423)
					(end 289.656266 -240.922302)
				)
				(arc
					(start 291.055806 -240.922302)
					(mid 291.091727 -240.907423)
					(end 291.106606 -240.871502)
				)
				(arc
					(start 291.106606 -240.462562)
					(mid 291.091727 -240.426641)
					(end 291.055806 -240.411762)
				)
				(arc
					(start 289.656266 -240.411762)
					(mid 289.620345 -240.426641)
					(end 289.605466 -240.462562)
				)
			)
		)
	)
	(zone
		(layers "In1.Cu" "In2.Cu")
		(hatch none 0.5)
		(connect_pads
			(clearance 0)
		)
		(min_thickness 0.25)
		(keepout
			(tracks not_allowed)
			(vias allowed)
			(pads allowed)
			(copperpour not_allowed)
			(footprints allowed)
		)
		(placement
			(enabled no)
			(sheetname "")
		)
		(fill yes
			(thermal_gap 0.5)
			(thermal_bridge_width 0.5)
			(island_removal_mode 0)
		)
		(polygon
			(pts
				(arc
					(start 45.10913 -200.071482)
					(mid 45.124009 -200.107403)
					(end 45.15993 -200.122282)
				)
				(arc
					(start 46.55947 -200.122282)
					(mid 46.595391 -200.107403)
					(end 46.61027 -200.071482)
				)
				(arc
					(start 46.61027 -199.662542)
					(mid 46.595391 -199.626621)
					(end 46.55947 -199.611742)
				)
				(arc
					(start 45.15993 -199.611742)
					(mid 45.124009 -199.626621)
					(end 45.10913 -199.662542)
				)
			)
		)
	)
	(zone
		(layers "In1.Cu" "In2.Cu")
		(hatch none 0.5)
		(connect_pads
			(clearance 0)
		)
		(min_thickness 0.25)
		(keepout
			(tracks not_allowed)
			(vias allowed)
			(pads allowed)
			(copperpour not_allowed)
			(footprints allowed)
		)
		(placement
			(enabled no)
			(sheetname "")
		)
		(fill yes
			(thermal_gap 0.5)
			(thermal_bridge_width 0.5)
			(island_removal_mode 0)
		)
		(polygon
			(pts
				(arc
					(start 262.873998 -261.271512)
					(mid 262.888877 -261.307433)
					(end 262.924798 -261.322312)
				)
				(arc
					(start 264.324338 -261.322312)
					(mid 264.360259 -261.307433)
					(end 264.375138 -261.271512)
				)
				(arc
					(start 264.375138 -260.862572)
					(mid 264.360259 -260.826651)
					(end 264.324338 -260.811772)
				)
				(arc
					(start 262.924798 -260.811772)
					(mid 262.888877 -260.826651)
					(end 262.873998 -260.862572)
				)
			)
		)
	)
	(zone
		(layers "In1.Cu" "In2.Cu")
		(hatch none 0.5)
		(connect_pads
			(clearance 0)
		)
		(min_thickness 0.25)
		(keepout
			(tracks not_allowed)
			(vias allowed)
			(pads allowed)
			(copperpour not_allowed)
			(footprints allowed)
		)
		(placement
			(enabled no)
			(sheetname "")
		)
		(fill yes
			(thermal_gap 0.5)
			(thermal_bridge_width 0.5)
			(island_removal_mode 0)
		)
		(polygon
			(pts
				(arc
					(start 158.06293 -234.071414)
					(mid 158.077809 -234.107335)
					(end 158.11373 -234.122214)
				)
				(arc
					(start 159.51327 -234.122214)
					(mid 159.549191 -234.107335)
					(end 159.56407 -234.071414)
				)
				(arc
					(start 159.56407 -233.662474)
					(mid 159.549191 -233.626553)
					(end 159.51327 -233.611674)
				)
				(arc
					(start 158.11373 -233.611674)
					(mid 158.077809 -233.626553)
					(end 158.06293 -233.662474)
				)
			)
		)
	)
	(zone
		(layers "In1.Cu" "In2.Cu")
		(hatch none 0.5)
		(connect_pads
			(clearance 0)
		)
		(min_thickness 0.25)
		(keepout
			(tracks not_allowed)
			(vias allowed)
			(pads allowed)
			(copperpour not_allowed)
			(footprints allowed)
		)
		(placement
			(enabled no)
			(sheetname "")
		)
		(fill yes
			(thermal_gap 0.5)
			(thermal_bridge_width 0.5)
			(island_removal_mode 0)
		)
		(polygon
			(pts
				(arc
					(start 52.65293 -198.37146)
					(mid 52.667809 -198.407381)
					(end 52.70373 -198.42226)
				)
				(arc
					(start 54.10327 -198.42226)
					(mid 54.139191 -198.407381)
					(end 54.15407 -198.37146)
				)
				(arc
					(start 54.15407 -197.96252)
					(mid 54.139191 -197.926599)
					(end 54.10327 -197.91172)
				)
				(arc
					(start 52.70373 -197.91172)
					(mid 52.667809 -197.926599)
					(end 52.65293 -197.96252)
				)
			)
		)
	)
	(zone
		(layers "In1.Cu" "In2.Cu")
		(hatch none 0.5)
		(connect_pads
			(clearance 0)
		)
		(min_thickness 0.25)
		(keepout
			(tracks not_allowed)
			(vias allowed)
			(pads allowed)
			(copperpour not_allowed)
			(footprints allowed)
		)
		(placement
			(enabled no)
			(sheetname "")
		)
		(fill yes
			(thermal_gap 0.5)
			(thermal_bridge_width 0.5)
			(island_removal_mode 0)
		)
		(polygon
			(pts
				(arc
					(start 37.56533 -308.871366)
					(mid 37.580209 -308.907287)
					(end 37.61613 -308.922166)
				)
				(arc
					(start 39.01567 -308.922166)
					(mid 39.051591 -308.907287)
					(end 39.06647 -308.871366)
				)
				(arc
					(start 39.06647 -308.462426)
					(mid 39.051591 -308.426505)
					(end 39.01567 -308.411626)
				)
				(arc
					(start 37.61613 -308.411626)
					(mid 37.580209 -308.426505)
					(end 37.56533 -308.462426)
				)
			)
		)
	)
	(zone
		(layers "In1.Cu" "In2.Cu")
		(hatch none 0.5)
		(connect_pads
			(clearance 0)
		)
		(min_thickness 0.25)
		(keepout
			(tracks not_allowed)
			(vias allowed)
			(pads allowed)
			(copperpour not_allowed)
			(footprints allowed)
		)
		(placement
			(enabled no)
			(sheetname "")
		)
		(fill yes
			(thermal_gap 0.5)
			(thermal_bridge_width 0.5)
			(island_removal_mode 0)
		)
		(polygon
			(pts
				(arc
					(start 214.969598 -236.62132)
					(mid 214.984477 -236.657241)
					(end 215.020398 -236.67212)
				)
				(arc
					(start 216.419938 -236.67212)
					(mid 216.455859 -236.657241)
					(end 216.470738 -236.62132)
				)
				(arc
					(start 216.470738 -236.21238)
					(mid 216.455859 -236.176459)
					(end 216.419938 -236.16158)
				)
				(arc
					(start 215.020398 -236.16158)
					(mid 214.984477 -236.176459)
					(end 214.969598 -236.21238)
				)
			)
		)
	)
	(zone
		(layers "In1.Cu" "In2.Cu")
		(hatch none 0.5)
		(connect_pads
			(clearance 0)
		)
		(min_thickness 0.25)
		(keepout
			(tracks not_allowed)
			(vias allowed)
			(pads allowed)
			(copperpour not_allowed)
			(footprints allowed)
		)
		(placement
			(enabled no)
			(sheetname "")
		)
		(fill yes
			(thermal_gap 0.5)
			(thermal_bridge_width 0.5)
			(island_removal_mode 0)
		)
		(polygon
			(pts
				(arc
					(start 266.974066 -246.821452)
					(mid 266.988945 -246.857373)
					(end 267.024866 -246.872252)
				)
				(arc
					(start 268.424406 -246.872252)
					(mid 268.460327 -246.857373)
					(end 268.475206 -246.821452)
				)
				(arc
					(start 268.475206 -246.412512)
					(mid 268.460327 -246.376591)
					(end 268.424406 -246.361712)
				)
				(arc
					(start 267.024866 -246.361712)
					(mid 266.988945 -246.376591)
					(end 266.974066 -246.412512)
				)
			)
		)
	)
	(zone
		(layers "In1.Cu" "In2.Cu")
		(hatch none 0.5)
		(connect_pads
			(clearance 0)
		)
		(min_thickness 0.25)
		(keepout
			(tracks not_allowed)
			(vias allowed)
			(pads allowed)
			(copperpour not_allowed)
			(footprints allowed)
		)
		(placement
			(enabled no)
			(sheetname "")
		)
		(fill yes
			(thermal_gap 0.5)
			(thermal_bridge_width 0.5)
			(island_removal_mode 0)
		)
		(polygon
			(pts
				(arc
					(start 210.86953 -219.621354)
					(mid 210.884409 -219.657275)
					(end 210.92033 -219.672154)
				)
				(arc
					(start 212.31987 -219.672154)
					(mid 212.355791 -219.657275)
					(end 212.37067 -219.621354)
				)
				(arc
					(start 212.37067 -219.212414)
					(mid 212.355791 -219.176493)
					(end 212.31987 -219.161614)
				)
				(arc
					(start 210.92033 -219.161614)
					(mid 210.884409 -219.176493)
					(end 210.86953 -219.212414)
				)
			)
		)
	)
	(zone
		(layers "In1.Cu" "In2.Cu")
		(hatch none 0.5)
		(connect_pads
			(clearance 0)
		)
		(min_thickness 0.25)
		(keepout
			(tracks not_allowed)
			(vias allowed)
			(pads allowed)
			(copperpour not_allowed)
			(footprints allowed)
		)
		(placement
			(enabled no)
			(sheetname "")
		)
		(fill yes
			(thermal_gap 0.5)
			(thermal_bridge_width 0.5)
			(island_removal_mode 0)
		)
		(polygon
			(pts
				(arc
					(start 285.505398 -218.77147)
					(mid 285.520277 -218.807391)
					(end 285.556198 -218.82227)
				)
				(arc
					(start 286.955738 -218.82227)
					(mid 286.991659 -218.807391)
					(end 287.006538 -218.77147)
				)
				(arc
					(start 287.006538 -218.36253)
					(mid 286.991659 -218.326609)
					(end 286.955738 -218.31173)
				)
				(arc
					(start 285.556198 -218.31173)
					(mid 285.520277 -218.326609)
					(end 285.505398 -218.36253)
				)
			)
		)
	)
	(zone
		(layers "In1.Cu" "In2.Cu")
		(hatch none 0.5)
		(connect_pads
			(clearance 0)
		)
		(min_thickness 0.25)
		(keepout
			(tracks not_allowed)
			(vias allowed)
			(pads allowed)
			(copperpour not_allowed)
			(footprints allowed)
		)
		(placement
			(enabled no)
			(sheetname "")
		)
		(fill yes
			(thermal_gap 0.5)
			(thermal_bridge_width 0.5)
			(island_removal_mode 0)
		)
		(polygon
			(pts
				(arc
					(start 180.69433 -301.221394)
					(mid 180.709209 -301.257315)
					(end 180.74513 -301.272194)
				)
				(arc
					(start 182.14467 -301.272194)
					(mid 182.180591 -301.257315)
					(end 182.19547 -301.221394)
				)
				(arc
					(start 182.19547 -300.812454)
					(mid 182.180591 -300.776533)
					(end 182.14467 -300.761654)
				)
				(arc
					(start 180.74513 -300.761654)
					(mid 180.709209 -300.776533)
					(end 180.69433 -300.812454)
				)
			)
		)
	)
	(zone
		(layers "In1.Cu" "In2.Cu")
		(hatch none 0.5)
		(connect_pads
			(clearance 0)
		)
		(min_thickness 0.25)
		(keepout
			(tracks not_allowed)
			(vias allowed)
			(pads allowed)
			(copperpour not_allowed)
			(footprints allowed)
		)
		(placement
			(enabled no)
			(sheetname "")
		)
		(fill yes
			(thermal_gap 0.5)
			(thermal_bridge_width 0.5)
			(island_removal_mode 0)
		)
		(polygon
			(pts
				(arc
					(start 282.061666 -250.221496)
					(mid 282.076545 -250.257417)
					(end 282.112466 -250.272296)
				)
				(arc
					(start 283.512006 -250.272296)
					(mid 283.547927 -250.257417)
					(end 283.562806 -250.221496)
				)
				(arc
					(start 283.562806 -249.812556)
					(mid 283.547927 -249.776635)
					(end 283.512006 -249.761756)
				)
				(arc
					(start 282.112466 -249.761756)
					(mid 282.076545 -249.776635)
					(end 282.061666 -249.812556)
				)
			)
		)
	)
	(zone
		(layers "In1.Cu" "In2.Cu")
		(hatch none 0.5)
		(connect_pads
			(clearance 0)
		)
		(min_thickness 0.25)
		(keepout
			(tracks not_allowed)
			(vias allowed)
			(pads allowed)
			(copperpour not_allowed)
			(footprints allowed)
		)
		(placement
			(enabled no)
			(sheetname "")
		)
		(fill yes
			(thermal_gap 0.5)
			(thermal_bridge_width 0.5)
			(island_removal_mode 0)
		)
		(polygon
			(pts
				(arc
					(start 455.365866 -222.171514)
					(mid 455.380745 -222.207435)
					(end 455.416666 -222.222314)
				)
				(arc
					(start 456.816206 -222.222314)
					(mid 456.852127 -222.207435)
					(end 456.867006 -222.171514)
				)
				(arc
					(start 456.867006 -221.762574)
					(mid 456.852127 -221.726653)
					(end 456.816206 -221.711774)
				)
				(arc
					(start 455.416666 -221.711774)
					(mid 455.380745 -221.726653)
					(end 455.365866 -221.762574)
				)
			)
		)
	)
	(zone
		(layers "In1.Cu" "In2.Cu")
		(hatch none 0.5)
		(connect_pads
			(clearance 0)
		)
		(min_thickness 0.25)
		(keepout
			(tracks not_allowed)
			(vias allowed)
			(pads allowed)
			(copperpour not_allowed)
			(footprints allowed)
		)
		(placement
			(enabled no)
			(sheetname "")
		)
		(fill yes
			(thermal_gap 0.5)
			(thermal_bridge_width 0.5)
			(island_removal_mode 0)
		)
		(polygon
			(pts
				(arc
					(start 210.86953 -232.371392)
					(mid 210.884409 -232.407313)
					(end 210.92033 -232.422192)
				)
				(arc
					(start 212.31987 -232.422192)
					(mid 212.355791 -232.407313)
					(end 212.37067 -232.371392)
				)
				(arc
					(start 212.37067 -231.962452)
					(mid 212.355791 -231.926531)
					(end 212.31987 -231.911652)
				)
				(arc
					(start 210.92033 -231.911652)
					(mid 210.884409 -231.926531)
					(end 210.86953 -231.962452)
				)
			)
		)
	)
	(zone
		(layers "In1.Cu" "In2.Cu")
		(hatch none 0.5)
		(connect_pads
			(clearance 0)
		)
		(min_thickness 0.25)
		(keepout
			(tracks not_allowed)
			(vias allowed)
			(pads allowed)
			(copperpour not_allowed)
			(footprints allowed)
		)
		(placement
			(enabled no)
			(sheetname "")
		)
		(fill yes
			(thermal_gap 0.5)
			(thermal_bridge_width 0.5)
			(island_removal_mode 0)
		)
		(polygon
			(pts
				(arc
					(start 428.634398 -274.871434)
					(mid 428.649277 -274.907355)
					(end 428.685198 -274.922234)
				)
				(arc
					(start 430.084738 -274.922234)
					(mid 430.120659 -274.907355)
					(end 430.135538 -274.871434)
				)
				(arc
					(start 430.135538 -274.462494)
					(mid 430.120659 -274.426573)
					(end 430.084738 -274.411694)
				)
				(arc
					(start 428.685198 -274.411694)
					(mid 428.649277 -274.426573)
					(end 428.634398 -274.462494)
				)
			)
		)
	)
	(zone
		(layers "In1.Cu" "In2.Cu")
		(hatch none 0.5)
		(connect_pads
			(clearance 0)
		)
		(min_thickness 0.25)
		(keepout
			(tracks not_allowed)
			(vias allowed)
			(pads allowed)
			(copperpour not_allowed)
			(footprints allowed)
		)
		(placement
			(enabled no)
			(sheetname "")
		)
		(fill yes
			(thermal_gap 0.5)
			(thermal_bridge_width 0.5)
			(island_removal_mode 0)
		)
		(polygon
			(pts
				(arc
					(start 285.505398 -290.171378)
					(mid 285.520277 -290.207299)
					(end 285.556198 -290.222178)
				)
				(arc
					(start 286.955738 -290.222178)
					(mid 286.991659 -290.207299)
					(end 287.006538 -290.171378)
				)
				(arc
					(start 287.006538 -289.762438)
					(mid 286.991659 -289.726517)
					(end 286.955738 -289.711638)
				)
				(arc
					(start 285.556198 -289.711638)
					(mid 285.520277 -289.726517)
					(end 285.505398 -289.762438)
				)
			)
		)
	)
	(zone
		(layers "In1.Cu" "In2.Cu")
		(hatch none 0.5)
		(connect_pads
			(clearance 0)
		)
		(min_thickness 0.25)
		(keepout
			(tracks not_allowed)
			(vias allowed)
			(pads allowed)
			(copperpour not_allowed)
			(footprints allowed)
		)
		(placement
			(enabled no)
			(sheetname "")
		)
		(fill yes
			(thermal_gap 0.5)
			(thermal_bridge_width 0.5)
			(island_removal_mode 0)
		)
		(polygon
			(pts
				(arc
					(start 417.646866 -251.921518)
					(mid 417.661745 -251.957439)
					(end 417.697666 -251.972318)
				)
				(arc
					(start 419.097206 -251.972318)
					(mid 419.133127 -251.957439)
					(end 419.148006 -251.921518)
				)
				(arc
					(start 419.148006 -251.512578)
					(mid 419.133127 -251.476657)
					(end 419.097206 -251.461778)
				)
				(arc
					(start 417.697666 -251.461778)
					(mid 417.661745 -251.476657)
					(end 417.646866 -251.512578)
				)
			)
		)
	)
	(zone
		(layers "In1.Cu" "In2.Cu")
		(hatch none 0.5)
		(connect_pads
			(clearance 0)
		)
		(min_thickness 0.25)
		(keepout
			(tracks not_allowed)
			(vias allowed)
			(pads allowed)
			(copperpour not_allowed)
			(footprints allowed)
		)
		(placement
			(enabled no)
			(sheetname "")
		)
		(fill yes
			(thermal_gap 0.5)
			(thermal_bridge_width 0.5)
			(island_removal_mode 0)
		)
		(polygon
			(pts
				(arc
					(start 308.136798 -230.67137)
					(mid 308.151677 -230.707291)
					(end 308.187598 -230.72217)
				)
				(arc
					(start 309.587138 -230.72217)
					(mid 309.623059 -230.707291)
					(end 309.637938 -230.67137)
				)
				(arc
					(start 309.637938 -230.26243)
					(mid 309.623059 -230.226509)
					(end 309.587138 -230.21163)
				)
				(arc
					(start 308.187598 -230.21163)
					(mid 308.151677 -230.226509)
					(end 308.136798 -230.26243)
				)
			)
		)
	)
	(zone
		(layers "In1.Cu" "In2.Cu")
		(hatch none 0.5)
		(connect_pads
			(clearance 0)
		)
		(min_thickness 0.25)
		(keepout
			(tracks not_allowed)
			(vias allowed)
			(pads allowed)
			(copperpour not_allowed)
			(footprints allowed)
		)
		(placement
			(enabled no)
			(sheetname "")
		)
		(fill yes
			(thermal_gap 0.5)
			(thermal_bridge_width 0.5)
			(island_removal_mode 0)
		)
		(polygon
			(pts
				(arc
					(start 443.721998 -209.421476)
					(mid 443.736877 -209.457397)
					(end 443.772798 -209.472276)
				)
				(arc
					(start 445.172338 -209.472276)
					(mid 445.208259 -209.457397)
					(end 445.223138 -209.421476)
				)
				(arc
					(start 445.223138 -209.012536)
					(mid 445.208259 -208.976615)
					(end 445.172338 -208.961736)
				)
				(arc
					(start 443.772798 -208.961736)
					(mid 443.736877 -208.976615)
					(end 443.721998 -209.012536)
				)
			)
		)
	)
	(zone
		(layers "In1.Cu" "In2.Cu")
		(hatch none 0.5)
		(connect_pads
			(clearance 0)
		)
		(min_thickness 0.25)
		(keepout
			(tracks not_allowed)
			(vias allowed)
			(pads allowed)
			(copperpour not_allowed)
			(footprints allowed)
		)
		(placement
			(enabled no)
			(sheetname "")
		)
		(fill yes
			(thermal_gap 0.5)
			(thermal_bridge_width 0.5)
			(island_removal_mode 0)
		)
		(polygon
			(pts
				(arc
					(start 173.15053 -211.971382)
					(mid 173.165409 -212.007303)
					(end 173.20133 -212.022182)
				)
				(arc
					(start 174.60087 -212.022182)
					(mid 174.636791 -212.007303)
					(end 174.65167 -211.971382)
				)
				(arc
					(start 174.65167 -211.562442)
					(mid 174.636791 -211.526521)
					(end 174.60087 -211.511642)
				)
				(arc
					(start 173.20133 -211.511642)
					(mid 173.165409 -211.526521)
					(end 173.15053 -211.562442)
				)
			)
		)
	)
	(zone
		(layers "In1.Cu" "In2.Cu")
		(hatch none 0.5)
		(connect_pads
			(clearance 0)
		)
		(min_thickness 0.25)
		(keepout
			(tracks not_allowed)
			(vias allowed)
			(pads allowed)
			(copperpour not_allowed)
			(footprints allowed)
		)
		(placement
			(enabled no)
			(sheetname "")
		)
		(fill yes
			(thermal_gap 0.5)
			(thermal_bridge_width 0.5)
			(island_removal_mode 0)
		)
		(polygon
			(pts
				(arc
					(start 285.505398 -294.421306)
					(mid 285.520277 -294.457227)
					(end 285.556198 -294.472106)
				)
				(arc
					(start 286.955738 -294.472106)
					(mid 286.991659 -294.457227)
					(end 287.006538 -294.421306)
				)
				(arc
					(start 287.006538 -294.012366)
					(mid 286.991659 -293.976445)
					(end 286.955738 -293.961566)
				)
				(arc
					(start 285.556198 -293.961566)
					(mid 285.520277 -293.976445)
					(end 285.505398 -294.012366)
				)
			)
		)
	)
	(zone
		(layers "In1.Cu" "In2.Cu")
		(hatch none 0.5)
		(connect_pads
			(clearance 0)
		)
		(min_thickness 0.25)
		(keepout
			(tracks not_allowed)
			(vias allowed)
			(pads allowed)
			(copperpour not_allowed)
			(footprints allowed)
		)
		(placement
			(enabled no)
			(sheetname "")
		)
		(fill yes
			(thermal_gap 0.5)
			(thermal_bridge_width 0.5)
			(island_removal_mode 0)
		)
		(polygon
			(pts
				(arc
					(start 274.517866 -265.52144)
					(mid 274.532745 -265.557361)
					(end 274.568666 -265.57224)
				)
				(arc
					(start 275.968206 -265.57224)
					(mid 276.004127 -265.557361)
					(end 276.019006 -265.52144)
				)
				(arc
					(start 276.019006 -265.1125)
					(mid 276.004127 -265.076579)
					(end 275.968206 -265.0617)
				)
				(arc
					(start 274.568666 -265.0617)
					(mid 274.532745 -265.076579)
					(end 274.517866 -265.1125)
				)
			)
		)
	)
	(zone
		(layers "In1.Cu" "In2.Cu")
		(hatch none 0.5)
		(connect_pads
			(clearance 0)
		)
		(min_thickness 0.25)
		(keepout
			(tracks not_allowed)
			(vias allowed)
			(pads allowed)
			(copperpour not_allowed)
			(footprints allowed)
		)
		(placement
			(enabled no)
			(sheetname "")
		)
		(fill yes
			(thermal_gap 0.5)
			(thermal_bridge_width 0.5)
			(island_removal_mode 0)
		)
		(polygon
			(pts
				(arc
					(start 177.250598 -237.471458)
					(mid 177.265477 -237.507379)
					(end 177.301398 -237.522258)
				)
				(arc
					(start 178.700938 -237.522258)
					(mid 178.736859 -237.507379)
					(end 178.751738 -237.471458)
				)
				(arc
					(start 178.751738 -237.062518)
					(mid 178.736859 -237.026597)
					(end 178.700938 -237.011718)
				)
				(arc
					(start 177.301398 -237.011718)
					(mid 177.265477 -237.026597)
					(end 177.250598 -237.062518)
				)
			)
		)
	)
	(zone
		(layers "In1.Cu" "In2.Cu")
		(hatch none 0.5)
		(connect_pads
			(clearance 0)
		)
		(min_thickness 0.25)
		(keepout
			(tracks not_allowed)
			(vias allowed)
			(pads allowed)
			(copperpour not_allowed)
			(footprints allowed)
		)
		(placement
			(enabled no)
			(sheetname "")
		)
		(fill yes
			(thermal_gap 0.5)
			(thermal_bridge_width 0.5)
			(island_removal_mode 0)
		)
		(polygon
			(pts
				(arc
					(start 169.706798 -208.571338)
					(mid 169.721677 -208.607259)
					(end 169.757598 -208.622138)
				)
				(arc
					(start 171.157138 -208.622138)
					(mid 171.193059 -208.607259)
					(end 171.207938 -208.571338)
				)
				(arc
					(start 171.207938 -208.162398)
					(mid 171.193059 -208.126477)
					(end 171.157138 -208.111598)
				)
				(arc
					(start 169.757598 -208.111598)
					(mid 169.721677 -208.126477)
					(end 169.706798 -208.162398)
				)
			)
		)
	)
	(zone
		(layers "In1.Cu" "In2.Cu")
		(hatch none 0.5)
		(connect_pads
			(clearance 0)
		)
		(min_thickness 0.25)
		(keepout
			(tracks not_allowed)
			(vias allowed)
			(pads allowed)
			(copperpour not_allowed)
			(footprints allowed)
		)
		(placement
			(enabled no)
			(sheetname "")
		)
		(fill yes
			(thermal_gap 0.5)
			(thermal_bridge_width 0.5)
			(island_removal_mode 0)
		)
		(polygon
			(pts
				(arc
					(start 19.033998 -231.521508)
					(mid 19.048877 -231.557429)
					(end 19.084798 -231.572308)
				)
				(arc
					(start 20.484338 -231.572308)
					(mid 20.520259 -231.557429)
					(end 20.535138 -231.521508)
				)
				(arc
					(start 20.535138 -231.112568)
					(mid 20.520259 -231.076647)
					(end 20.484338 -231.061768)
				)
				(arc
					(start 19.084798 -231.061768)
					(mid 19.048877 -231.076647)
					(end 19.033998 -231.112568)
				)
			)
		)
	)
	(zone
		(layers "In1.Cu" "In2.Cu")
		(hatch none 0.5)
		(connect_pads
			(clearance 0)
		)
		(min_thickness 0.25)
		(keepout
			(tracks not_allowed)
			(vias allowed)
			(pads allowed)
			(copperpour not_allowed)
			(footprints allowed)
		)
		(placement
			(enabled no)
			(sheetname "")
		)
		(fill yes
			(thermal_gap 0.5)
			(thermal_bridge_width 0.5)
			(island_removal_mode 0)
		)
		(polygon
			(pts
				(arc
					(start 26.577798 -229.821486)
					(mid 26.592677 -229.857407)
					(end 26.628598 -229.872286)
				)
				(arc
					(start 28.028138 -229.872286)
					(mid 28.064059 -229.857407)
					(end 28.078938 -229.821486)
				)
				(arc
					(start 28.078938 -229.412546)
					(mid 28.064059 -229.376625)
					(end 28.028138 -229.361746)
				)
				(arc
					(start 26.628598 -229.361746)
					(mid 26.592677 -229.376625)
					(end 26.577798 -229.412546)
				)
			)
		)
	)
	(zone
		(layers "In1.Cu" "In2.Cu")
		(hatch none 0.5)
		(connect_pads
			(clearance 0)
		)
		(min_thickness 0.25)
		(keepout
			(tracks not_allowed)
			(vias allowed)
			(pads allowed)
			(copperpour not_allowed)
			(footprints allowed)
		)
		(placement
			(enabled no)
			(sheetname "")
		)
		(fill yes
			(thermal_gap 0.5)
			(thermal_bridge_width 0.5)
			(island_removal_mode 0)
		)
		(polygon
			(pts
				(arc
					(start 34.121598 -315.671454)
					(mid 34.136477 -315.707375)
					(end 34.172398 -315.722254)
				)
				(arc
					(start 35.571938 -315.722254)
					(mid 35.607859 -315.707375)
					(end 35.622738 -315.671454)
				)
				(arc
					(start 35.622738 -315.262514)
					(mid 35.607859 -315.226593)
					(end 35.571938 -315.211714)
				)
				(arc
					(start 34.172398 -315.211714)
					(mid 34.136477 -315.226593)
					(end 34.121598 -315.262514)
				)
			)
		)
	)
	(zone
		(layers "In1.Cu" "In2.Cu")
		(hatch none 0.5)
		(connect_pads
			(clearance 0)
		)
		(min_thickness 0.25)
		(keepout
			(tracks not_allowed)
			(vias allowed)
			(pads allowed)
			(copperpour not_allowed)
			(footprints allowed)
		)
		(placement
			(enabled no)
			(sheetname "")
		)
		(fill yes
			(thermal_gap 0.5)
			(thermal_bridge_width 0.5)
			(island_removal_mode 0)
		)
		(polygon
			(pts
				(arc
					(start 207.425798 -236.62132)
					(mid 207.440677 -236.657241)
					(end 207.476598 -236.67212)
				)
				(arc
					(start 208.876138 -236.67212)
					(mid 208.912059 -236.657241)
					(end 208.926938 -236.62132)
				)
				(arc
					(start 208.926938 -236.21238)
					(mid 208.912059 -236.176459)
					(end 208.876138 -236.16158)
				)
				(arc
					(start 207.476598 -236.16158)
					(mid 207.440677 -236.176459)
					(end 207.425798 -236.21238)
				)
			)
		)
	)
	(zone
		(layers "In1.Cu" "In2.Cu")
		(hatch none 0.5)
		(connect_pads
			(clearance 0)
		)
		(min_thickness 0.25)
		(keepout
			(tracks not_allowed)
			(vias allowed)
			(pads allowed)
			(copperpour not_allowed)
			(footprints allowed)
		)
		(placement
			(enabled no)
			(sheetname "")
		)
		(fill yes
			(thermal_gap 0.5)
			(thermal_bridge_width 0.5)
			(island_removal_mode 0)
		)
		(polygon
			(pts
				(arc
					(start 447.822066 -250.221496)
					(mid 447.836945 -250.257417)
					(end 447.872866 -250.272296)
				)
				(arc
					(start 449.272406 -250.272296)
					(mid 449.308327 -250.257417)
					(end 449.323206 -250.221496)
				)
				(arc
					(start 449.323206 -249.812556)
					(mid 449.308327 -249.776635)
					(end 449.272406 -249.761756)
				)
				(arc
					(start 447.872866 -249.761756)
					(mid 447.836945 -249.776635)
					(end 447.822066 -249.812556)
				)
			)
		)
	)
	(zone
		(layers "In1.Cu" "In2.Cu")
		(hatch none 0.5)
		(connect_pads
			(clearance 0)
		)
		(min_thickness 0.25)
		(keepout
			(tracks not_allowed)
			(vias allowed)
			(pads allowed)
			(copperpour not_allowed)
			(footprints allowed)
		)
		(placement
			(enabled no)
			(sheetname "")
		)
		(fill yes
			(thermal_gap 0.5)
			(thermal_bridge_width 0.5)
			(island_removal_mode 0)
		)
		(polygon
			(pts
				(arc
					(start 262.873998 -264.671302)
					(mid 262.888877 -264.707223)
					(end 262.924798 -264.722102)
				)
				(arc
					(start 264.324338 -264.722102)
					(mid 264.360259 -264.707223)
					(end 264.375138 -264.671302)
				)
				(arc
					(start 264.375138 -264.262362)
					(mid 264.360259 -264.226441)
					(end 264.324338 -264.211562)
				)
				(arc
					(start 262.924798 -264.211562)
					(mid 262.888877 -264.226441)
					(end 262.873998 -264.262362)
				)
			)
		)
	)
	(zone
		(layers "In1.Cu" "In2.Cu")
		(hatch none 0.5)
		(connect_pads
			(clearance 0)
		)
		(min_thickness 0.25)
		(keepout
			(tracks not_allowed)
			(vias allowed)
			(pads allowed)
			(copperpour not_allowed)
			(footprints allowed)
		)
		(placement
			(enabled no)
			(sheetname "")
		)
		(fill yes
			(thermal_gap 0.5)
			(thermal_bridge_width 0.5)
			(island_removal_mode 0)
		)
		(polygon
			(pts
				(arc
					(start 436.178198 -288.471356)
					(mid 436.193077 -288.507277)
					(end 436.228998 -288.522156)
				)
				(arc
					(start 437.628538 -288.522156)
					(mid 437.664459 -288.507277)
					(end 437.679338 -288.471356)
				)
				(arc
					(start 437.679338 -288.062416)
					(mid 437.664459 -288.026495)
					(end 437.628538 -288.011616)
				)
				(arc
					(start 436.228998 -288.011616)
					(mid 436.193077 -288.026495)
					(end 436.178198 -288.062416)
				)
			)
		)
	)
	(zone
		(layers "In1.Cu" "In2.Cu")
		(hatch none 0.5)
		(connect_pads
			(clearance 0)
		)
		(min_thickness 0.25)
		(keepout
			(tracks not_allowed)
			(vias allowed)
			(pads allowed)
			(copperpour not_allowed)
			(footprints allowed)
		)
		(placement
			(enabled no)
			(sheetname "")
		)
		(fill yes
			(thermal_gap 0.5)
			(thermal_bridge_width 0.5)
			(island_removal_mode 0)
		)
		(polygon
			(pts
				(arc
					(start 417.646866 -222.171514)
					(mid 417.661745 -222.207435)
					(end 417.697666 -222.222314)
				)
				(arc
					(start 419.097206 -222.222314)
					(mid 419.133127 -222.207435)
					(end 419.148006 -222.171514)
				)
				(arc
					(start 419.148006 -221.762574)
					(mid 419.133127 -221.726653)
					(end 419.097206 -221.711774)
				)
				(arc
					(start 417.697666 -221.711774)
					(mid 417.661745 -221.726653)
					(end 417.646866 -221.762574)
				)
			)
		)
	)
	(zone
		(layers "In1.Cu" "In2.Cu")
		(hatch none 0.5)
		(connect_pads
			(clearance 0)
		)
		(min_thickness 0.25)
		(keepout
			(tracks not_allowed)
			(vias allowed)
			(pads allowed)
			(copperpour not_allowed)
			(footprints allowed)
		)
		(placement
			(enabled no)
			(sheetname "")
		)
		(fill yes
			(thermal_gap 0.5)
			(thermal_bridge_width 0.5)
			(island_removal_mode 0)
		)
		(polygon
			(pts
				(arc
					(start 270.417798 -284.221428)
					(mid 270.432677 -284.257349)
					(end 270.468598 -284.272228)
				)
				(arc
					(start 271.868138 -284.272228)
					(mid 271.904059 -284.257349)
					(end 271.918938 -284.221428)
				)
				(arc
					(start 271.918938 -283.812488)
					(mid 271.904059 -283.776567)
					(end 271.868138 -283.761688)
				)
				(arc
					(start 270.468598 -283.761688)
					(mid 270.432677 -283.776567)
					(end 270.417798 -283.812488)
				)
			)
		)
	)
	(zone
		(layers "In1.Cu" "In2.Cu")
		(hatch none 0.5)
		(connect_pads
			(clearance 0)
		)
		(min_thickness 0.25)
		(keepout
			(tracks not_allowed)
			(vias allowed)
			(pads allowed)
			(copperpour not_allowed)
			(footprints allowed)
		)
		(placement
			(enabled no)
			(sheetname "")
		)
		(fill yes
			(thermal_gap 0.5)
			(thermal_bridge_width 0.5)
			(island_removal_mode 0)
		)
		(polygon
			(pts
				(arc
					(start 162.162998 -279.9715)
					(mid 162.177877 -280.007421)
					(end 162.213798 -280.0223)
				)
				(arc
					(start 163.613338 -280.0223)
					(mid 163.649259 -280.007421)
					(end 163.664138 -279.9715)
				)
				(arc
					(start 163.664138 -279.56256)
					(mid 163.649259 -279.526639)
					(end 163.613338 -279.51176)
				)
				(arc
					(start 162.213798 -279.51176)
					(mid 162.177877 -279.526639)
					(end 162.162998 -279.56256)
				)
			)
		)
	)
	(zone
		(layers "In1.Cu" "In2.Cu")
		(hatch none 0.5)
		(connect_pads
			(clearance 0)
		)
		(min_thickness 0.25)
		(keepout
			(tracks not_allowed)
			(vias allowed)
			(pads allowed)
			(copperpour not_allowed)
			(footprints allowed)
		)
		(placement
			(enabled no)
			(sheetname "")
		)
		(fill yes
			(thermal_gap 0.5)
			(thermal_bridge_width 0.5)
			(island_removal_mode 0)
		)
		(polygon
			(pts
				(arc
					(start 297.149266 -289.321494)
					(mid 297.164145 -289.357415)
					(end 297.200066 -289.372294)
				)
				(arc
					(start 298.599606 -289.372294)
					(mid 298.635527 -289.357415)
					(end 298.650406 -289.321494)
				)
				(arc
					(start 298.650406 -288.912554)
					(mid 298.635527 -288.876633)
					(end 298.599606 -288.861754)
				)
				(arc
					(start 297.200066 -288.861754)
					(mid 297.164145 -288.876633)
					(end 297.149266 -288.912554)
				)
			)
		)
	)
	(zone
		(layers "In1.Cu" "In2.Cu")
		(hatch none 0.5)
		(connect_pads
			(clearance 0)
		)
		(min_thickness 0.25)
		(keepout
			(tracks not_allowed)
			(vias allowed)
			(pads allowed)
			(copperpour not_allowed)
			(footprints allowed)
		)
		(placement
			(enabled no)
			(sheetname "")
		)
		(fill yes
			(thermal_gap 0.5)
			(thermal_bridge_width 0.5)
			(island_removal_mode 0)
		)
		(polygon
			(pts
				(arc
					(start 255.330198 -294.421306)
					(mid 255.345077 -294.457227)
					(end 255.380998 -294.472106)
				)
				(arc
					(start 256.780538 -294.472106)
					(mid 256.816459 -294.457227)
					(end 256.831338 -294.421306)
				)
				(arc
					(start 256.831338 -294.012366)
					(mid 256.816459 -293.976445)
					(end 256.780538 -293.961566)
				)
				(arc
					(start 255.380998 -293.961566)
					(mid 255.345077 -293.976445)
					(end 255.330198 -294.012366)
				)
			)
		)
	)
	(zone
		(layers "In1.Cu" "In2.Cu")
		(hatch none 0.5)
		(connect_pads
			(clearance 0)
		)
		(min_thickness 0.25)
		(keepout
			(tracks not_allowed)
			(vias allowed)
			(pads allowed)
			(copperpour not_allowed)
			(footprints allowed)
		)
		(placement
			(enabled no)
			(sheetname "")
		)
		(fill yes
			(thermal_gap 0.5)
			(thermal_bridge_width 0.5)
			(island_removal_mode 0)
		)
		(polygon
			(pts
				(arc
					(start 455.365866 -197.521322)
					(mid 455.380745 -197.557243)
					(end 455.416666 -197.572122)
				)
				(arc
					(start 456.816206 -197.572122)
					(mid 456.852127 -197.557243)
					(end 456.867006 -197.521322)
				)
				(arc
					(start 456.867006 -197.112382)
					(mid 456.852127 -197.076461)
					(end 456.816206 -197.061582)
				)
				(arc
					(start 455.416666 -197.061582)
					(mid 455.380745 -197.076461)
					(end 455.365866 -197.112382)
				)
			)
		)
	)
	(zone
		(layers "In1.Cu" "In2.Cu")
		(hatch none 0.5)
		(connect_pads
			(clearance 0)
		)
		(min_thickness 0.25)
		(keepout
			(tracks not_allowed)
			(vias allowed)
			(pads allowed)
			(copperpour not_allowed)
			(footprints allowed)
		)
		(placement
			(enabled no)
			(sheetname "")
		)
		(fill yes
			(thermal_gap 0.5)
			(thermal_bridge_width 0.5)
			(island_removal_mode 0)
		)
		(polygon
			(pts
				(arc
					(start 293.049198 -299.521372)
					(mid 293.064077 -299.557293)
					(end 293.099998 -299.572172)
				)
				(arc
					(start 294.499538 -299.572172)
					(mid 294.535459 -299.557293)
					(end 294.550338 -299.521372)
				)
				(arc
					(start 294.550338 -299.112432)
					(mid 294.535459 -299.076511)
					(end 294.499538 -299.061632)
				)
				(arc
					(start 293.099998 -299.061632)
					(mid 293.064077 -299.076511)
					(end 293.049198 -299.112432)
				)
			)
		)
	)
	(zone
		(layers "In1.Cu" "In2.Cu")
		(hatch none 0.5)
		(connect_pads
			(clearance 0)
		)
		(min_thickness 0.25)
		(keepout
			(tracks not_allowed)
			(vias allowed)
			(pads allowed)
			(copperpour not_allowed)
			(footprints allowed)
		)
		(placement
			(enabled no)
			(sheetname "")
		)
		(fill yes
			(thermal_gap 0.5)
			(thermal_bridge_width 0.5)
			(island_removal_mode 0)
		)
		(polygon
			(pts
				(arc
					(start 14.93393 -288.471356)
					(mid 14.948809 -288.507277)
					(end 14.98473 -288.522156)
				)
				(arc
					(start 16.38427 -288.522156)
					(mid 16.420191 -288.507277)
					(end 16.43507 -288.471356)
				)
				(arc
					(start 16.43507 -288.062416)
					(mid 16.420191 -288.026495)
					(end 16.38427 -288.011616)
				)
				(arc
					(start 14.98473 -288.011616)
					(mid 14.948809 -288.026495)
					(end 14.93393 -288.062416)
				)
			)
		)
	)
	(zone
		(layers "In1.Cu" "In2.Cu")
		(hatch none 0.5)
		(connect_pads
			(clearance 0)
		)
		(min_thickness 0.25)
		(keepout
			(tracks not_allowed)
			(vias allowed)
			(pads allowed)
			(copperpour not_allowed)
			(footprints allowed)
		)
		(placement
			(enabled no)
			(sheetname "")
		)
		(fill yes
			(thermal_gap 0.5)
			(thermal_bridge_width 0.5)
			(island_removal_mode 0)
		)
		(polygon
			(pts
				(arc
					(start 293.049198 -275.721318)
					(mid 293.064077 -275.757239)
					(end 293.099998 -275.772118)
				)
				(arc
					(start 294.499538 -275.772118)
					(mid 294.535459 -275.757239)
					(end 294.550338 -275.721318)
				)
				(arc
					(start 294.550338 -275.312378)
					(mid 294.535459 -275.276457)
					(end 294.499538 -275.261578)
				)
				(arc
					(start 293.099998 -275.261578)
					(mid 293.064077 -275.276457)
					(end 293.049198 -275.312378)
				)
			)
		)
	)
	(zone
		(layers "In1.Cu" "In2.Cu")
		(hatch none 0.5)
		(connect_pads
			(clearance 0)
		)
		(min_thickness 0.25)
		(keepout
			(tracks not_allowed)
			(vias allowed)
			(pads allowed)
			(copperpour not_allowed)
			(footprints allowed)
		)
		(placement
			(enabled no)
			(sheetname "")
		)
		(fill yes
			(thermal_gap 0.5)
			(thermal_bridge_width 0.5)
			(island_removal_mode 0)
		)
		(polygon
			(pts
				(arc
					(start 22.47773 -200.071482)
					(mid 22.492609 -200.107403)
					(end 22.52853 -200.122282)
				)
				(arc
					(start 23.92807 -200.122282)
					(mid 23.963991 -200.107403)
					(end 23.97887 -200.071482)
				)
				(arc
					(start 23.97887 -199.662542)
					(mid 23.963991 -199.626621)
					(end 23.92807 -199.611742)
				)
				(arc
					(start 22.52853 -199.611742)
					(mid 22.492609 -199.626621)
					(end 22.47773 -199.662542)
				)
			)
		)
	)
	(zone
		(layers "In1.Cu" "In2.Cu")
		(hatch none 0.5)
		(connect_pads
			(clearance 0)
		)
		(min_thickness 0.25)
		(keepout
			(tracks not_allowed)
			(vias allowed)
			(pads allowed)
			(copperpour not_allowed)
			(footprints allowed)
		)
		(placement
			(enabled no)
			(sheetname "")
		)
		(fill yes
			(thermal_gap 0.5)
			(thermal_bridge_width 0.5)
			(island_removal_mode 0)
		)
		(polygon
			(pts
				(arc
					(start 259.430266 -248.521474)
					(mid 259.445145 -248.557395)
					(end 259.481066 -248.572274)
				)
				(arc
					(start 260.880606 -248.572274)
					(mid 260.916527 -248.557395)
					(end 260.931406 -248.521474)
				)
				(arc
					(start 260.931406 -248.112534)
					(mid 260.916527 -248.076613)
					(end 260.880606 -248.061734)
				)
				(arc
					(start 259.481066 -248.061734)
					(mid 259.445145 -248.076613)
					(end 259.430266 -248.112534)
				)
			)
		)
	)
	(zone
		(layers "In1.Cu" "In2.Cu")
		(hatch none 0.5)
		(connect_pads
			(clearance 0)
		)
		(min_thickness 0.25)
		(keepout
			(tracks not_allowed)
			(vias allowed)
			(pads allowed)
			(copperpour not_allowed)
			(footprints allowed)
		)
		(placement
			(enabled no)
			(sheetname "")
		)
		(fill yes
			(thermal_gap 0.5)
			(thermal_bridge_width 0.5)
			(island_removal_mode 0)
		)
		(polygon
			(pts
				(arc
					(start 425.190666 -234.921298)
					(mid 425.205545 -234.957219)
					(end 425.241466 -234.972098)
				)
				(arc
					(start 426.641006 -234.972098)
					(mid 426.676927 -234.957219)
					(end 426.691806 -234.921298)
				)
				(arc
					(start 426.691806 -234.512358)
					(mid 426.676927 -234.476437)
					(end 426.641006 -234.461558)
				)
				(arc
					(start 425.241466 -234.461558)
					(mid 425.205545 -234.476437)
					(end 425.190666 -234.512358)
				)
			)
		)
	)
	(zone
		(layers "In1.Cu" "In2.Cu")
		(hatch none 0.5)
		(connect_pads
			(clearance 0)
		)
		(min_thickness 0.25)
		(keepout
			(tracks not_allowed)
			(vias allowed)
			(pads allowed)
			(copperpour not_allowed)
			(footprints allowed)
		)
		(placement
			(enabled no)
			(sheetname "")
		)
		(fill yes
			(thermal_gap 0.5)
			(thermal_bridge_width 0.5)
			(island_removal_mode 0)
		)
		(polygon
			(pts
				(arc
					(start 199.881998 -223.871536)
					(mid 199.896877 -223.907457)
					(end 199.932798 -223.922336)
				)
				(arc
					(start 201.332338 -223.922336)
					(mid 201.368259 -223.907457)
					(end 201.383138 -223.871536)
				)
				(arc
					(start 201.383138 -223.462596)
					(mid 201.368259 -223.426675)
					(end 201.332338 -223.411796)
				)
				(arc
					(start 199.932798 -223.411796)
					(mid 199.896877 -223.426675)
					(end 199.881998 -223.462596)
				)
			)
		)
	)
	(zone
		(layers "In1.Cu" "In2.Cu")
		(hatch none 0.5)
		(connect_pads
			(clearance 0)
		)
		(min_thickness 0.25)
		(keepout
			(tracks not_allowed)
			(vias allowed)
			(pads allowed)
			(copperpour not_allowed)
			(footprints allowed)
		)
		(placement
			(enabled no)
			(sheetname "")
		)
		(fill yes
			(thermal_gap 0.5)
			(thermal_bridge_width 0.5)
			(island_removal_mode 0)
		)
		(polygon
			(pts
				(arc
					(start 413.546798 -316.521338)
					(mid 413.561677 -316.557259)
					(end 413.597598 -316.572138)
				)
				(arc
					(start 414.997138 -316.572138)
					(mid 415.033059 -316.557259)
					(end 415.047938 -316.521338)
				)
				(arc
					(start 415.047938 -316.112398)
					(mid 415.033059 -316.076477)
					(end 414.997138 -316.061598)
				)
				(arc
					(start 413.597598 -316.061598)
					(mid 413.561677 -316.076477)
					(end 413.546798 -316.112398)
				)
			)
		)
	)
	(zone
		(layers "In1.Cu" "In2.Cu")
		(hatch none 0.5)
		(connect_pads
			(clearance 0)
		)
		(min_thickness 0.25)
		(keepout
			(tracks not_allowed)
			(vias allowed)
			(pads allowed)
			(copperpour not_allowed)
			(footprints allowed)
		)
		(placement
			(enabled no)
			(sheetname "")
		)
		(fill yes
			(thermal_gap 0.5)
			(thermal_bridge_width 0.5)
			(island_removal_mode 0)
		)
		(polygon
			(pts
				(arc
					(start 282.061666 -283.371544)
					(mid 282.076545 -283.407465)
					(end 282.112466 -283.422344)
				)
				(arc
					(start 283.512006 -283.422344)
					(mid 283.547927 -283.407465)
					(end 283.562806 -283.371544)
				)
				(arc
					(start 283.562806 -282.962604)
					(mid 283.547927 -282.926683)
					(end 283.512006 -282.911804)
				)
				(arc
					(start 282.112466 -282.911804)
					(mid 282.076545 -282.926683)
					(end 282.061666 -282.962604)
				)
			)
		)
	)
	(zone
		(layers "In1.Cu" "In2.Cu")
		(hatch none 0.5)
		(connect_pads
			(clearance 0)
		)
		(min_thickness 0.25)
		(keepout
			(tracks not_allowed)
			(vias allowed)
			(pads allowed)
			(copperpour not_allowed)
			(footprints allowed)
		)
		(placement
			(enabled no)
			(sheetname "")
		)
		(fill yes
			(thermal_gap 0.5)
			(thermal_bridge_width 0.5)
			(island_removal_mode 0)
		)
		(polygon
			(pts
				(arc
					(start 293.049198 -202.621388)
					(mid 293.064077 -202.657309)
					(end 293.099998 -202.672188)
				)
				(arc
					(start 294.499538 -202.672188)
					(mid 294.535459 -202.657309)
					(end 294.550338 -202.621388)
				)
				(arc
					(start 294.550338 -202.212448)
					(mid 294.535459 -202.176527)
					(end 294.499538 -202.161648)
				)
				(arc
					(start 293.099998 -202.161648)
					(mid 293.064077 -202.176527)
					(end 293.049198 -202.212448)
				)
			)
		)
	)
	(zone
		(layers "In1.Cu" "In2.Cu")
		(hatch none 0.5)
		(connect_pads
			(clearance 0)
		)
		(min_thickness 0.25)
		(keepout
			(tracks not_allowed)
			(vias allowed)
			(pads allowed)
			(copperpour not_allowed)
			(footprints allowed)
		)
		(placement
			(enabled no)
			(sheetname "")
		)
		(fill yes
			(thermal_gap 0.5)
			(thermal_bridge_width 0.5)
			(island_removal_mode 0)
		)
		(polygon
			(pts
				(arc
					(start 458.809598 -200.071482)
					(mid 458.824477 -200.107403)
					(end 458.860398 -200.122282)
				)
				(arc
					(start 460.259938 -200.122282)
					(mid 460.295859 -200.107403)
					(end 460.310738 -200.071482)
				)
				(arc
					(start 460.310738 -199.662542)
					(mid 460.295859 -199.626621)
					(end 460.259938 -199.611742)
				)
				(arc
					(start 458.860398 -199.611742)
					(mid 458.824477 -199.626621)
					(end 458.809598 -199.662542)
				)
			)
		)
	)
	(zone
		(layers "In1.Cu" "In2.Cu")
		(hatch none 0.5)
		(connect_pads
			(clearance 0)
		)
		(min_thickness 0.25)
		(keepout
			(tracks not_allowed)
			(vias allowed)
			(pads allowed)
			(copperpour not_allowed)
			(footprints allowed)
		)
		(placement
			(enabled no)
			(sheetname "")
		)
		(fill yes
			(thermal_gap 0.5)
			(thermal_bridge_width 0.5)
			(island_removal_mode 0)
		)
		(polygon
			(pts
				(arc
					(start 304.693066 -268.921484)
					(mid 304.707945 -268.957405)
					(end 304.743866 -268.972284)
				)
				(arc
					(start 306.143406 -268.972284)
					(mid 306.179327 -268.957405)
					(end 306.194206 -268.921484)
				)
				(arc
					(start 306.194206 -268.512544)
					(mid 306.179327 -268.476623)
					(end 306.143406 -268.461744)
				)
				(arc
					(start 304.743866 -268.461744)
					(mid 304.707945 -268.476623)
					(end 304.693066 -268.512544)
				)
			)
		)
	)
	(zone
		(layers "In1.Cu" "In2.Cu")
		(hatch none 0.5)
		(connect_pads
			(clearance 0)
		)
		(min_thickness 0.25)
		(keepout
			(tracks not_allowed)
			(vias allowed)
			(pads allowed)
			(copperpour not_allowed)
			(footprints allowed)
		)
		(placement
			(enabled no)
			(sheetname "")
		)
		(fill yes
			(thermal_gap 0.5)
			(thermal_bridge_width 0.5)
			(island_removal_mode 0)
		)
		(polygon
			(pts
				(arc
					(start 173.15053 -240.021364)
					(mid 173.165409 -240.057285)
					(end 173.20133 -240.072164)
				)
				(arc
					(start 174.60087 -240.072164)
					(mid 174.636791 -240.057285)
					(end 174.65167 -240.021364)
				)
				(arc
					(start 174.65167 -239.612424)
					(mid 174.636791 -239.576503)
					(end 174.60087 -239.561624)
				)
				(arc
					(start 173.20133 -239.561624)
					(mid 173.165409 -239.576503)
					(end 173.15053 -239.612424)
				)
			)
		)
	)
	(zone
		(layers "In1.Cu" "In2.Cu")
		(hatch none 0.5)
		(connect_pads
			(clearance 0)
		)
		(min_thickness 0.25)
		(keepout
			(tracks not_allowed)
			(vias allowed)
			(pads allowed)
			(copperpour not_allowed)
			(footprints allowed)
		)
		(placement
			(enabled no)
			(sheetname "")
		)
		(fill yes
			(thermal_gap 0.5)
			(thermal_bridge_width 0.5)
			(island_removal_mode 0)
		)
		(polygon
			(pts
				(arc
					(start 458.809598 -247.671336)
					(mid 458.824477 -247.707257)
					(end 458.860398 -247.722136)
				)
				(arc
					(start 460.259938 -247.722136)
					(mid 460.295859 -247.707257)
					(end 460.310738 -247.671336)
				)
				(arc
					(start 460.310738 -247.262396)
					(mid 460.295859 -247.226475)
					(end 460.259938 -247.211596)
				)
				(arc
					(start 458.860398 -247.211596)
					(mid 458.824477 -247.226475)
					(end 458.809598 -247.262396)
				)
			)
		)
	)
	(zone
		(layers "In1.Cu" "In2.Cu")
		(hatch none 0.5)
		(connect_pads
			(clearance 0)
		)
		(min_thickness 0.25)
		(keepout
			(tracks not_allowed)
			(vias allowed)
			(pads allowed)
			(copperpour not_allowed)
			(footprints allowed)
		)
		(placement
			(enabled no)
			(sheetname "")
		)
		(fill yes
			(thermal_gap 0.5)
			(thermal_bridge_width 0.5)
			(island_removal_mode 0)
		)
		(polygon
			(pts
				(arc
					(start 169.706798 -265.52144)
					(mid 169.721677 -265.557361)
					(end 169.757598 -265.57224)
				)
				(arc
					(start 171.157138 -265.57224)
					(mid 171.193059 -265.557361)
					(end 171.207938 -265.52144)
				)
				(arc
					(start 171.207938 -265.1125)
					(mid 171.193059 -265.076579)
					(end 171.157138 -265.0617)
				)
				(arc
					(start 169.757598 -265.0617)
					(mid 169.721677 -265.076579)
					(end 169.706798 -265.1125)
				)
			)
		)
	)
	(zone
		(layers "In1.Cu" "In2.Cu")
		(hatch none 0.5)
		(connect_pads
			(clearance 0)
		)
		(min_thickness 0.25)
		(keepout
			(tracks not_allowed)
			(vias allowed)
			(pads allowed)
			(copperpour not_allowed)
			(footprints allowed)
		)
		(placement
			(enabled no)
			(sheetname "")
		)
		(fill yes
			(thermal_gap 0.5)
			(thermal_bridge_width 0.5)
			(island_removal_mode 0)
		)
		(polygon
			(pts
				(arc
					(start 214.969598 -228.121464)
					(mid 214.984477 -228.157385)
					(end 215.020398 -228.172264)
				)
				(arc
					(start 216.419938 -228.172264)
					(mid 216.455859 -228.157385)
					(end 216.470738 -228.121464)
				)
				(arc
					(start 216.470738 -227.712524)
					(mid 216.455859 -227.676603)
					(end 216.419938 -227.661724)
				)
				(arc
					(start 215.020398 -227.661724)
					(mid 214.984477 -227.676603)
					(end 214.969598 -227.712524)
				)
			)
		)
	)
	(zone
		(layers "In1.Cu" "In2.Cu")
		(hatch none 0.5)
		(connect_pads
			(clearance 0)
		)
		(min_thickness 0.25)
		(keepout
			(tracks not_allowed)
			(vias allowed)
			(pads allowed)
			(copperpour not_allowed)
			(footprints allowed)
		)
		(placement
			(enabled no)
			(sheetname "")
		)
		(fill yes
			(thermal_gap 0.5)
			(thermal_bridge_width 0.5)
			(island_removal_mode 0)
		)
		(polygon
			(pts
				(arc
					(start 432.734466 -302.071532)
					(mid 432.749345 -302.107453)
					(end 432.785266 -302.122332)
				)
				(arc
					(start 434.184806 -302.122332)
					(mid 434.220727 -302.107453)
					(end 434.235606 -302.071532)
				)
				(arc
					(start 434.235606 -301.662592)
					(mid 434.220727 -301.626671)
					(end 434.184806 -301.611792)
				)
				(arc
					(start 432.785266 -301.611792)
					(mid 432.749345 -301.626671)
					(end 432.734466 -301.662592)
				)
			)
		)
	)
	(zone
		(layers "In1.Cu" "In2.Cu")
		(hatch none 0.5)
		(connect_pads
			(clearance 0)
		)
		(min_thickness 0.25)
		(keepout
			(tracks not_allowed)
			(vias allowed)
			(pads allowed)
			(copperpour not_allowed)
			(footprints allowed)
		)
		(placement
			(enabled no)
			(sheetname "")
		)
		(fill yes
			(thermal_gap 0.5)
			(thermal_bridge_width 0.5)
			(island_removal_mode 0)
		)
		(polygon
			(pts
				(arc
					(start 297.149266 -267.221462)
					(mid 297.164145 -267.257383)
					(end 297.200066 -267.272262)
				)
				(arc
					(start 298.599606 -267.272262)
					(mid 298.635527 -267.257383)
					(end 298.650406 -267.221462)
				)
				(arc
					(start 298.650406 -266.812522)
					(mid 298.635527 -266.776601)
					(end 298.599606 -266.761722)
				)
				(arc
					(start 297.200066 -266.761722)
					(mid 297.164145 -266.776601)
					(end 297.149266 -266.812522)
				)
			)
		)
	)
	(zone
		(layers "In1.Cu" "In2.Cu")
		(hatch none 0.5)
		(connect_pads
			(clearance 0)
		)
		(min_thickness 0.25)
		(keepout
			(tracks not_allowed)
			(vias allowed)
			(pads allowed)
			(copperpour not_allowed)
			(footprints allowed)
		)
		(placement
			(enabled no)
			(sheetname "")
		)
		(fill yes
			(thermal_gap 0.5)
			(thermal_bridge_width 0.5)
			(island_removal_mode 0)
		)
		(polygon
			(pts
				(arc
					(start 432.734466 -265.52144)
					(mid 432.749345 -265.557361)
					(end 432.785266 -265.57224)
				)
				(arc
					(start 434.184806 -265.57224)
					(mid 434.220727 -265.557361)
					(end 434.235606 -265.52144)
				)
				(arc
					(start 434.235606 -265.1125)
					(mid 434.220727 -265.076579)
					(end 434.184806 -265.0617)
				)
				(arc
					(start 432.785266 -265.0617)
					(mid 432.749345 -265.076579)
					(end 432.734466 -265.1125)
				)
			)
		)
	)
	(zone
		(layers "In1.Cu" "In2.Cu")
		(hatch none 0.5)
		(connect_pads
			(clearance 0)
		)
		(min_thickness 0.25)
		(keepout
			(tracks not_allowed)
			(vias allowed)
			(pads allowed)
			(copperpour not_allowed)
			(footprints allowed)
		)
		(placement
			(enabled no)
			(sheetname "")
		)
		(fill yes
			(thermal_gap 0.5)
			(thermal_bridge_width 0.5)
			(island_removal_mode 0)
		)
		(polygon
			(pts
				(arc
					(start 49.209198 -231.521508)
					(mid 49.224077 -231.557429)
					(end 49.259998 -231.572308)
				)
				(arc
					(start 50.659538 -231.572308)
					(mid 50.695459 -231.557429)
					(end 50.710338 -231.521508)
				)
				(arc
					(start 50.710338 -231.112568)
					(mid 50.695459 -231.076647)
					(end 50.659538 -231.061768)
				)
				(arc
					(start 49.259998 -231.061768)
					(mid 49.224077 -231.076647)
					(end 49.209198 -231.112568)
				)
			)
		)
	)
	(zone
		(layers "In1.Cu" "In2.Cu")
		(hatch none 0.5)
		(connect_pads
			(clearance 0)
		)
		(min_thickness 0.25)
		(keepout
			(tracks not_allowed)
			(vias allowed)
			(pads allowed)
			(copperpour not_allowed)
			(footprints allowed)
		)
		(placement
			(enabled no)
			(sheetname "")
		)
		(fill yes
			(thermal_gap 0.5)
			(thermal_bridge_width 0.5)
			(island_removal_mode 0)
		)
		(polygon
			(pts
				(arc
					(start 214.969598 -233.22153)
					(mid 214.984477 -233.257451)
					(end 215.020398 -233.27233)
				)
				(arc
					(start 216.419938 -233.27233)
					(mid 216.455859 -233.257451)
					(end 216.470738 -233.22153)
				)
				(arc
					(start 216.470738 -232.81259)
					(mid 216.455859 -232.776669)
					(end 216.419938 -232.76179)
				)
				(arc
					(start 215.020398 -232.76179)
					(mid 214.984477 -232.776669)
					(end 214.969598 -232.81259)
				)
			)
		)
	)
	(zone
		(layers "In1.Cu" "In2.Cu")
		(hatch none 0.5)
		(connect_pads
			(clearance 0)
		)
		(min_thickness 0.25)
		(keepout
			(tracks not_allowed)
			(vias allowed)
			(pads allowed)
			(copperpour not_allowed)
			(footprints allowed)
		)
		(placement
			(enabled no)
			(sheetname "")
		)
		(fill yes
			(thermal_gap 0.5)
			(thermal_bridge_width 0.5)
			(island_removal_mode 0)
		)
		(polygon
			(pts
				(arc
					(start 188.23813 -293.571422)
					(mid 188.253009 -293.607343)
					(end 188.28893 -293.622222)
				)
				(arc
					(start 189.68847 -293.622222)
					(mid 189.724391 -293.607343)
					(end 189.73927 -293.571422)
				)
				(arc
					(start 189.73927 -293.162482)
					(mid 189.724391 -293.126561)
					(end 189.68847 -293.111682)
				)
				(arc
					(start 188.28893 -293.111682)
					(mid 188.253009 -293.126561)
					(end 188.23813 -293.162482)
				)
			)
		)
	)
	(zone
		(layers "In1.Cu" "In2.Cu")
		(hatch none 0.5)
		(connect_pads
			(clearance 0)
		)
		(min_thickness 0.25)
		(keepout
			(tracks not_allowed)
			(vias allowed)
			(pads allowed)
			(copperpour not_allowed)
			(footprints allowed)
		)
		(placement
			(enabled no)
			(sheetname "")
		)
		(fill yes
			(thermal_gap 0.5)
			(thermal_bridge_width 0.5)
			(island_removal_mode 0)
		)
		(polygon
			(pts
				(arc
					(start 22.47773 -313.121294)
					(mid 22.492609 -313.157215)
					(end 22.52853 -313.172094)
				)
				(arc
					(start 23.92807 -313.172094)
					(mid 23.963991 -313.157215)
					(end 23.97887 -313.121294)
				)
				(arc
					(start 23.97887 -312.712354)
					(mid 23.963991 -312.676433)
					(end 23.92807 -312.661554)
				)
				(arc
					(start 22.52853 -312.661554)
					(mid 22.492609 -312.676433)
					(end 22.47773 -312.712354)
				)
			)
		)
	)
	(zone
		(layers "In1.Cu" "In2.Cu")
		(hatch none 0.5)
		(connect_pads
			(clearance 0)
		)
		(min_thickness 0.25)
		(keepout
			(tracks not_allowed)
			(vias allowed)
			(pads allowed)
			(copperpour not_allowed)
			(footprints allowed)
		)
		(placement
			(enabled no)
			(sheetname "")
		)
		(fill yes
			(thermal_gap 0.5)
			(thermal_bridge_width 0.5)
			(island_removal_mode 0)
		)
		(polygon
			(pts
				(arc
					(start 199.881998 -214.521542)
					(mid 199.896877 -214.557463)
					(end 199.932798 -214.572342)
				)
				(arc
					(start 201.332338 -214.572342)
					(mid 201.368259 -214.557463)
					(end 201.383138 -214.521542)
				)
				(arc
					(start 201.383138 -214.112602)
					(mid 201.368259 -214.076681)
					(end 201.332338 -214.061802)
				)
				(arc
					(start 199.932798 -214.061802)
					(mid 199.896877 -214.076681)
					(end 199.881998 -214.112602)
				)
			)
		)
	)
	(zone
		(layers "In1.Cu" "In2.Cu")
		(hatch none 0.5)
		(connect_pads
			(clearance 0)
		)
		(min_thickness 0.25)
		(keepout
			(tracks not_allowed)
			(vias allowed)
			(pads allowed)
			(copperpour not_allowed)
			(footprints allowed)
		)
		(placement
			(enabled no)
			(sheetname "")
		)
		(fill yes
			(thermal_gap 0.5)
			(thermal_bridge_width 0.5)
			(island_removal_mode 0)
		)
		(polygon
			(pts
				(arc
					(start 169.706798 -237.471458)
					(mid 169.721677 -237.507379)
					(end 169.757598 -237.522258)
				)
				(arc
					(start 171.157138 -237.522258)
					(mid 171.193059 -237.507379)
					(end 171.207938 -237.471458)
				)
				(arc
					(start 171.207938 -237.062518)
					(mid 171.193059 -237.026597)
					(end 171.157138 -237.011718)
				)
				(arc
					(start 169.757598 -237.011718)
					(mid 169.721677 -237.026597)
					(end 169.706798 -237.062518)
				)
			)
		)
	)
	(zone
		(layers "In1.Cu" "In2.Cu")
		(hatch none 0.5)
		(connect_pads
			(clearance 0)
		)
		(min_thickness 0.25)
		(keepout
			(tracks not_allowed)
			(vias allowed)
			(pads allowed)
			(copperpour not_allowed)
			(footprints allowed)
		)
		(placement
			(enabled no)
			(sheetname "")
		)
		(fill yes
			(thermal_gap 0.5)
			(thermal_bridge_width 0.5)
			(island_removal_mode 0)
		)
		(polygon
			(pts
				(arc
					(start 203.32573 -266.371324)
					(mid 203.340609 -266.407245)
					(end 203.37653 -266.422124)
				)
				(arc
					(start 204.77607 -266.422124)
					(mid 204.811991 -266.407245)
					(end 204.82687 -266.371324)
				)
				(arc
					(start 204.82687 -265.962384)
					(mid 204.811991 -265.926463)
					(end 204.77607 -265.911584)
				)
				(arc
					(start 203.37653 -265.911584)
					(mid 203.340609 -265.926463)
					(end 203.32573 -265.962384)
				)
			)
		)
	)
	(zone
		(layers "In1.Cu" "In2.Cu")
		(hatch none 0.5)
		(connect_pads
			(clearance 0)
		)
		(min_thickness 0.25)
		(keepout
			(tracks not_allowed)
			(vias allowed)
			(pads allowed)
			(copperpour not_allowed)
			(footprints allowed)
		)
		(placement
			(enabled no)
			(sheetname "")
		)
		(fill yes
			(thermal_gap 0.5)
			(thermal_bridge_width 0.5)
			(island_removal_mode 0)
		)
		(polygon
			(pts
				(arc
					(start 210.86953 -261.271512)
					(mid 210.884409 -261.307433)
					(end 210.92033 -261.322312)
				)
				(arc
					(start 212.31987 -261.322312)
					(mid 212.355791 -261.307433)
					(end 212.37067 -261.271512)
				)
				(arc
					(start 212.37067 -260.862572)
					(mid 212.355791 -260.826651)
					(end 212.31987 -260.811772)
				)
				(arc
					(start 210.92033 -260.811772)
					(mid 210.884409 -260.826651)
					(end 210.86953 -260.862572)
				)
			)
		)
	)
	(zone
		(layers "In1.Cu" "In2.Cu")
		(hatch none 0.5)
		(connect_pads
			(clearance 0)
		)
		(min_thickness 0.25)
		(keepout
			(tracks not_allowed)
			(vias allowed)
			(pads allowed)
			(copperpour not_allowed)
			(footprints allowed)
		)
		(placement
			(enabled no)
			(sheetname "")
		)
		(fill yes
			(thermal_gap 0.5)
			(thermal_bridge_width 0.5)
			(island_removal_mode 0)
		)
		(polygon
			(pts
				(arc
					(start 417.646866 -302.921416)
					(mid 417.661745 -302.957337)
					(end 417.697666 -302.972216)
				)
				(arc
					(start 419.097206 -302.972216)
					(mid 419.133127 -302.957337)
					(end 419.148006 -302.921416)
				)
				(arc
					(start 419.148006 -302.512476)
					(mid 419.133127 -302.476555)
					(end 419.097206 -302.461676)
				)
				(arc
					(start 417.697666 -302.461676)
					(mid 417.661745 -302.476555)
					(end 417.646866 -302.512476)
				)
			)
		)
	)
	(zone
		(layers "In1.Cu" "In2.Cu")
		(hatch none 0.5)
		(connect_pads
			(clearance 0)
		)
		(min_thickness 0.25)
		(keepout
			(tracks not_allowed)
			(vias allowed)
			(pads allowed)
			(copperpour not_allowed)
			(footprints allowed)
		)
		(placement
			(enabled no)
			(sheetname "")
		)
		(fill yes
			(thermal_gap 0.5)
			(thermal_bridge_width 0.5)
			(island_removal_mode 0)
		)
		(polygon
			(pts
				(arc
					(start 443.721998 -279.121362)
					(mid 443.736877 -279.157283)
					(end 443.772798 -279.172162)
				)
				(arc
					(start 445.172338 -279.172162)
					(mid 445.208259 -279.157283)
					(end 445.223138 -279.121362)
				)
				(arc
					(start 445.223138 -278.712422)
					(mid 445.208259 -278.676501)
					(end 445.172338 -278.661622)
				)
				(arc
					(start 443.772798 -278.661622)
					(mid 443.736877 -278.676501)
					(end 443.721998 -278.712422)
				)
			)
		)
	)
	(zone
		(layers "In1.Cu" "In2.Cu")
		(hatch none 0.5)
		(connect_pads
			(clearance 0)
		)
		(min_thickness 0.25)
		(keepout
			(tracks not_allowed)
			(vias allowed)
			(pads allowed)
			(copperpour not_allowed)
			(footprints allowed)
		)
		(placement
			(enabled no)
			(sheetname "")
		)
		(fill yes
			(thermal_gap 0.5)
			(thermal_bridge_width 0.5)
			(island_removal_mode 0)
		)
		(polygon
			(pts
				(arc
					(start 37.56533 -238.321342)
					(mid 37.580209 -238.357263)
					(end 37.61613 -238.372142)
				)
				(arc
					(start 39.01567 -238.372142)
					(mid 39.051591 -238.357263)
					(end 39.06647 -238.321342)
				)
				(arc
					(start 39.06647 -237.912402)
					(mid 39.051591 -237.876481)
					(end 39.01567 -237.861602)
				)
				(arc
					(start 37.61613 -237.861602)
					(mid 37.580209 -237.876481)
					(end 37.56533 -237.912402)
				)
			)
		)
	)
	(zone
		(layers "In1.Cu" "In2.Cu")
		(hatch none 0.5)
		(connect_pads
			(clearance 0)
		)
		(min_thickness 0.25)
		(keepout
			(tracks not_allowed)
			(vias allowed)
			(pads allowed)
			(copperpour not_allowed)
			(footprints allowed)
		)
		(placement
			(enabled no)
			(sheetname "")
		)
		(fill yes
			(thermal_gap 0.5)
			(thermal_bridge_width 0.5)
			(island_removal_mode 0)
		)
		(polygon
			(pts
				(arc
					(start 195.78193 -308.871366)
					(mid 195.796809 -308.907287)
					(end 195.83273 -308.922166)
				)
				(arc
					(start 197.23227 -308.922166)
					(mid 197.268191 -308.907287)
					(end 197.28307 -308.871366)
				)
				(arc
					(start 197.28307 -308.462426)
					(mid 197.268191 -308.426505)
					(end 197.23227 -308.411626)
				)
				(arc
					(start 195.83273 -308.411626)
					(mid 195.796809 -308.426505)
					(end 195.78193 -308.462426)
				)
			)
		)
	)
	(zone
		(layers "In1.Cu" "In2.Cu")
		(hatch none 0.5)
		(connect_pads
			(clearance 0)
		)
		(min_thickness 0.25)
		(keepout
			(tracks not_allowed)
			(vias allowed)
			(pads allowed)
			(copperpour not_allowed)
			(footprints allowed)
		)
		(placement
			(enabled no)
			(sheetname "")
		)
		(fill yes
			(thermal_gap 0.5)
			(thermal_bridge_width 0.5)
			(island_removal_mode 0)
		)
		(polygon
			(pts
				(arc
					(start 312.236866 -298.671488)
					(mid 312.251745 -298.707409)
					(end 312.287666 -298.722288)
				)
				(arc
					(start 313.687206 -298.722288)
					(mid 313.723127 -298.707409)
					(end 313.738006 -298.671488)
				)
				(arc
					(start 313.738006 -298.262548)
					(mid 313.723127 -298.226627)
					(end 313.687206 -298.211748)
				)
				(arc
					(start 312.287666 -298.211748)
					(mid 312.251745 -298.226627)
					(end 312.236866 -298.262548)
				)
			)
		)
	)
	(zone
		(layers "In1.Cu" "In2.Cu")
		(hatch none 0.5)
		(connect_pads
			(clearance 0)
		)
		(min_thickness 0.25)
		(keepout
			(tracks not_allowed)
			(vias allowed)
			(pads allowed)
			(copperpour not_allowed)
			(footprints allowed)
		)
		(placement
			(enabled no)
			(sheetname "")
		)
		(fill yes
			(thermal_gap 0.5)
			(thermal_bridge_width 0.5)
			(island_removal_mode 0)
		)
		(polygon
			(pts
				(arc
					(start 162.162998 -217.921332)
					(mid 162.177877 -217.957253)
					(end 162.213798 -217.972132)
				)
				(arc
					(start 163.613338 -217.972132)
					(mid 163.649259 -217.957253)
					(end 163.664138 -217.921332)
				)
				(arc
					(start 163.664138 -217.512392)
					(mid 163.649259 -217.476471)
					(end 163.613338 -217.461592)
				)
				(arc
					(start 162.213798 -217.461592)
					(mid 162.177877 -217.476471)
					(end 162.162998 -217.512392)
				)
			)
		)
	)
	(zone
		(layers "In1.Cu" "In2.Cu")
		(hatch none 0.5)
		(connect_pads
			(clearance 0)
		)
		(min_thickness 0.25)
		(keepout
			(tracks not_allowed)
			(vias allowed)
			(pads allowed)
			(copperpour not_allowed)
			(footprints allowed)
		)
		(placement
			(enabled no)
			(sheetname "")
		)
		(fill yes
			(thermal_gap 0.5)
			(thermal_bridge_width 0.5)
			(island_removal_mode 0)
		)
		(polygon
			(pts
				(arc
					(start 19.033998 -311.421526)
					(mid 19.048877 -311.457447)
					(end 19.084798 -311.472326)
				)
				(arc
					(start 20.484338 -311.472326)
					(mid 20.520259 -311.457447)
					(end 20.535138 -311.421526)
				)
				(arc
					(start 20.535138 -311.012586)
					(mid 20.520259 -310.976665)
					(end 20.484338 -310.961786)
				)
				(arc
					(start 19.084798 -310.961786)
					(mid 19.048877 -310.976665)
					(end 19.033998 -311.012586)
				)
			)
		)
	)
	(zone
		(layers "In1.Cu" "In2.Cu")
		(hatch none 0.5)
		(connect_pads
			(clearance 0)
		)
		(min_thickness 0.25)
		(keepout
			(tracks not_allowed)
			(vias allowed)
			(pads allowed)
			(copperpour not_allowed)
			(footprints allowed)
		)
		(placement
			(enabled no)
			(sheetname "")
		)
		(fill yes
			(thermal_gap 0.5)
			(thermal_bridge_width 0.5)
			(island_removal_mode 0)
		)
		(polygon
			(pts
				(arc
					(start 410.103066 -217.921332)
					(mid 410.117945 -217.957253)
					(end 410.153866 -217.972132)
				)
				(arc
					(start 411.553406 -217.972132)
					(mid 411.589327 -217.957253)
					(end 411.604206 -217.921332)
				)
				(arc
					(start 411.604206 -217.512392)
					(mid 411.589327 -217.476471)
					(end 411.553406 -217.461592)
				)
				(arc
					(start 410.153866 -217.461592)
					(mid 410.117945 -217.476471)
					(end 410.103066 -217.512392)
				)
			)
		)
	)
	(zone
		(layers "In1.Cu" "In2.Cu")
		(hatch none 0.5)
		(connect_pads
			(clearance 0)
		)
		(min_thickness 0.25)
		(keepout
			(tracks not_allowed)
			(vias allowed)
			(pads allowed)
			(copperpour not_allowed)
			(footprints allowed)
		)
		(placement
			(enabled no)
			(sheetname "")
		)
		(fill yes
			(thermal_gap 0.5)
			(thermal_bridge_width 0.5)
			(island_removal_mode 0)
		)
		(polygon
			(pts
				(arc
					(start 413.546798 -275.721318)
					(mid 413.561677 -275.757239)
					(end 413.597598 -275.772118)
				)
				(arc
					(start 414.997138 -275.772118)
					(mid 415.033059 -275.757239)
					(end 415.047938 -275.721318)
				)
				(arc
					(start 415.047938 -275.312378)
					(mid 415.033059 -275.276457)
					(end 414.997138 -275.261578)
				)
				(arc
					(start 413.597598 -275.261578)
					(mid 413.561677 -275.276457)
					(end 413.546798 -275.312378)
				)
			)
		)
	)
	(zone
		(layers "In1.Cu" "In2.Cu")
		(hatch none 0.5)
		(connect_pads
			(clearance 0)
		)
		(min_thickness 0.25)
		(keepout
			(tracks not_allowed)
			(vias allowed)
			(pads allowed)
			(copperpour not_allowed)
			(footprints allowed)
		)
		(placement
			(enabled no)
			(sheetname "")
		)
		(fill yes
			(thermal_gap 0.5)
			(thermal_bridge_width 0.5)
			(island_removal_mode 0)
		)
		(polygon
			(pts
				(arc
					(start 436.178198 -213.671404)
					(mid 436.193077 -213.707325)
					(end 436.228998 -213.722204)
				)
				(arc
					(start 437.628538 -213.722204)
					(mid 437.664459 -213.707325)
					(end 437.679338 -213.671404)
				)
				(arc
					(start 437.679338 -213.262464)
					(mid 437.664459 -213.226543)
					(end 437.628538 -213.211664)
				)
				(arc
					(start 436.228998 -213.211664)
					(mid 436.193077 -213.226543)
					(end 436.178198 -213.262464)
				)
			)
		)
	)
	(zone
		(layers "In1.Cu" "In2.Cu")
		(hatch none 0.5)
		(connect_pads
			(clearance 0)
		)
		(min_thickness 0.25)
		(keepout
			(tracks not_allowed)
			(vias allowed)
			(pads allowed)
			(copperpour not_allowed)
			(footprints allowed)
		)
		(placement
			(enabled no)
			(sheetname "")
		)
		(fill yes
			(thermal_gap 0.5)
			(thermal_bridge_width 0.5)
			(island_removal_mode 0)
		)
		(polygon
			(pts
				(arc
					(start 184.794398 -304.621438)
					(mid 184.809277 -304.657359)
					(end 184.845198 -304.672238)
				)
				(arc
					(start 186.244738 -304.672238)
					(mid 186.280659 -304.657359)
					(end 186.295538 -304.621438)
				)
				(arc
					(start 186.295538 -304.212498)
					(mid 186.280659 -304.176577)
					(end 186.244738 -304.161698)
				)
				(arc
					(start 184.845198 -304.161698)
					(mid 184.809277 -304.176577)
					(end 184.794398 -304.212498)
				)
			)
		)
	)
	(zone
		(layers "In1.Cu" "In2.Cu")
		(hatch none 0.5)
		(connect_pads
			(clearance 0)
		)
		(min_thickness 0.25)
		(keepout
			(tracks not_allowed)
			(vias allowed)
			(pads allowed)
			(copperpour not_allowed)
			(footprints allowed)
		)
		(placement
			(enabled no)
			(sheetname "")
		)
		(fill yes
			(thermal_gap 0.5)
			(thermal_bridge_width 0.5)
			(island_removal_mode 0)
		)
		(polygon
			(pts
				(arc
					(start 262.873998 -224.72142)
					(mid 262.888877 -224.757341)
					(end 262.924798 -224.77222)
				)
				(arc
					(start 264.324338 -224.77222)
					(mid 264.360259 -224.757341)
					(end 264.375138 -224.72142)
				)
				(arc
					(start 264.375138 -224.31248)
					(mid 264.360259 -224.276559)
					(end 264.324338 -224.26168)
				)
				(arc
					(start 262.924798 -224.26168)
					(mid 262.888877 -224.276559)
					(end 262.873998 -224.31248)
				)
			)
		)
	)
	(zone
		(layers "In1.Cu" "In2.Cu")
		(hatch none 0.5)
		(connect_pads
			(clearance 0)
		)
		(min_thickness 0.25)
		(keepout
			(tracks not_allowed)
			(vias allowed)
			(pads allowed)
			(copperpour not_allowed)
			(footprints allowed)
		)
		(placement
			(enabled no)
			(sheetname "")
		)
		(fill yes
			(thermal_gap 0.5)
			(thermal_bridge_width 0.5)
			(island_removal_mode 0)
		)
		(polygon
			(pts
				(arc
					(start 255.330198 -264.671302)
					(mid 255.345077 -264.707223)
					(end 255.380998 -264.722102)
				)
				(arc
					(start 256.780538 -264.722102)
					(mid 256.816459 -264.707223)
					(end 256.831338 -264.671302)
				)
				(arc
					(start 256.831338 -264.262362)
					(mid 256.816459 -264.226441)
					(end 256.780538 -264.211562)
				)
				(arc
					(start 255.380998 -264.211562)
					(mid 255.345077 -264.226441)
					(end 255.330198 -264.262362)
				)
			)
		)
	)
	(zone
		(layers "In1.Cu" "In2.Cu")
		(hatch none 0.5)
		(connect_pads
			(clearance 0)
		)
		(min_thickness 0.25)
		(keepout
			(tracks not_allowed)
			(vias allowed)
			(pads allowed)
			(copperpour not_allowed)
			(footprints allowed)
		)
		(placement
			(enabled no)
			(sheetname "")
		)
		(fill yes
			(thermal_gap 0.5)
			(thermal_bridge_width 0.5)
			(island_removal_mode 0)
		)
		(polygon
			(pts
				(arc
					(start 451.265798 -215.371426)
					(mid 451.280677 -215.407347)
					(end 451.316598 -215.422226)
				)
				(arc
					(start 452.716138 -215.422226)
					(mid 452.752059 -215.407347)
					(end 452.766938 -215.371426)
				)
				(arc
					(start 452.766938 -214.962486)
					(mid 452.752059 -214.926565)
					(end 452.716138 -214.911686)
				)
				(arc
					(start 451.316598 -214.911686)
					(mid 451.280677 -214.926565)
					(end 451.265798 -214.962486)
				)
			)
		)
	)
	(zone
		(layers "In1.Cu" "In2.Cu")
		(hatch none 0.5)
		(connect_pads
			(clearance 0)
		)
		(min_thickness 0.25)
		(keepout
			(tracks not_allowed)
			(vias allowed)
			(pads allowed)
			(copperpour not_allowed)
			(footprints allowed)
		)
		(placement
			(enabled no)
			(sheetname "")
		)
		(fill yes
			(thermal_gap 0.5)
			(thermal_bridge_width 0.5)
			(island_removal_mode 0)
		)
		(polygon
			(pts
				(arc
					(start 443.721998 -234.071414)
					(mid 443.736877 -234.107335)
					(end 443.772798 -234.122214)
				)
				(arc
					(start 445.172338 -234.122214)
					(mid 445.208259 -234.107335)
					(end 445.223138 -234.071414)
				)
				(arc
					(start 445.223138 -233.662474)
					(mid 445.208259 -233.626553)
					(end 445.172338 -233.611674)
				)
				(arc
					(start 443.772798 -233.611674)
					(mid 443.736877 -233.626553)
					(end 443.721998 -233.662474)
				)
			)
		)
	)
	(zone
		(layers "In1.Cu" "In2.Cu")
		(hatch none 0.5)
		(connect_pads
			(clearance 0)
		)
		(min_thickness 0.25)
		(keepout
			(tracks not_allowed)
			(vias allowed)
			(pads allowed)
			(copperpour not_allowed)
			(footprints allowed)
		)
		(placement
			(enabled no)
			(sheetname "")
		)
		(fill yes
			(thermal_gap 0.5)
			(thermal_bridge_width 0.5)
			(island_removal_mode 0)
		)
		(polygon
			(pts
				(arc
					(start 199.881998 -265.52144)
					(mid 199.896877 -265.557361)
					(end 199.932798 -265.57224)
				)
				(arc
					(start 201.332338 -265.57224)
					(mid 201.368259 -265.557361)
					(end 201.383138 -265.52144)
				)
				(arc
					(start 201.383138 -265.1125)
					(mid 201.368259 -265.076579)
					(end 201.332338 -265.0617)
				)
				(arc
					(start 199.932798 -265.0617)
					(mid 199.896877 -265.076579)
					(end 199.881998 -265.1125)
				)
			)
		)
	)
	(zone
		(layers "In1.Cu" "In2.Cu")
		(hatch none 0.5)
		(connect_pads
			(clearance 0)
		)
		(min_thickness 0.25)
		(keepout
			(tracks not_allowed)
			(vias allowed)
			(pads allowed)
			(copperpour not_allowed)
			(footprints allowed)
		)
		(placement
			(enabled no)
			(sheetname "")
		)
		(fill yes
			(thermal_gap 0.5)
			(thermal_bridge_width 0.5)
			(island_removal_mode 0)
		)
		(polygon
			(pts
				(arc
					(start 293.049198 -268.071346)
					(mid 293.064077 -268.107267)
					(end 293.099998 -268.122146)
				)
				(arc
					(start 294.499538 -268.122146)
					(mid 294.535459 -268.107267)
					(end 294.550338 -268.071346)
				)
				(arc
					(start 294.550338 -267.662406)
					(mid 294.535459 -267.626485)
					(end 294.499538 -267.611606)
				)
				(arc
					(start 293.099998 -267.611606)
					(mid 293.064077 -267.626485)
					(end 293.049198 -267.662406)
				)
			)
		)
	)
	(zone
		(layers "In1.Cu" "In2.Cu")
		(hatch none 0.5)
		(connect_pads
			(clearance 0)
		)
		(min_thickness 0.25)
		(keepout
			(tracks not_allowed)
			(vias allowed)
			(pads allowed)
			(copperpour not_allowed)
			(footprints allowed)
		)
		(placement
			(enabled no)
			(sheetname "")
		)
		(fill yes
			(thermal_gap 0.5)
			(thermal_bridge_width 0.5)
			(island_removal_mode 0)
		)
		(polygon
			(pts
				(arc
					(start 7.39013 -237.471458)
					(mid 7.405009 -237.507379)
					(end 7.44093 -237.522258)
				)
				(arc
					(start 8.84047 -237.522258)
					(mid 8.876391 -237.507379)
					(end 8.89127 -237.471458)
				)
				(arc
					(start 8.89127 -237.062518)
					(mid 8.876391 -237.026597)
					(end 8.84047 -237.011718)
				)
				(arc
					(start 7.44093 -237.011718)
					(mid 7.405009 -237.026597)
					(end 7.39013 -237.062518)
				)
			)
		)
	)
	(zone
		(layers "In1.Cu" "In2.Cu")
		(hatch none 0.5)
		(connect_pads
			(clearance 0)
		)
		(min_thickness 0.25)
		(keepout
			(tracks not_allowed)
			(vias allowed)
			(pads allowed)
			(copperpour not_allowed)
			(footprints allowed)
		)
		(placement
			(enabled no)
			(sheetname "")
		)
		(fill yes
			(thermal_gap 0.5)
			(thermal_bridge_width 0.5)
			(island_removal_mode 0)
		)
		(polygon
			(pts
				(arc
					(start 458.809598 -310.571388)
					(mid 458.824477 -310.607309)
					(end 458.860398 -310.622188)
				)
				(arc
					(start 460.259938 -310.622188)
					(mid 460.295859 -310.607309)
					(end 460.310738 -310.571388)
				)
				(arc
					(start 460.310738 -310.162448)
					(mid 460.295859 -310.126527)
					(end 460.259938 -310.111648)
				)
				(arc
					(start 458.860398 -310.111648)
					(mid 458.824477 -310.126527)
					(end 458.809598 -310.162448)
				)
			)
		)
	)
	(zone
		(layers "In1.Cu" "In2.Cu")
		(hatch none 0.5)
		(connect_pads
			(clearance 0)
		)
		(min_thickness 0.25)
		(keepout
			(tracks not_allowed)
			(vias allowed)
			(pads allowed)
			(copperpour not_allowed)
			(footprints allowed)
		)
		(placement
			(enabled no)
			(sheetname "")
		)
		(fill yes
			(thermal_gap 0.5)
			(thermal_bridge_width 0.5)
			(island_removal_mode 0)
		)
		(polygon
			(pts
				(arc
					(start 192.338198 -262.121396)
					(mid 192.353077 -262.157317)
					(end 192.388998 -262.172196)
				)
				(arc
					(start 193.788538 -262.172196)
					(mid 193.824459 -262.157317)
					(end 193.839338 -262.121396)
				)
				(arc
					(start 193.839338 -261.712456)
					(mid 193.824459 -261.676535)
					(end 193.788538 -261.661656)
				)
				(arc
					(start 192.388998 -261.661656)
					(mid 192.353077 -261.676535)
					(end 192.338198 -261.712456)
				)
			)
		)
	)
	(zone
		(layers "In1.Cu" "In2.Cu")
		(hatch none 0.5)
		(connect_pads
			(clearance 0)
		)
		(min_thickness 0.25)
		(keepout
			(tracks not_allowed)
			(vias allowed)
			(pads allowed)
			(copperpour not_allowed)
			(footprints allowed)
		)
		(placement
			(enabled no)
			(sheetname "")
		)
		(fill yes
			(thermal_gap 0.5)
			(thermal_bridge_width 0.5)
			(island_removal_mode 0)
		)
		(polygon
			(pts
				(arc
					(start 210.86953 -307.171344)
					(mid 210.884409 -307.207265)
					(end 210.92033 -307.222144)
				)
				(arc
					(start 212.31987 -307.222144)
					(mid 212.355791 -307.207265)
					(end 212.37067 -307.171344)
				)
				(arc
					(start 212.37067 -306.762404)
					(mid 212.355791 -306.726483)
					(end 212.31987 -306.711604)
				)
				(arc
					(start 210.92033 -306.711604)
					(mid 210.884409 -306.726483)
					(end 210.86953 -306.762404)
				)
			)
		)
	)
	(zone
		(layers "In1.Cu" "In2.Cu")
		(hatch none 0.5)
		(connect_pads
			(clearance 0)
		)
		(min_thickness 0.25)
		(keepout
			(tracks not_allowed)
			(vias allowed)
			(pads allowed)
			(copperpour not_allowed)
			(footprints allowed)
		)
		(placement
			(enabled no)
			(sheetname "")
		)
		(fill yes
			(thermal_gap 0.5)
			(thermal_bridge_width 0.5)
			(island_removal_mode 0)
		)
		(polygon
			(pts
				(arc
					(start 162.162998 -239.17148)
					(mid 162.177877 -239.207401)
					(end 162.213798 -239.22228)
				)
				(arc
					(start 163.613338 -239.22228)
					(mid 163.649259 -239.207401)
					(end 163.664138 -239.17148)
				)
				(arc
					(start 163.664138 -238.76254)
					(mid 163.649259 -238.726619)
					(end 163.613338 -238.71174)
				)
				(arc
					(start 162.213798 -238.71174)
					(mid 162.177877 -238.726619)
					(end 162.162998 -238.76254)
				)
			)
		)
	)
	(zone
		(layers "In1.Cu" "In2.Cu")
		(hatch none 0.5)
		(connect_pads
			(clearance 0)
		)
		(min_thickness 0.25)
		(keepout
			(tracks not_allowed)
			(vias allowed)
			(pads allowed)
			(copperpour not_allowed)
			(footprints allowed)
		)
		(placement
			(enabled no)
			(sheetname "")
		)
		(fill yes
			(thermal_gap 0.5)
			(thermal_bridge_width 0.5)
			(island_removal_mode 0)
		)
		(polygon
			(pts
				(arc
					(start 308.136798 -241.721386)
					(mid 308.151677 -241.757307)
					(end 308.187598 -241.772186)
				)
				(arc
					(start 309.587138 -241.772186)
					(mid 309.623059 -241.757307)
					(end 309.637938 -241.721386)
				)
				(arc
					(start 309.637938 -241.312446)
					(mid 309.623059 -241.276525)
					(end 309.587138 -241.261646)
				)
				(arc
					(start 308.187598 -241.261646)
					(mid 308.151677 -241.276525)
					(end 308.136798 -241.312446)
				)
			)
		)
	)
	(zone
		(layers "In1.Cu" "In2.Cu")
		(hatch none 0.5)
		(connect_pads
			(clearance 0)
		)
		(min_thickness 0.25)
		(keepout
			(tracks not_allowed)
			(vias allowed)
			(pads allowed)
			(copperpour not_allowed)
			(footprints allowed)
		)
		(placement
			(enabled no)
			(sheetname "")
		)
		(fill yes
			(thermal_gap 0.5)
			(thermal_bridge_width 0.5)
			(island_removal_mode 0)
		)
		(polygon
			(pts
				(arc
					(start 195.78193 -204.32141)
					(mid 195.796809 -204.357331)
					(end 195.83273 -204.37221)
				)
				(arc
					(start 197.23227 -204.37221)
					(mid 197.268191 -204.357331)
					(end 197.28307 -204.32141)
				)
				(arc
					(start 197.28307 -203.91247)
					(mid 197.268191 -203.876549)
					(end 197.23227 -203.86167)
				)
				(arc
					(start 195.83273 -203.86167)
					(mid 195.796809 -203.876549)
					(end 195.78193 -203.91247)
				)
			)
		)
	)
	(zone
		(layers "In1.Cu" "In2.Cu")
		(hatch none 0.5)
		(connect_pads
			(clearance 0)
		)
		(min_thickness 0.25)
		(keepout
			(tracks not_allowed)
			(vias allowed)
			(pads allowed)
			(copperpour not_allowed)
			(footprints allowed)
		)
		(placement
			(enabled no)
			(sheetname "")
		)
		(fill yes
			(thermal_gap 0.5)
			(thermal_bridge_width 0.5)
			(island_removal_mode 0)
		)
		(polygon
			(pts
				(arc
					(start 436.178198 -299.521372)
					(mid 436.193077 -299.557293)
					(end 436.228998 -299.572172)
				)
				(arc
					(start 437.628538 -299.572172)
					(mid 437.664459 -299.557293)
					(end 437.679338 -299.521372)
				)
				(arc
					(start 437.679338 -299.112432)
					(mid 437.664459 -299.076511)
					(end 437.628538 -299.061632)
				)
				(arc
					(start 436.228998 -299.061632)
					(mid 436.193077 -299.076511)
					(end 436.178198 -299.112432)
				)
			)
		)
	)
	(zone
		(layers "In1.Cu" "In2.Cu")
		(hatch none 0.5)
		(connect_pads
			(clearance 0)
		)
		(min_thickness 0.25)
		(keepout
			(tracks not_allowed)
			(vias allowed)
			(pads allowed)
			(copperpour not_allowed)
			(footprints allowed)
		)
		(placement
			(enabled no)
			(sheetname "")
		)
		(fill yes
			(thermal_gap 0.5)
			(thermal_bridge_width 0.5)
			(island_removal_mode 0)
		)
		(polygon
			(pts
				(arc
					(start 270.417798 -198.37146)
					(mid 270.432677 -198.407381)
					(end 270.468598 -198.42226)
				)
				(arc
					(start 271.868138 -198.42226)
					(mid 271.904059 -198.407381)
					(end 271.918938 -198.37146)
				)
				(arc
					(start 271.918938 -197.96252)
					(mid 271.904059 -197.926599)
					(end 271.868138 -197.91172)
				)
				(arc
					(start 270.468598 -197.91172)
					(mid 270.432677 -197.926599)
					(end 270.417798 -197.96252)
				)
			)
		)
	)
	(zone
		(layers "In1.Cu" "In2.Cu")
		(hatch none 0.5)
		(connect_pads
			(clearance 0)
		)
		(min_thickness 0.25)
		(keepout
			(tracks not_allowed)
			(vias allowed)
			(pads allowed)
			(copperpour not_allowed)
			(footprints allowed)
		)
		(placement
			(enabled no)
			(sheetname "")
		)
		(fill yes
			(thermal_gap 0.5)
			(thermal_bridge_width 0.5)
			(island_removal_mode 0)
		)
		(polygon
			(pts
				(arc
					(start 26.577798 -281.671522)
					(mid 26.592677 -281.707443)
					(end 26.628598 -281.722322)
				)
				(arc
					(start 28.028138 -281.722322)
					(mid 28.064059 -281.707443)
					(end 28.078938 -281.671522)
				)
				(arc
					(start 28.078938 -281.262582)
					(mid 28.064059 -281.226661)
					(end 28.028138 -281.211782)
				)
				(arc
					(start 26.628598 -281.211782)
					(mid 26.592677 -281.226661)
					(end 26.577798 -281.262582)
				)
			)
		)
	)
	(zone
		(layers "In1.Cu" "In2.Cu")
		(hatch none 0.5)
		(connect_pads
			(clearance 0)
		)
		(min_thickness 0.25)
		(keepout
			(tracks not_allowed)
			(vias allowed)
			(pads allowed)
			(copperpour not_allowed)
			(footprints allowed)
		)
		(placement
			(enabled no)
			(sheetname "")
		)
		(fill yes
			(thermal_gap 0.5)
			(thermal_bridge_width 0.5)
			(island_removal_mode 0)
		)
		(polygon
			(pts
				(arc
					(start 432.734466 -270.621506)
					(mid 432.749345 -270.657427)
					(end 432.785266 -270.672306)
				)
				(arc
					(start 434.184806 -270.672306)
					(mid 434.220727 -270.657427)
					(end 434.235606 -270.621506)
				)
				(arc
					(start 434.235606 -270.212566)
					(mid 434.220727 -270.176645)
					(end 434.184806 -270.161766)
				)
				(arc
					(start 432.785266 -270.161766)
					(mid 432.749345 -270.176645)
					(end 432.734466 -270.212566)
				)
			)
		)
	)
	(zone
		(layers "In1.Cu" "In2.Cu")
		(hatch none 0.5)
		(connect_pads
			(clearance 0)
		)
		(min_thickness 0.25)
		(keepout
			(tracks not_allowed)
			(vias allowed)
			(pads allowed)
			(copperpour not_allowed)
			(footprints allowed)
		)
		(placement
			(enabled no)
			(sheetname "")
		)
		(fill yes
			(thermal_gap 0.5)
			(thermal_bridge_width 0.5)
			(island_removal_mode 0)
		)
		(polygon
			(pts
				(arc
					(start 425.190666 -236.62132)
					(mid 425.205545 -236.657241)
					(end 425.241466 -236.67212)
				)
				(arc
					(start 426.641006 -236.67212)
					(mid 426.676927 -236.657241)
					(end 426.691806 -236.62132)
				)
				(arc
					(start 426.691806 -236.21238)
					(mid 426.676927 -236.176459)
					(end 426.641006 -236.16158)
				)
				(arc
					(start 425.241466 -236.16158)
					(mid 425.205545 -236.176459)
					(end 425.190666 -236.21238)
				)
			)
		)
	)
	(zone
		(layers "In1.Cu" "In2.Cu")
		(hatch none 0.5)
		(connect_pads
			(clearance 0)
		)
		(min_thickness 0.25)
		(keepout
			(tracks not_allowed)
			(vias allowed)
			(pads allowed)
			(copperpour not_allowed)
			(footprints allowed)
		)
		(placement
			(enabled no)
			(sheetname "")
		)
		(fill yes
			(thermal_gap 0.5)
			(thermal_bridge_width 0.5)
			(island_removal_mode 0)
		)
		(polygon
			(pts
				(arc
					(start 293.049198 -213.671404)
					(mid 293.064077 -213.707325)
					(end 293.099998 -213.722204)
				)
				(arc
					(start 294.499538 -213.722204)
					(mid 294.535459 -213.707325)
					(end 294.550338 -213.671404)
				)
				(arc
					(start 294.550338 -213.262464)
					(mid 294.535459 -213.226543)
					(end 294.499538 -213.211664)
				)
				(arc
					(start 293.099998 -213.211664)
					(mid 293.064077 -213.226543)
					(end 293.049198 -213.262464)
				)
			)
		)
	)
	(zone
		(layers "In1.Cu" "In2.Cu")
		(hatch none 0.5)
		(connect_pads
			(clearance 0)
		)
		(min_thickness 0.25)
		(keepout
			(tracks not_allowed)
			(vias allowed)
			(pads allowed)
			(copperpour not_allowed)
			(footprints allowed)
		)
		(placement
			(enabled no)
			(sheetname "")
		)
		(fill yes
			(thermal_gap 0.5)
			(thermal_bridge_width 0.5)
			(island_removal_mode 0)
		)
		(polygon
			(pts
				(arc
					(start 262.873998 -316.521338)
					(mid 262.888877 -316.557259)
					(end 262.924798 -316.572138)
				)
				(arc
					(start 264.324338 -316.572138)
					(mid 264.360259 -316.557259)
					(end 264.375138 -316.521338)
				)
				(arc
					(start 264.375138 -316.112398)
					(mid 264.360259 -316.076477)
					(end 264.324338 -316.061598)
				)
				(arc
					(start 262.924798 -316.061598)
					(mid 262.888877 -316.076477)
					(end 262.873998 -316.112398)
				)
			)
		)
	)
	(zone
		(layers "In1.Cu" "In2.Cu")
		(hatch none 0.5)
		(connect_pads
			(clearance 0)
		)
		(min_thickness 0.25)
		(keepout
			(tracks not_allowed)
			(vias allowed)
			(pads allowed)
			(copperpour not_allowed)
			(footprints allowed)
		)
		(placement
			(enabled no)
			(sheetname "")
		)
		(fill yes
			(thermal_gap 0.5)
			(thermal_bridge_width 0.5)
			(island_removal_mode 0)
		)
		(polygon
			(pts
				(arc
					(start 282.061666 -285.92145)
					(mid 282.076545 -285.957371)
					(end 282.112466 -285.97225)
				)
				(arc
					(start 283.512006 -285.97225)
					(mid 283.547927 -285.957371)
					(end 283.562806 -285.92145)
				)
				(arc
					(start 283.562806 -285.51251)
					(mid 283.547927 -285.476589)
					(end 283.512006 -285.46171)
				)
				(arc
					(start 282.112466 -285.46171)
					(mid 282.076545 -285.476589)
					(end 282.061666 -285.51251)
				)
			)
		)
	)
	(zone
		(layers "In1.Cu" "In2.Cu")
		(hatch none 0.5)
		(connect_pads
			(clearance 0)
		)
		(min_thickness 0.25)
		(keepout
			(tracks not_allowed)
			(vias allowed)
			(pads allowed)
			(copperpour not_allowed)
			(footprints allowed)
		)
		(placement
			(enabled no)
			(sheetname "")
		)
		(fill yes
			(thermal_gap 0.5)
			(thermal_bridge_width 0.5)
			(island_removal_mode 0)
		)
		(polygon
			(pts
				(arc
					(start 274.517866 -295.271444)
					(mid 274.532745 -295.307365)
					(end 274.568666 -295.322244)
				)
				(arc
					(start 275.968206 -295.322244)
					(mid 276.004127 -295.307365)
					(end 276.019006 -295.271444)
				)
				(arc
					(start 276.019006 -294.862504)
					(mid 276.004127 -294.826583)
					(end 275.968206 -294.811704)
				)
				(arc
					(start 274.568666 -294.811704)
					(mid 274.532745 -294.826583)
					(end 274.517866 -294.862504)
				)
			)
		)
	)
	(zone
		(layers "In1.Cu" "In2.Cu")
		(hatch none 0.5)
		(connect_pads
			(clearance 0)
		)
		(min_thickness 0.25)
		(keepout
			(tracks not_allowed)
			(vias allowed)
			(pads allowed)
			(copperpour not_allowed)
			(footprints allowed)
		)
		(placement
			(enabled no)
			(sheetname "")
		)
		(fill yes
			(thermal_gap 0.5)
			(thermal_bridge_width 0.5)
			(island_removal_mode 0)
		)
		(polygon
			(pts
				(arc
					(start 410.103066 -223.871536)
					(mid 410.117945 -223.907457)
					(end 410.153866 -223.922336)
				)
				(arc
					(start 411.553406 -223.922336)
					(mid 411.589327 -223.907457)
					(end 411.604206 -223.871536)
				)
				(arc
					(start 411.604206 -223.462596)
					(mid 411.589327 -223.426675)
					(end 411.553406 -223.411796)
				)
				(arc
					(start 410.153866 -223.411796)
					(mid 410.117945 -223.426675)
					(end 410.103066 -223.462596)
				)
			)
		)
	)
	(zone
		(layers "In1.Cu" "In2.Cu")
		(hatch none 0.5)
		(connect_pads
			(clearance 0)
		)
		(min_thickness 0.25)
		(keepout
			(tracks not_allowed)
			(vias allowed)
			(pads allowed)
			(copperpour not_allowed)
			(footprints allowed)
		)
		(placement
			(enabled no)
			(sheetname "")
		)
		(fill yes
			(thermal_gap 0.5)
			(thermal_bridge_width 0.5)
			(island_removal_mode 0)
		)
		(polygon
			(pts
				(arc
					(start 11.490198 -200.071482)
					(mid 11.505077 -200.107403)
					(end 11.540998 -200.122282)
				)
				(arc
					(start 12.940538 -200.122282)
					(mid 12.976459 -200.107403)
					(end 12.991338 -200.071482)
				)
				(arc
					(start 12.991338 -199.662542)
					(mid 12.976459 -199.626621)
					(end 12.940538 -199.611742)
				)
				(arc
					(start 11.540998 -199.611742)
					(mid 11.505077 -199.626621)
					(end 11.490198 -199.662542)
				)
			)
		)
	)
	(zone
		(layers "In1.Cu" "In2.Cu")
		(hatch none 0.5)
		(connect_pads
			(clearance 0)
		)
		(min_thickness 0.25)
		(keepout
			(tracks not_allowed)
			(vias allowed)
			(pads allowed)
			(copperpour not_allowed)
			(footprints allowed)
		)
		(placement
			(enabled no)
			(sheetname "")
		)
		(fill yes
			(thermal_gap 0.5)
			(thermal_bridge_width 0.5)
			(island_removal_mode 0)
		)
		(polygon
			(pts
				(arc
					(start 406.002998 -277.42134)
					(mid 406.017877 -277.457261)
					(end 406.053798 -277.47214)
				)
				(arc
					(start 407.453338 -277.47214)
					(mid 407.489259 -277.457261)
					(end 407.504138 -277.42134)
				)
				(arc
					(start 407.504138 -277.0124)
					(mid 407.489259 -276.976479)
					(end 407.453338 -276.9616)
				)
				(arc
					(start 406.053798 -276.9616)
					(mid 406.017877 -276.976479)
					(end 406.002998 -277.0124)
				)
			)
		)
	)
	(zone
		(layers "In1.Cu" "In2.Cu")
		(hatch none 0.5)
		(connect_pads
			(clearance 0)
		)
		(min_thickness 0.25)
		(keepout
			(tracks not_allowed)
			(vias allowed)
			(pads allowed)
			(copperpour not_allowed)
			(footprints allowed)
		)
		(placement
			(enabled no)
			(sheetname "")
		)
		(fill yes
			(thermal_gap 0.5)
			(thermal_bridge_width 0.5)
			(island_removal_mode 0)
		)
		(polygon
			(pts
				(arc
					(start 462.909666 -212.82152)
					(mid 462.924545 -212.857441)
					(end 462.960466 -212.87232)
				)
				(arc
					(start 464.360006 -212.87232)
					(mid 464.395927 -212.857441)
					(end 464.410806 -212.82152)
				)
				(arc
					(start 464.410806 -212.41258)
					(mid 464.395927 -212.376659)
					(end 464.360006 -212.36178)
				)
				(arc
					(start 462.960466 -212.36178)
					(mid 462.924545 -212.376659)
					(end 462.909666 -212.41258)
				)
			)
		)
	)
	(zone
		(layers "In1.Cu" "In2.Cu")
		(hatch none 0.5)
		(connect_pads
			(clearance 0)
		)
		(min_thickness 0.25)
		(keepout
			(tracks not_allowed)
			(vias allowed)
			(pads allowed)
			(copperpour not_allowed)
			(footprints allowed)
		)
		(placement
			(enabled no)
			(sheetname "")
		)
		(fill yes
			(thermal_gap 0.5)
			(thermal_bridge_width 0.5)
			(island_removal_mode 0)
		)
		(polygon
			(pts
				(arc
					(start 34.121598 -262.121396)
					(mid 34.136477 -262.157317)
					(end 34.172398 -262.172196)
				)
				(arc
					(start 35.571938 -262.172196)
					(mid 35.607859 -262.157317)
					(end 35.622738 -262.121396)
				)
				(arc
					(start 35.622738 -261.712456)
					(mid 35.607859 -261.676535)
					(end 35.571938 -261.661656)
				)
				(arc
					(start 34.172398 -261.661656)
					(mid 34.136477 -261.676535)
					(end 34.121598 -261.712456)
				)
			)
		)
	)
	(zone
		(layers "In1.Cu" "In2.Cu")
		(hatch none 0.5)
		(connect_pads
			(clearance 0)
		)
		(min_thickness 0.25)
		(keepout
			(tracks not_allowed)
			(vias allowed)
			(pads allowed)
			(copperpour not_allowed)
			(footprints allowed)
		)
		(placement
			(enabled no)
			(sheetname "")
		)
		(fill yes
			(thermal_gap 0.5)
			(thermal_bridge_width 0.5)
			(island_removal_mode 0)
		)
		(polygon
			(pts
				(arc
					(start 436.178198 -226.421442)
					(mid 436.193077 -226.457363)
					(end 436.228998 -226.472242)
				)
				(arc
					(start 437.628538 -226.472242)
					(mid 437.664459 -226.457363)
					(end 437.679338 -226.421442)
				)
				(arc
					(start 437.679338 -226.012502)
					(mid 437.664459 -225.976581)
					(end 437.628538 -225.961702)
				)
				(arc
					(start 436.228998 -225.961702)
					(mid 436.193077 -225.976581)
					(end 436.178198 -226.012502)
				)
			)
		)
	)
	(zone
		(layers "In1.Cu" "In2.Cu")
		(hatch none 0.5)
		(connect_pads
			(clearance 0)
		)
		(min_thickness 0.25)
		(keepout
			(tracks not_allowed)
			(vias allowed)
			(pads allowed)
			(copperpour not_allowed)
			(footprints allowed)
		)
		(placement
			(enabled no)
			(sheetname "")
		)
		(fill yes
			(thermal_gap 0.5)
			(thermal_bridge_width 0.5)
			(island_removal_mode 0)
		)
		(polygon
			(pts
				(arc
					(start 440.278266 -276.571456)
					(mid 440.293145 -276.607377)
					(end 440.329066 -276.622256)
				)
				(arc
					(start 441.728606 -276.622256)
					(mid 441.764527 -276.607377)
					(end 441.779406 -276.571456)
				)
				(arc
					(start 441.779406 -276.162516)
					(mid 441.764527 -276.126595)
					(end 441.728606 -276.111716)
				)
				(arc
					(start 440.329066 -276.111716)
					(mid 440.293145 -276.126595)
					(end 440.278266 -276.162516)
				)
			)
		)
	)
	(zone
		(layers "In1.Cu" "In2.Cu")
		(hatch none 0.5)
		(connect_pads
			(clearance 0)
		)
		(min_thickness 0.25)
		(keepout
			(tracks not_allowed)
			(vias allowed)
			(pads allowed)
			(copperpour not_allowed)
			(footprints allowed)
		)
		(placement
			(enabled no)
			(sheetname "")
		)
		(fill yes
			(thermal_gap 0.5)
			(thermal_bridge_width 0.5)
			(island_removal_mode 0)
		)
		(polygon
			(pts
				(arc
					(start 428.634398 -299.521372)
					(mid 428.649277 -299.557293)
					(end 428.685198 -299.572172)
				)
				(arc
					(start 430.084738 -299.572172)
					(mid 430.120659 -299.557293)
					(end 430.135538 -299.521372)
				)
				(arc
					(start 430.135538 -299.112432)
					(mid 430.120659 -299.076511)
					(end 430.084738 -299.061632)
				)
				(arc
					(start 428.685198 -299.061632)
					(mid 428.649277 -299.076511)
					(end 428.634398 -299.112432)
				)
			)
		)
	)
	(zone
		(layers "In1.Cu" "In2.Cu")
		(hatch none 0.5)
		(connect_pads
			(clearance 0)
		)
		(min_thickness 0.25)
		(keepout
			(tracks not_allowed)
			(vias allowed)
			(pads allowed)
			(copperpour not_allowed)
			(footprints allowed)
		)
		(placement
			(enabled no)
			(sheetname "")
		)
		(fill yes
			(thermal_gap 0.5)
			(thermal_bridge_width 0.5)
			(island_removal_mode 0)
		)
		(polygon
			(pts
				(arc
					(start 274.517866 -291.021516)
					(mid 274.532745 -291.057437)
					(end 274.568666 -291.072316)
				)
				(arc
					(start 275.968206 -291.072316)
					(mid 276.004127 -291.057437)
					(end 276.019006 -291.021516)
				)
				(arc
					(start 276.019006 -290.612576)
					(mid 276.004127 -290.576655)
					(end 275.968206 -290.561776)
				)
				(arc
					(start 274.568666 -290.561776)
					(mid 274.532745 -290.576655)
					(end 274.517866 -290.612576)
				)
			)
		)
	)
	(zone
		(layers "In1.Cu" "In2.Cu")
		(hatch none 0.5)
		(connect_pads
			(clearance 0)
		)
		(min_thickness 0.25)
		(keepout
			(tracks not_allowed)
			(vias allowed)
			(pads allowed)
			(copperpour not_allowed)
			(footprints allowed)
		)
		(placement
			(enabled no)
			(sheetname "")
		)
		(fill yes
			(thermal_gap 0.5)
			(thermal_bridge_width 0.5)
			(island_removal_mode 0)
		)
		(polygon
			(pts
				(arc
					(start 425.190666 -228.121464)
					(mid 425.205545 -228.157385)
					(end 425.241466 -228.172264)
				)
				(arc
					(start 426.641006 -228.172264)
					(mid 426.676927 -228.157385)
					(end 426.691806 -228.121464)
				)
				(arc
					(start 426.691806 -227.712524)
					(mid 426.676927 -227.676603)
					(end 426.641006 -227.661724)
				)
				(arc
					(start 425.241466 -227.661724)
					(mid 425.205545 -227.676603)
					(end 425.190666 -227.712524)
				)
			)
		)
	)
	(zone
		(layers "In1.Cu" "In2.Cu")
		(hatch none 0.5)
		(connect_pads
			(clearance 0)
		)
		(min_thickness 0.25)
		(keepout
			(tracks not_allowed)
			(vias allowed)
			(pads allowed)
			(copperpour not_allowed)
			(footprints allowed)
		)
		(placement
			(enabled no)
			(sheetname "")
		)
		(fill yes
			(thermal_gap 0.5)
			(thermal_bridge_width 0.5)
			(island_removal_mode 0)
		)
		(polygon
			(pts
				(arc
					(start 56.752998 -223.871536)
					(mid 56.767877 -223.907457)
					(end 56.803798 -223.922336)
				)
				(arc
					(start 58.203338 -223.922336)
					(mid 58.239259 -223.907457)
					(end 58.254138 -223.871536)
				)
				(arc
					(start 58.254138 -223.462596)
					(mid 58.239259 -223.426675)
					(end 58.203338 -223.411796)
				)
				(arc
					(start 56.803798 -223.411796)
					(mid 56.767877 -223.426675)
					(end 56.752998 -223.462596)
				)
			)
		)
	)
	(zone
		(layers "In1.Cu" "In2.Cu")
		(hatch none 0.5)
		(connect_pads
			(clearance 0)
		)
		(min_thickness 0.25)
		(keepout
			(tracks not_allowed)
			(vias allowed)
			(pads allowed)
			(copperpour not_allowed)
			(footprints allowed)
		)
		(placement
			(enabled no)
			(sheetname "")
		)
		(fill yes
			(thermal_gap 0.5)
			(thermal_bridge_width 0.5)
			(island_removal_mode 0)
		)
		(polygon
			(pts
				(arc
					(start 451.265798 -312.27141)
					(mid 451.280677 -312.307331)
					(end 451.316598 -312.32221)
				)
				(arc
					(start 452.716138 -312.32221)
					(mid 452.752059 -312.307331)
					(end 452.766938 -312.27141)
				)
				(arc
					(start 452.766938 -311.86247)
					(mid 452.752059 -311.826549)
					(end 452.716138 -311.81167)
				)
				(arc
					(start 451.316598 -311.81167)
					(mid 451.280677 -311.826549)
					(end 451.265798 -311.86247)
				)
			)
		)
	)
	(zone
		(layers "In1.Cu" "In2.Cu")
		(hatch none 0.5)
		(connect_pads
			(clearance 0)
		)
		(min_thickness 0.25)
		(keepout
			(tracks not_allowed)
			(vias allowed)
			(pads allowed)
			(copperpour not_allowed)
			(footprints allowed)
		)
		(placement
			(enabled no)
			(sheetname "")
		)
		(fill yes
			(thermal_gap 0.5)
			(thermal_bridge_width 0.5)
			(island_removal_mode 0)
		)
		(polygon
			(pts
				(arc
					(start 270.417798 -244.271292)
					(mid 270.432677 -244.307213)
					(end 270.468598 -244.322092)
				)
				(arc
					(start 271.868138 -244.322092)
					(mid 271.904059 -244.307213)
					(end 271.918938 -244.271292)
				)
				(arc
					(start 271.918938 -243.862352)
					(mid 271.904059 -243.826431)
					(end 271.868138 -243.811552)
				)
				(arc
					(start 270.468598 -243.811552)
					(mid 270.432677 -243.826431)
					(end 270.417798 -243.862352)
				)
			)
		)
	)
	(zone
		(layers "In1.Cu" "In2.Cu")
		(hatch none 0.5)
		(connect_pads
			(clearance 0)
		)
		(min_thickness 0.25)
		(keepout
			(tracks not_allowed)
			(vias allowed)
			(pads allowed)
			(copperpour not_allowed)
			(footprints allowed)
		)
		(placement
			(enabled no)
			(sheetname "")
		)
		(fill yes
			(thermal_gap 0.5)
			(thermal_bridge_width 0.5)
			(island_removal_mode 0)
		)
		(polygon
			(pts
				(arc
					(start 277.961598 -277.42134)
					(mid 277.976477 -277.457261)
					(end 278.012398 -277.47214)
				)
				(arc
					(start 279.411938 -277.47214)
					(mid 279.447859 -277.457261)
					(end 279.462738 -277.42134)
				)
				(arc
					(start 279.462738 -277.0124)
					(mid 279.447859 -276.976479)
					(end 279.411938 -276.9616)
				)
				(arc
					(start 278.012398 -276.9616)
					(mid 277.976477 -276.976479)
					(end 277.961598 -277.0124)
				)
			)
		)
	)
	(zone
		(layers "In1.Cu" "In2.Cu")
		(hatch none 0.5)
		(connect_pads
			(clearance 0)
		)
		(min_thickness 0.25)
		(keepout
			(tracks not_allowed)
			(vias allowed)
			(pads allowed)
			(copperpour not_allowed)
			(footprints allowed)
		)
		(placement
			(enabled no)
			(sheetname "")
		)
		(fill yes
			(thermal_gap 0.5)
			(thermal_bridge_width 0.5)
			(island_removal_mode 0)
		)
		(polygon
			(pts
				(arc
					(start 451.265798 -277.42134)
					(mid 451.280677 -277.457261)
					(end 451.316598 -277.47214)
				)
				(arc
					(start 452.716138 -277.47214)
					(mid 452.752059 -277.457261)
					(end 452.766938 -277.42134)
				)
				(arc
					(start 452.766938 -277.0124)
					(mid 452.752059 -276.976479)
					(end 452.716138 -276.9616)
				)
				(arc
					(start 451.316598 -276.9616)
					(mid 451.280677 -276.976479)
					(end 451.265798 -277.0124)
				)
			)
		)
	)
	(zone
		(layers "In1.Cu" "In2.Cu")
		(hatch none 0.5)
		(connect_pads
			(clearance 0)
		)
		(min_thickness 0.25)
		(keepout
			(tracks not_allowed)
			(vias allowed)
			(pads allowed)
			(copperpour not_allowed)
			(footprints allowed)
		)
		(placement
			(enabled no)
			(sheetname "")
		)
		(fill yes
			(thermal_gap 0.5)
			(thermal_bridge_width 0.5)
			(island_removal_mode 0)
		)
		(polygon
			(pts
				(arc
					(start 7.39013 -308.871366)
					(mid 7.405009 -308.907287)
					(end 7.44093 -308.922166)
				)
				(arc
					(start 8.84047 -308.922166)
					(mid 8.876391 -308.907287)
					(end 8.89127 -308.871366)
				)
				(arc
					(start 8.89127 -308.462426)
					(mid 8.876391 -308.426505)
					(end 8.84047 -308.411626)
				)
				(arc
					(start 7.44093 -308.411626)
					(mid 7.405009 -308.426505)
					(end 7.39013 -308.462426)
				)
			)
		)
	)
	(zone
		(layers "In1.Cu" "In2.Cu")
		(hatch none 0.5)
		(connect_pads
			(clearance 0)
		)
		(min_thickness 0.25)
		(keepout
			(tracks not_allowed)
			(vias allowed)
			(pads allowed)
			(copperpour not_allowed)
			(footprints allowed)
		)
		(placement
			(enabled no)
			(sheetname "")
		)
		(fill yes
			(thermal_gap 0.5)
			(thermal_bridge_width 0.5)
			(island_removal_mode 0)
		)
		(polygon
			(pts
				(arc
					(start 293.049198 -305.471322)
					(mid 293.064077 -305.507243)
					(end 293.099998 -305.522122)
				)
				(arc
					(start 294.499538 -305.522122)
					(mid 294.535459 -305.507243)
					(end 294.550338 -305.471322)
				)
				(arc
					(start 294.550338 -305.062382)
					(mid 294.535459 -305.026461)
					(end 294.499538 -305.011582)
				)
				(arc
					(start 293.099998 -305.011582)
					(mid 293.064077 -305.026461)
					(end 293.049198 -305.062382)
				)
			)
		)
	)
	(zone
		(layers "In1.Cu" "In2.Cu")
		(hatch none 0.5)
		(connect_pads
			(clearance 0)
		)
		(min_thickness 0.25)
		(keepout
			(tracks not_allowed)
			(vias allowed)
			(pads allowed)
			(copperpour not_allowed)
			(footprints allowed)
		)
		(placement
			(enabled no)
			(sheetname "")
		)
		(fill yes
			(thermal_gap 0.5)
			(thermal_bridge_width 0.5)
			(island_removal_mode 0)
		)
		(polygon
			(pts
				(arc
					(start 184.794398 -313.971432)
					(mid 184.809277 -314.007353)
					(end 184.845198 -314.022232)
				)
				(arc
					(start 186.244738 -314.022232)
					(mid 186.280659 -314.007353)
					(end 186.295538 -313.971432)
				)
				(arc
					(start 186.295538 -313.562492)
					(mid 186.280659 -313.526571)
					(end 186.244738 -313.511692)
				)
				(arc
					(start 184.845198 -313.511692)
					(mid 184.809277 -313.526571)
					(end 184.794398 -313.562492)
				)
			)
		)
	)
	(zone
		(layers "In1.Cu" "In2.Cu")
		(hatch none 0.5)
		(connect_pads
			(clearance 0)
		)
		(min_thickness 0.25)
		(keepout
			(tracks not_allowed)
			(vias allowed)
			(pads allowed)
			(copperpour not_allowed)
			(footprints allowed)
		)
		(placement
			(enabled no)
			(sheetname "")
		)
		(fill yes
			(thermal_gap 0.5)
			(thermal_bridge_width 0.5)
			(island_removal_mode 0)
		)
		(polygon
			(pts
				(arc
					(start 289.605466 -302.071532)
					(mid 289.620345 -302.107453)
					(end 289.656266 -302.122332)
				)
				(arc
					(start 291.055806 -302.122332)
					(mid 291.091727 -302.107453)
					(end 291.106606 -302.071532)
				)
				(arc
					(start 291.106606 -301.662592)
					(mid 291.091727 -301.626671)
					(end 291.055806 -301.611792)
				)
				(arc
					(start 289.656266 -301.611792)
					(mid 289.620345 -301.626671)
					(end 289.605466 -301.662592)
				)
			)
		)
	)
	(zone
		(layers "In1.Cu" "In2.Cu")
		(hatch none 0.5)
		(connect_pads
			(clearance 0)
		)
		(min_thickness 0.25)
		(keepout
			(tracks not_allowed)
			(vias allowed)
			(pads allowed)
			(copperpour not_allowed)
			(footprints allowed)
		)
		(placement
			(enabled no)
			(sheetname "")
		)
		(fill yes
			(thermal_gap 0.5)
			(thermal_bridge_width 0.5)
			(island_removal_mode 0)
		)
		(polygon
			(pts
				(arc
					(start 177.250598 -283.371544)
					(mid 177.265477 -283.407465)
					(end 177.301398 -283.422344)
				)
				(arc
					(start 178.700938 -283.422344)
					(mid 178.736859 -283.407465)
					(end 178.751738 -283.371544)
				)
				(arc
					(start 178.751738 -282.962604)
					(mid 178.736859 -282.926683)
					(end 178.700938 -282.911804)
				)
				(arc
					(start 177.301398 -282.911804)
					(mid 177.265477 -282.926683)
					(end 177.250598 -282.962604)
				)
			)
		)
	)
	(zone
		(layers "In1.Cu" "In2.Cu")
		(hatch none 0.5)
		(connect_pads
			(clearance 0)
		)
		(min_thickness 0.25)
		(keepout
			(tracks not_allowed)
			(vias allowed)
			(pads allowed)
			(copperpour not_allowed)
			(footprints allowed)
		)
		(placement
			(enabled no)
			(sheetname "")
		)
		(fill yes
			(thermal_gap 0.5)
			(thermal_bridge_width 0.5)
			(island_removal_mode 0)
		)
		(polygon
			(pts
				(arc
					(start 165.60673 -285.071312)
					(mid 165.621609 -285.107233)
					(end 165.65753 -285.122112)
				)
				(arc
					(start 167.05707 -285.122112)
					(mid 167.092991 -285.107233)
					(end 167.10787 -285.071312)
				)
				(arc
					(start 167.10787 -284.662372)
					(mid 167.092991 -284.626451)
					(end 167.05707 -284.611572)
				)
				(arc
					(start 165.65753 -284.611572)
					(mid 165.621609 -284.626451)
					(end 165.60673 -284.662372)
				)
			)
		)
	)
	(zone
		(layers "In1.Cu" "In2.Cu")
		(hatch none 0.5)
		(connect_pads
			(clearance 0)
		)
		(min_thickness 0.25)
		(keepout
			(tracks not_allowed)
			(vias allowed)
			(pads allowed)
			(copperpour not_allowed)
			(footprints allowed)
		)
		(placement
			(enabled no)
			(sheetname "")
		)
		(fill yes
			(thermal_gap 0.5)
			(thermal_bridge_width 0.5)
			(island_removal_mode 0)
		)
		(polygon
			(pts
				(arc
					(start 45.10913 -217.071448)
					(mid 45.124009 -217.107369)
					(end 45.15993 -217.122248)
				)
				(arc
					(start 46.55947 -217.122248)
					(mid 46.595391 -217.107369)
					(end 46.61027 -217.071448)
				)
				(arc
					(start 46.61027 -216.662508)
					(mid 46.595391 -216.626587)
					(end 46.55947 -216.611708)
				)
				(arc
					(start 45.15993 -216.611708)
					(mid 45.124009 -216.626587)
					(end 45.10913 -216.662508)
				)
			)
		)
	)
	(zone
		(layers "In1.Cu" "In2.Cu")
		(hatch none 0.5)
		(connect_pads
			(clearance 0)
		)
		(min_thickness 0.25)
		(keepout
			(tracks not_allowed)
			(vias allowed)
			(pads allowed)
			(copperpour not_allowed)
			(footprints allowed)
		)
		(placement
			(enabled no)
			(sheetname "")
		)
		(fill yes
			(thermal_gap 0.5)
			(thermal_bridge_width 0.5)
			(island_removal_mode 0)
		)
		(polygon
			(pts
				(arc
					(start 30.02153 -279.121362)
					(mid 30.036409 -279.157283)
					(end 30.07233 -279.172162)
				)
				(arc
					(start 31.47187 -279.172162)
					(mid 31.507791 -279.157283)
					(end 31.52267 -279.121362)
				)
				(arc
					(start 31.52267 -278.712422)
					(mid 31.507791 -278.676501)
					(end 31.47187 -278.661622)
				)
				(arc
					(start 30.07233 -278.661622)
					(mid 30.036409 -278.676501)
					(end 30.02153 -278.712422)
				)
			)
		)
	)
	(zone
		(layers "In1.Cu" "In2.Cu")
		(hatch none 0.5)
		(connect_pads
			(clearance 0)
		)
		(min_thickness 0.25)
		(keepout
			(tracks not_allowed)
			(vias allowed)
			(pads allowed)
			(copperpour not_allowed)
			(footprints allowed)
		)
		(placement
			(enabled no)
			(sheetname "")
		)
		(fill yes
			(thermal_gap 0.5)
			(thermal_bridge_width 0.5)
			(island_removal_mode 0)
		)
		(polygon
			(pts
				(arc
					(start 184.794398 -302.921416)
					(mid 184.809277 -302.957337)
					(end 184.845198 -302.972216)
				)
				(arc
					(start 186.244738 -302.972216)
					(mid 186.280659 -302.957337)
					(end 186.295538 -302.921416)
				)
				(arc
					(start 186.295538 -302.512476)
					(mid 186.280659 -302.476555)
					(end 186.244738 -302.461676)
				)
				(arc
					(start 184.845198 -302.461676)
					(mid 184.809277 -302.476555)
					(end 184.794398 -302.512476)
				)
			)
		)
	)
	(zone
		(layers "In1.Cu" "In2.Cu")
		(hatch none 0.5)
		(connect_pads
			(clearance 0)
		)
		(min_thickness 0.25)
		(keepout
			(tracks not_allowed)
			(vias allowed)
			(pads allowed)
			(copperpour not_allowed)
			(footprints allowed)
		)
		(placement
			(enabled no)
			(sheetname "")
		)
		(fill yes
			(thermal_gap 0.5)
			(thermal_bridge_width 0.5)
			(island_removal_mode 0)
		)
		(polygon
			(pts
				(arc
					(start 293.049198 -217.071448)
					(mid 293.064077 -217.107369)
					(end 293.099998 -217.122248)
				)
				(arc
					(start 294.499538 -217.122248)
					(mid 294.535459 -217.107369)
					(end 294.550338 -217.071448)
				)
				(arc
					(start 294.550338 -216.662508)
					(mid 294.535459 -216.626587)
					(end 294.499538 -216.611708)
				)
				(arc
					(start 293.099998 -216.611708)
					(mid 293.064077 -216.626587)
					(end 293.049198 -216.662508)
				)
			)
		)
	)
	(zone
		(layers "In1.Cu" "In2.Cu")
		(hatch none 0.5)
		(connect_pads
			(clearance 0)
		)
		(min_thickness 0.25)
		(keepout
			(tracks not_allowed)
			(vias allowed)
			(pads allowed)
			(copperpour not_allowed)
			(footprints allowed)
		)
		(placement
			(enabled no)
			(sheetname "")
		)
		(fill yes
			(thermal_gap 0.5)
			(thermal_bridge_width 0.5)
			(island_removal_mode 0)
		)
		(polygon
			(pts
				(arc
					(start 297.149266 -220.471492)
					(mid 297.164145 -220.507413)
					(end 297.200066 -220.522292)
				)
				(arc
					(start 298.599606 -220.522292)
					(mid 298.635527 -220.507413)
					(end 298.650406 -220.471492)
				)
				(arc
					(start 298.650406 -220.062552)
					(mid 298.635527 -220.026631)
					(end 298.599606 -220.011752)
				)
				(arc
					(start 297.200066 -220.011752)
					(mid 297.164145 -220.026631)
					(end 297.149266 -220.062552)
				)
			)
		)
	)
	(zone
		(layers "In1.Cu" "In2.Cu")
		(hatch none 0.5)
		(connect_pads
			(clearance 0)
		)
		(min_thickness 0.25)
		(keepout
			(tracks not_allowed)
			(vias allowed)
			(pads allowed)
			(copperpour not_allowed)
			(footprints allowed)
		)
		(placement
			(enabled no)
			(sheetname "")
		)
		(fill yes
			(thermal_gap 0.5)
			(thermal_bridge_width 0.5)
			(island_removal_mode 0)
		)
		(polygon
			(pts
				(arc
					(start 447.822066 -302.071532)
					(mid 447.836945 -302.107453)
					(end 447.872866 -302.122332)
				)
				(arc
					(start 449.272406 -302.122332)
					(mid 449.308327 -302.107453)
					(end 449.323206 -302.071532)
				)
				(arc
					(start 449.323206 -301.662592)
					(mid 449.308327 -301.626671)
					(end 449.272406 -301.611792)
				)
				(arc
					(start 447.872866 -301.611792)
					(mid 447.836945 -301.626671)
					(end 447.822066 -301.662592)
				)
			)
		)
	)
	(zone
		(layers "In1.Cu" "In2.Cu")
		(hatch none 0.5)
		(connect_pads
			(clearance 0)
		)
		(min_thickness 0.25)
		(keepout
			(tracks not_allowed)
			(vias allowed)
			(pads allowed)
			(copperpour not_allowed)
			(footprints allowed)
		)
		(placement
			(enabled no)
			(sheetname "")
		)
		(fill yes
			(thermal_gap 0.5)
			(thermal_bridge_width 0.5)
			(island_removal_mode 0)
		)
		(polygon
			(pts
				(arc
					(start 312.236866 -267.221462)
					(mid 312.251745 -267.257383)
					(end 312.287666 -267.272262)
				)
				(arc
					(start 313.687206 -267.272262)
					(mid 313.723127 -267.257383)
					(end 313.738006 -267.221462)
				)
				(arc
					(start 313.738006 -266.812522)
					(mid 313.723127 -266.776601)
					(end 313.687206 -266.761722)
				)
				(arc
					(start 312.287666 -266.761722)
					(mid 312.251745 -266.776601)
					(end 312.236866 -266.812522)
				)
			)
		)
	)
	(zone
		(layers "In1.Cu" "In2.Cu")
		(hatch none 0.5)
		(connect_pads
			(clearance 0)
		)
		(min_thickness 0.25)
		(keepout
			(tracks not_allowed)
			(vias allowed)
			(pads allowed)
			(copperpour not_allowed)
			(footprints allowed)
		)
		(placement
			(enabled no)
			(sheetname "")
		)
		(fill yes
			(thermal_gap 0.5)
			(thermal_bridge_width 0.5)
			(island_removal_mode 0)
		)
		(polygon
			(pts
				(arc
					(start 413.546798 -252.771402)
					(mid 413.561677 -252.807323)
					(end 413.597598 -252.822202)
				)
				(arc
					(start 414.997138 -252.822202)
					(mid 415.033059 -252.807323)
					(end 415.047938 -252.771402)
				)
				(arc
					(start 415.047938 -252.362462)
					(mid 415.033059 -252.326541)
					(end 414.997138 -252.311662)
				)
				(arc
					(start 413.597598 -252.311662)
					(mid 413.561677 -252.326541)
					(end 413.546798 -252.362462)
				)
			)
		)
	)
	(zone
		(layers "In1.Cu" "In2.Cu")
		(hatch none 0.5)
		(connect_pads
			(clearance 0)
		)
		(min_thickness 0.25)
		(keepout
			(tracks not_allowed)
			(vias allowed)
			(pads allowed)
			(copperpour not_allowed)
			(footprints allowed)
		)
		(placement
			(enabled no)
			(sheetname "")
		)
		(fill yes
			(thermal_gap 0.5)
			(thermal_bridge_width 0.5)
			(island_removal_mode 0)
		)
		(polygon
			(pts
				(arc
					(start 56.752998 -231.521508)
					(mid 56.767877 -231.557429)
					(end 56.803798 -231.572308)
				)
				(arc
					(start 58.203338 -231.572308)
					(mid 58.239259 -231.557429)
					(end 58.254138 -231.521508)
				)
				(arc
					(start 58.254138 -231.112568)
					(mid 58.239259 -231.076647)
					(end 58.203338 -231.061768)
				)
				(arc
					(start 56.803798 -231.061768)
					(mid 56.767877 -231.076647)
					(end 56.752998 -231.112568)
				)
			)
		)
	)
	(zone
		(layers "In1.Cu" "In2.Cu")
		(hatch none 0.5)
		(connect_pads
			(clearance 0)
		)
		(min_thickness 0.25)
		(keepout
			(tracks not_allowed)
			(vias allowed)
			(pads allowed)
			(copperpour not_allowed)
			(footprints allowed)
		)
		(placement
			(enabled no)
			(sheetname "")
		)
		(fill yes
			(thermal_gap 0.5)
			(thermal_bridge_width 0.5)
			(island_removal_mode 0)
		)
		(polygon
			(pts
				(arc
					(start 26.577798 -212.82152)
					(mid 26.592677 -212.857441)
					(end 26.628598 -212.87232)
				)
				(arc
					(start 28.028138 -212.87232)
					(mid 28.064059 -212.857441)
					(end 28.078938 -212.82152)
				)
				(arc
					(start 28.078938 -212.41258)
					(mid 28.064059 -212.376659)
					(end 28.028138 -212.36178)
				)
				(arc
					(start 26.628598 -212.36178)
					(mid 26.592677 -212.376659)
					(end 26.577798 -212.41258)
				)
			)
		)
	)
	(zone
		(layers "In1.Cu" "In2.Cu")
		(hatch none 0.5)
		(connect_pads
			(clearance 0)
		)
		(min_thickness 0.25)
		(keepout
			(tracks not_allowed)
			(vias allowed)
			(pads allowed)
			(copperpour not_allowed)
			(footprints allowed)
		)
		(placement
			(enabled no)
			(sheetname "")
		)
		(fill yes
			(thermal_gap 0.5)
			(thermal_bridge_width 0.5)
			(island_removal_mode 0)
		)
		(polygon
			(pts
				(arc
					(start 451.265798 -274.871434)
					(mid 451.280677 -274.907355)
					(end 451.316598 -274.922234)
				)
				(arc
					(start 452.716138 -274.922234)
					(mid 452.752059 -274.907355)
					(end 452.766938 -274.871434)
				)
				(arc
					(start 452.766938 -274.462494)
					(mid 452.752059 -274.426573)
					(end 452.716138 -274.411694)
				)
				(arc
					(start 451.316598 -274.411694)
					(mid 451.280677 -274.426573)
					(end 451.265798 -274.462494)
				)
			)
		)
	)
	(zone
		(layers "In1.Cu" "In2.Cu")
		(hatch none 0.5)
		(connect_pads
			(clearance 0)
		)
		(min_thickness 0.25)
		(keepout
			(tracks not_allowed)
			(vias allowed)
			(pads allowed)
			(copperpour not_allowed)
			(footprints allowed)
		)
		(placement
			(enabled no)
			(sheetname "")
		)
		(fill yes
			(thermal_gap 0.5)
			(thermal_bridge_width 0.5)
			(island_removal_mode 0)
		)
		(polygon
			(pts
				(arc
					(start 22.47773 -240.021364)
					(mid 22.492609 -240.057285)
					(end 22.52853 -240.072164)
				)
				(arc
					(start 23.92807 -240.072164)
					(mid 23.963991 -240.057285)
					(end 23.97887 -240.021364)
				)
				(arc
					(start 23.97887 -239.612424)
					(mid 23.963991 -239.576503)
					(end 23.92807 -239.561624)
				)
				(arc
					(start 22.52853 -239.561624)
					(mid 22.492609 -239.576503)
					(end 22.47773 -239.612424)
				)
			)
		)
	)
	(zone
		(layers "In1.Cu" "In2.Cu")
		(hatch none 0.5)
		(connect_pads
			(clearance 0)
		)
		(min_thickness 0.25)
		(keepout
			(tracks not_allowed)
			(vias allowed)
			(pads allowed)
			(copperpour not_allowed)
			(footprints allowed)
		)
		(placement
			(enabled no)
			(sheetname "")
		)
		(fill yes
			(thermal_gap 0.5)
			(thermal_bridge_width 0.5)
			(island_removal_mode 0)
		)
		(polygon
			(pts
				(arc
					(start 436.178198 -310.571388)
					(mid 436.193077 -310.607309)
					(end 436.228998 -310.622188)
				)
				(arc
					(start 437.628538 -310.622188)
					(mid 437.664459 -310.607309)
					(end 437.679338 -310.571388)
				)
				(arc
					(start 437.679338 -310.162448)
					(mid 437.664459 -310.126527)
					(end 437.628538 -310.111648)
				)
				(arc
					(start 436.228998 -310.111648)
					(mid 436.193077 -310.126527)
					(end 436.178198 -310.162448)
				)
			)
		)
	)
	(zone
		(layers "In1.Cu" "In2.Cu")
		(hatch none 0.5)
		(connect_pads
			(clearance 0)
		)
		(min_thickness 0.25)
		(keepout
			(tracks not_allowed)
			(vias allowed)
			(pads allowed)
			(copperpour not_allowed)
			(footprints allowed)
		)
		(placement
			(enabled no)
			(sheetname "")
		)
		(fill yes
			(thermal_gap 0.5)
			(thermal_bridge_width 0.5)
			(island_removal_mode 0)
		)
		(polygon
			(pts
				(arc
					(start 421.090598 -274.871434)
					(mid 421.105477 -274.907355)
					(end 421.141398 -274.922234)
				)
				(arc
					(start 422.540938 -274.922234)
					(mid 422.576859 -274.907355)
					(end 422.591738 -274.871434)
				)
				(arc
					(start 422.591738 -274.462494)
					(mid 422.576859 -274.426573)
					(end 422.540938 -274.411694)
				)
				(arc
					(start 421.141398 -274.411694)
					(mid 421.105477 -274.426573)
					(end 421.090598 -274.462494)
				)
			)
		)
	)
	(zone
		(layers "In1.Cu" "In2.Cu")
		(hatch none 0.5)
		(connect_pads
			(clearance 0)
		)
		(min_thickness 0.25)
		(keepout
			(tracks not_allowed)
			(vias allowed)
			(pads allowed)
			(copperpour not_allowed)
			(footprints allowed)
		)
		(placement
			(enabled no)
			(sheetname "")
		)
		(fill yes
			(thermal_gap 0.5)
			(thermal_bridge_width 0.5)
			(island_removal_mode 0)
		)
		(polygon
			(pts
				(arc
					(start 14.93393 -293.571422)
					(mid 14.948809 -293.607343)
					(end 14.98473 -293.622222)
				)
				(arc
					(start 16.38427 -293.622222)
					(mid 16.420191 -293.607343)
					(end 16.43507 -293.571422)
				)
				(arc
					(start 16.43507 -293.162482)
					(mid 16.420191 -293.126561)
					(end 16.38427 -293.111682)
				)
				(arc
					(start 14.98473 -293.111682)
					(mid 14.948809 -293.126561)
					(end 14.93393 -293.162482)
				)
			)
		)
	)
	(zone
		(layers "In1.Cu" "In2.Cu")
		(hatch none 0.5)
		(connect_pads
			(clearance 0)
		)
		(min_thickness 0.25)
		(keepout
			(tracks not_allowed)
			(vias allowed)
			(pads allowed)
			(copperpour not_allowed)
			(footprints allowed)
		)
		(placement
			(enabled no)
			(sheetname "")
		)
		(fill yes
			(thermal_gap 0.5)
			(thermal_bridge_width 0.5)
			(island_removal_mode 0)
		)
		(polygon
			(pts
				(arc
					(start 52.65293 -313.121294)
					(mid 52.667809 -313.157215)
					(end 52.70373 -313.172094)
				)
				(arc
					(start 54.10327 -313.172094)
					(mid 54.139191 -313.157215)
					(end 54.15407 -313.121294)
				)
				(arc
					(start 54.15407 -312.712354)
					(mid 54.139191 -312.676433)
					(end 54.10327 -312.661554)
				)
				(arc
					(start 52.70373 -312.661554)
					(mid 52.667809 -312.676433)
					(end 52.65293 -312.712354)
				)
			)
		)
	)
	(zone
		(layers "In1.Cu" "In2.Cu")
		(hatch none 0.5)
		(connect_pads
			(clearance 0)
		)
		(min_thickness 0.25)
		(keepout
			(tracks not_allowed)
			(vias allowed)
			(pads allowed)
			(copperpour not_allowed)
			(footprints allowed)
		)
		(placement
			(enabled no)
			(sheetname "")
		)
		(fill yes
			(thermal_gap 0.5)
			(thermal_bridge_width 0.5)
			(island_removal_mode 0)
		)
		(polygon
			(pts
				(arc
					(start 304.693066 -285.92145)
					(mid 304.707945 -285.957371)
					(end 304.743866 -285.97225)
				)
				(arc
					(start 306.143406 -285.97225)
					(mid 306.179327 -285.957371)
					(end 306.194206 -285.92145)
				)
				(arc
					(start 306.194206 -285.51251)
					(mid 306.179327 -285.476589)
					(end 306.143406 -285.46171)
				)
				(arc
					(start 304.743866 -285.46171)
					(mid 304.707945 -285.476589)
					(end 304.693066 -285.51251)
				)
			)
		)
	)
	(zone
		(layers "In1.Cu" "In2.Cu")
		(hatch none 0.5)
		(connect_pads
			(clearance 0)
		)
		(min_thickness 0.25)
		(keepout
			(tracks not_allowed)
			(vias allowed)
			(pads allowed)
			(copperpour not_allowed)
			(footprints allowed)
		)
		(placement
			(enabled no)
			(sheetname "")
		)
		(fill yes
			(thermal_gap 0.5)
			(thermal_bridge_width 0.5)
			(island_removal_mode 0)
		)
		(polygon
			(pts
				(arc
					(start 173.15053 -237.471458)
					(mid 173.165409 -237.507379)
					(end 173.20133 -237.522258)
				)
				(arc
					(start 174.60087 -237.522258)
					(mid 174.636791 -237.507379)
					(end 174.65167 -237.471458)
				)
				(arc
					(start 174.65167 -237.062518)
					(mid 174.636791 -237.026597)
					(end 174.60087 -237.011718)
				)
				(arc
					(start 173.20133 -237.011718)
					(mid 173.165409 -237.026597)
					(end 173.15053 -237.062518)
				)
			)
		)
	)
	(zone
		(layers "In1.Cu" "In2.Cu")
		(hatch none 0.5)
		(connect_pads
			(clearance 0)
		)
		(min_thickness 0.25)
		(keepout
			(tracks not_allowed)
			(vias allowed)
			(pads allowed)
			(copperpour not_allowed)
			(footprints allowed)
		)
		(placement
			(enabled no)
			(sheetname "")
		)
		(fill yes
			(thermal_gap 0.5)
			(thermal_bridge_width 0.5)
			(island_removal_mode 0)
		)
		(polygon
			(pts
				(arc
					(start 30.02153 -307.171344)
					(mid 30.036409 -307.207265)
					(end 30.07233 -307.222144)
				)
				(arc
					(start 31.47187 -307.222144)
					(mid 31.507791 -307.207265)
					(end 31.52267 -307.171344)
				)
				(arc
					(start 31.52267 -306.762404)
					(mid 31.507791 -306.726483)
					(end 31.47187 -306.711604)
				)
				(arc
					(start 30.07233 -306.711604)
					(mid 30.036409 -306.726483)
					(end 30.02153 -306.762404)
				)
			)
		)
	)
	(zone
		(layers "In1.Cu" "In2.Cu")
		(hatch none 0.5)
		(connect_pads
			(clearance 0)
		)
		(min_thickness 0.25)
		(keepout
			(tracks not_allowed)
			(vias allowed)
			(pads allowed)
			(copperpour not_allowed)
			(footprints allowed)
		)
		(placement
			(enabled no)
			(sheetname "")
		)
		(fill yes
			(thermal_gap 0.5)
			(thermal_bridge_width 0.5)
			(island_removal_mode 0)
		)
		(polygon
			(pts
				(arc
					(start 188.23813 -273.171412)
					(mid 188.253009 -273.207333)
					(end 188.28893 -273.222212)
				)
				(arc
					(start 189.68847 -273.222212)
					(mid 189.724391 -273.207333)
					(end 189.73927 -273.171412)
				)
				(arc
					(start 189.73927 -272.762472)
					(mid 189.724391 -272.726551)
					(end 189.68847 -272.711672)
				)
				(arc
					(start 188.28893 -272.711672)
					(mid 188.253009 -272.726551)
					(end 188.23813 -272.762472)
				)
			)
		)
	)
	(zone
		(layers "In1.Cu" "In2.Cu")
		(hatch none 0.5)
		(connect_pads
			(clearance 0)
		)
		(min_thickness 0.25)
		(keepout
			(tracks not_allowed)
			(vias allowed)
			(pads allowed)
			(copperpour not_allowed)
			(footprints allowed)
		)
		(placement
			(enabled no)
			(sheetname "")
		)
		(fill yes
			(thermal_gap 0.5)
			(thermal_bridge_width 0.5)
			(island_removal_mode 0)
		)
		(polygon
			(pts
				(arc
					(start 19.033998 -265.52144)
					(mid 19.048877 -265.557361)
					(end 19.084798 -265.57224)
				)
				(arc
					(start 20.484338 -265.57224)
					(mid 20.520259 -265.557361)
					(end 20.535138 -265.52144)
				)
				(arc
					(start 20.535138 -265.1125)
					(mid 20.520259 -265.076579)
					(end 20.484338 -265.0617)
				)
				(arc
					(start 19.084798 -265.0617)
					(mid 19.048877 -265.076579)
					(end 19.033998 -265.1125)
				)
			)
		)
	)
	(zone
		(layers "In1.Cu" "In2.Cu")
		(hatch none 0.5)
		(connect_pads
			(clearance 0)
		)
		(min_thickness 0.25)
		(keepout
			(tracks not_allowed)
			(vias allowed)
			(pads allowed)
			(copperpour not_allowed)
			(footprints allowed)
		)
		(placement
			(enabled no)
			(sheetname "")
		)
		(fill yes
			(thermal_gap 0.5)
			(thermal_bridge_width 0.5)
			(island_removal_mode 0)
		)
		(polygon
			(pts
				(arc
					(start 274.517866 -287.621472)
					(mid 274.532745 -287.657393)
					(end 274.568666 -287.672272)
				)
				(arc
					(start 275.968206 -287.672272)
					(mid 276.004127 -287.657393)
					(end 276.019006 -287.621472)
				)
				(arc
					(start 276.019006 -287.212532)
					(mid 276.004127 -287.176611)
					(end 275.968206 -287.161732)
				)
				(arc
					(start 274.568666 -287.161732)
					(mid 274.532745 -287.176611)
					(end 274.517866 -287.212532)
				)
			)
		)
	)
	(zone
		(layers "In1.Cu" "In2.Cu")
		(hatch none 0.5)
		(connect_pads
			(clearance 0)
		)
		(min_thickness 0.25)
		(keepout
			(tracks not_allowed)
			(vias allowed)
			(pads allowed)
			(copperpour not_allowed)
			(footprints allowed)
		)
		(placement
			(enabled no)
			(sheetname "")
		)
		(fill yes
			(thermal_gap 0.5)
			(thermal_bridge_width 0.5)
			(island_removal_mode 0)
		)
		(polygon
			(pts
				(arc
					(start 52.65293 -215.371426)
					(mid 52.667809 -215.407347)
					(end 52.70373 -215.422226)
				)
				(arc
					(start 54.10327 -215.422226)
					(mid 54.139191 -215.407347)
					(end 54.15407 -215.371426)
				)
				(arc
					(start 54.15407 -214.962486)
					(mid 54.139191 -214.926565)
					(end 54.10327 -214.911686)
				)
				(arc
					(start 52.70373 -214.911686)
					(mid 52.667809 -214.926565)
					(end 52.65293 -214.962486)
				)
			)
		)
	)
	(zone
		(layers "In1.Cu" "In2.Cu")
		(hatch none 0.5)
		(connect_pads
			(clearance 0)
		)
		(min_thickness 0.25)
		(keepout
			(tracks not_allowed)
			(vias allowed)
			(pads allowed)
			(copperpour not_allowed)
			(footprints allowed)
		)
		(placement
			(enabled no)
			(sheetname "")
		)
		(fill yes
			(thermal_gap 0.5)
			(thermal_bridge_width 0.5)
			(island_removal_mode 0)
		)
		(polygon
			(pts
				(arc
					(start 262.873998 -285.071312)
					(mid 262.888877 -285.107233)
					(end 262.924798 -285.122112)
				)
				(arc
					(start 264.324338 -285.122112)
					(mid 264.360259 -285.107233)
					(end 264.375138 -285.071312)
				)
				(arc
					(start 264.375138 -284.662372)
					(mid 264.360259 -284.626451)
					(end 264.324338 -284.611572)
				)
				(arc
					(start 262.924798 -284.611572)
					(mid 262.888877 -284.626451)
					(end 262.873998 -284.662372)
				)
			)
		)
	)
	(zone
		(layers "In1.Cu" "In2.Cu")
		(hatch none 0.5)
		(connect_pads
			(clearance 0)
		)
		(min_thickness 0.25)
		(keepout
			(tracks not_allowed)
			(vias allowed)
			(pads allowed)
			(copperpour not_allowed)
			(footprints allowed)
		)
		(placement
			(enabled no)
			(sheetname "")
		)
		(fill yes
			(thermal_gap 0.5)
			(thermal_bridge_width 0.5)
			(island_removal_mode 0)
		)
		(polygon
			(pts
				(arc
					(start 255.330198 -206.021432)
					(mid 255.345077 -206.057353)
					(end 255.380998 -206.072232)
				)
				(arc
					(start 256.780538 -206.072232)
					(mid 256.816459 -206.057353)
					(end 256.831338 -206.021432)
				)
				(arc
					(start 256.831338 -205.612492)
					(mid 256.816459 -205.576571)
					(end 256.780538 -205.561692)
				)
				(arc
					(start 255.380998 -205.561692)
					(mid 255.345077 -205.576571)
					(end 255.330198 -205.612492)
				)
			)
		)
	)
	(zone
		(layers "In1.Cu" "In2.Cu")
		(hatch none 0.5)
		(connect_pads
			(clearance 0)
		)
		(min_thickness 0.25)
		(keepout
			(tracks not_allowed)
			(vias allowed)
			(pads allowed)
			(copperpour not_allowed)
			(footprints allowed)
		)
		(placement
			(enabled no)
			(sheetname "")
		)
		(fill yes
			(thermal_gap 0.5)
			(thermal_bridge_width 0.5)
			(island_removal_mode 0)
		)
		(polygon
			(pts
				(arc
					(start 45.10913 -261.271512)
					(mid 45.124009 -261.307433)
					(end 45.15993 -261.322312)
				)
				(arc
					(start 46.55947 -261.322312)
					(mid 46.595391 -261.307433)
					(end 46.61027 -261.271512)
				)
				(arc
					(start 46.61027 -260.862572)
					(mid 46.595391 -260.826651)
					(end 46.55947 -260.811772)
				)
				(arc
					(start 45.15993 -260.811772)
					(mid 45.124009 -260.826651)
					(end 45.10913 -260.862572)
				)
			)
		)
	)
	(zone
		(layers "In1.Cu" "In2.Cu")
		(hatch none 0.5)
		(connect_pads
			(clearance 0)
		)
		(min_thickness 0.25)
		(keepout
			(tracks not_allowed)
			(vias allowed)
			(pads allowed)
			(copperpour not_allowed)
			(footprints allowed)
		)
		(placement
			(enabled no)
			(sheetname "")
		)
		(fill yes
			(thermal_gap 0.5)
			(thermal_bridge_width 0.5)
			(island_removal_mode 0)
		)
		(polygon
			(pts
				(arc
					(start 410.103066 -313.971432)
					(mid 410.117945 -314.007353)
					(end 410.153866 -314.022232)
				)
				(arc
					(start 411.553406 -314.022232)
					(mid 411.589327 -314.007353)
					(end 411.604206 -313.971432)
				)
				(arc
					(start 411.604206 -313.562492)
					(mid 411.589327 -313.526571)
					(end 411.553406 -313.511692)
				)
				(arc
					(start 410.153866 -313.511692)
					(mid 410.117945 -313.526571)
					(end 410.103066 -313.562492)
				)
			)
		)
	)
	(zone
		(layers "In1.Cu" "In2.Cu")
		(hatch none 0.5)
		(connect_pads
			(clearance 0)
		)
		(min_thickness 0.25)
		(keepout
			(tracks not_allowed)
			(vias allowed)
			(pads allowed)
			(copperpour not_allowed)
			(footprints allowed)
		)
		(placement
			(enabled no)
			(sheetname "")
		)
		(fill yes
			(thermal_gap 0.5)
			(thermal_bridge_width 0.5)
			(island_removal_mode 0)
		)
		(polygon
			(pts
				(arc
					(start 462.909666 -309.721504)
					(mid 462.924545 -309.757425)
					(end 462.960466 -309.772304)
				)
				(arc
					(start 464.360006 -309.772304)
					(mid 464.395927 -309.757425)
					(end 464.410806 -309.721504)
				)
				(arc
					(start 464.410806 -309.312564)
					(mid 464.395927 -309.276643)
					(end 464.360006 -309.261764)
				)
				(arc
					(start 462.960466 -309.261764)
					(mid 462.924545 -309.276643)
					(end 462.909666 -309.312564)
				)
			)
		)
	)
	(zone
		(layers "In1.Cu" "In2.Cu")
		(hatch none 0.5)
		(connect_pads
			(clearance 0)
		)
		(min_thickness 0.25)
		(keepout
			(tracks not_allowed)
			(vias allowed)
			(pads allowed)
			(copperpour not_allowed)
			(footprints allowed)
		)
		(placement
			(enabled no)
			(sheetname "")
		)
		(fill yes
			(thermal_gap 0.5)
			(thermal_bridge_width 0.5)
			(island_removal_mode 0)
		)
		(polygon
			(pts
				(arc
					(start 26.577798 -231.521508)
					(mid 26.592677 -231.557429)
					(end 26.628598 -231.572308)
				)
				(arc
					(start 28.028138 -231.572308)
					(mid 28.064059 -231.557429)
					(end 28.078938 -231.521508)
				)
				(arc
					(start 28.078938 -231.112568)
					(mid 28.064059 -231.076647)
					(end 28.028138 -231.061768)
				)
				(arc
					(start 26.628598 -231.061768)
					(mid 26.592677 -231.076647)
					(end 26.577798 -231.112568)
				)
			)
		)
	)
	(zone
		(layers "In1.Cu" "In2.Cu")
		(hatch none 0.5)
		(connect_pads
			(clearance 0)
		)
		(min_thickness 0.25)
		(keepout
			(tracks not_allowed)
			(vias allowed)
			(pads allowed)
			(copperpour not_allowed)
			(footprints allowed)
		)
		(placement
			(enabled no)
			(sheetname "")
		)
		(fill yes
			(thermal_gap 0.5)
			(thermal_bridge_width 0.5)
			(island_removal_mode 0)
		)
		(polygon
			(pts
				(arc
					(start 180.69433 -237.471458)
					(mid 180.709209 -237.507379)
					(end 180.74513 -237.522258)
				)
				(arc
					(start 182.14467 -237.522258)
					(mid 182.180591 -237.507379)
					(end 182.19547 -237.471458)
				)
				(arc
					(start 182.19547 -237.062518)
					(mid 182.180591 -237.026597)
					(end 182.14467 -237.011718)
				)
				(arc
					(start 180.74513 -237.011718)
					(mid 180.709209 -237.026597)
					(end 180.69433 -237.062518)
				)
			)
		)
	)
	(zone
		(layers "In1.Cu" "In2.Cu")
		(hatch none 0.5)
		(connect_pads
			(clearance 0)
		)
		(min_thickness 0.25)
		(keepout
			(tracks not_allowed)
			(vias allowed)
			(pads allowed)
			(copperpour not_allowed)
			(footprints allowed)
		)
		(placement
			(enabled no)
			(sheetname "")
		)
		(fill yes
			(thermal_gap 0.5)
			(thermal_bridge_width 0.5)
			(island_removal_mode 0)
		)
		(polygon
			(pts
				(arc
					(start 195.78193 -215.371426)
					(mid 195.796809 -215.407347)
					(end 195.83273 -215.422226)
				)
				(arc
					(start 197.23227 -215.422226)
					(mid 197.268191 -215.407347)
					(end 197.28307 -215.371426)
				)
				(arc
					(start 197.28307 -214.962486)
					(mid 197.268191 -214.926565)
					(end 197.23227 -214.911686)
				)
				(arc
					(start 195.83273 -214.911686)
					(mid 195.796809 -214.926565)
					(end 195.78193 -214.962486)
				)
			)
		)
	)
	(zone
		(layers "In1.Cu" "In2.Cu")
		(hatch none 0.5)
		(connect_pads
			(clearance 0)
		)
		(min_thickness 0.25)
		(keepout
			(tracks not_allowed)
			(vias allowed)
			(pads allowed)
			(copperpour not_allowed)
			(footprints allowed)
		)
		(placement
			(enabled no)
			(sheetname "")
		)
		(fill yes
			(thermal_gap 0.5)
			(thermal_bridge_width 0.5)
			(island_removal_mode 0)
		)
		(polygon
			(pts
				(arc
					(start 34.121598 -259.57149)
					(mid 34.136477 -259.607411)
					(end 34.172398 -259.62229)
				)
				(arc
					(start 35.571938 -259.62229)
					(mid 35.607859 -259.607411)
					(end 35.622738 -259.57149)
				)
				(arc
					(start 35.622738 -259.16255)
					(mid 35.607859 -259.126629)
					(end 35.571938 -259.11175)
				)
				(arc
					(start 34.172398 -259.11175)
					(mid 34.136477 -259.126629)
					(end 34.121598 -259.16255)
				)
			)
		)
	)
	(zone
		(layers "In1.Cu" "In2.Cu")
		(hatch none 0.5)
		(connect_pads
			(clearance 0)
		)
		(min_thickness 0.25)
		(keepout
			(tracks not_allowed)
			(vias allowed)
			(pads allowed)
			(copperpour not_allowed)
			(footprints allowed)
		)
		(placement
			(enabled no)
			(sheetname "")
		)
		(fill yes
			(thermal_gap 0.5)
			(thermal_bridge_width 0.5)
			(island_removal_mode 0)
		)
		(polygon
			(pts
				(arc
					(start 262.873998 -279.121362)
					(mid 262.888877 -279.157283)
					(end 262.924798 -279.172162)
				)
				(arc
					(start 264.324338 -279.172162)
					(mid 264.360259 -279.157283)
					(end 264.375138 -279.121362)
				)
				(arc
					(start 264.375138 -278.712422)
					(mid 264.360259 -278.676501)
					(end 264.324338 -278.661622)
				)
				(arc
					(start 262.924798 -278.661622)
					(mid 262.888877 -278.676501)
					(end 262.873998 -278.712422)
				)
			)
		)
	)
	(zone
		(layers "In1.Cu" "In2.Cu")
		(hatch none 0.5)
		(connect_pads
			(clearance 0)
		)
		(min_thickness 0.25)
		(keepout
			(tracks not_allowed)
			(vias allowed)
			(pads allowed)
			(copperpour not_allowed)
			(footprints allowed)
		)
		(placement
			(enabled no)
			(sheetname "")
		)
		(fill yes
			(thermal_gap 0.5)
			(thermal_bridge_width 0.5)
			(island_removal_mode 0)
		)
		(polygon
			(pts
				(arc
					(start 300.592998 -312.27141)
					(mid 300.607877 -312.307331)
					(end 300.643798 -312.32221)
				)
				(arc
					(start 302.043338 -312.32221)
					(mid 302.079259 -312.307331)
					(end 302.094138 -312.27141)
				)
				(arc
					(start 302.094138 -311.86247)
					(mid 302.079259 -311.826549)
					(end 302.043338 -311.81167)
				)
				(arc
					(start 300.643798 -311.81167)
					(mid 300.607877 -311.826549)
					(end 300.592998 -311.86247)
				)
			)
		)
	)
	(zone
		(layers "In1.Cu" "In2.Cu")
		(hatch none 0.5)
		(connect_pads
			(clearance 0)
		)
		(min_thickness 0.25)
		(keepout
			(tracks not_allowed)
			(vias allowed)
			(pads allowed)
			(copperpour not_allowed)
			(footprints allowed)
		)
		(placement
			(enabled no)
			(sheetname "")
		)
		(fill yes
			(thermal_gap 0.5)
			(thermal_bridge_width 0.5)
			(island_removal_mode 0)
		)
		(polygon
			(pts
				(arc
					(start 52.65293 -207.721454)
					(mid 52.667809 -207.757375)
					(end 52.70373 -207.772254)
				)
				(arc
					(start 54.10327 -207.772254)
					(mid 54.139191 -207.757375)
					(end 54.15407 -207.721454)
				)
				(arc
					(start 54.15407 -207.312514)
					(mid 54.139191 -207.276593)
					(end 54.10327 -207.261714)
				)
				(arc
					(start 52.70373 -207.261714)
					(mid 52.667809 -207.276593)
					(end 52.65293 -207.312514)
				)
			)
		)
	)
	(zone
		(layers "In1.Cu" "In2.Cu")
		(hatch none 0.5)
		(connect_pads
			(clearance 0)
		)
		(min_thickness 0.25)
		(keepout
			(tracks not_allowed)
			(vias allowed)
			(pads allowed)
			(copperpour not_allowed)
			(footprints allowed)
		)
		(placement
			(enabled no)
			(sheetname "")
		)
		(fill yes
			(thermal_gap 0.5)
			(thermal_bridge_width 0.5)
			(island_removal_mode 0)
		)
		(polygon
			(pts
				(arc
					(start 180.69433 -249.371358)
					(mid 180.709209 -249.407279)
					(end 180.74513 -249.422158)
				)
				(arc
					(start 182.14467 -249.422158)
					(mid 182.180591 -249.407279)
					(end 182.19547 -249.371358)
				)
				(arc
					(start 182.19547 -248.962418)
					(mid 182.180591 -248.926497)
					(end 182.14467 -248.911618)
				)
				(arc
					(start 180.74513 -248.911618)
					(mid 180.709209 -248.926497)
					(end 180.69433 -248.962418)
				)
			)
		)
	)
	(zone
		(layers "In1.Cu" "In2.Cu")
		(hatch none 0.5)
		(connect_pads
			(clearance 0)
		)
		(min_thickness 0.25)
		(keepout
			(tracks not_allowed)
			(vias allowed)
			(pads allowed)
			(copperpour not_allowed)
			(footprints allowed)
		)
		(placement
			(enabled no)
			(sheetname "")
		)
		(fill yes
			(thermal_gap 0.5)
			(thermal_bridge_width 0.5)
			(island_removal_mode 0)
		)
		(polygon
			(pts
				(arc
					(start 421.090598 -210.27136)
					(mid 421.105477 -210.307281)
					(end 421.141398 -210.32216)
				)
				(arc
					(start 422.540938 -210.32216)
					(mid 422.576859 -210.307281)
					(end 422.591738 -210.27136)
				)
				(arc
					(start 422.591738 -209.86242)
					(mid 422.576859 -209.826499)
					(end 422.540938 -209.81162)
				)
				(arc
					(start 421.141398 -209.81162)
					(mid 421.105477 -209.826499)
					(end 421.090598 -209.86242)
				)
			)
		)
	)
	(zone
		(layers "In1.Cu" "In2.Cu")
		(hatch none 0.5)
		(connect_pads
			(clearance 0)
		)
		(min_thickness 0.25)
		(keepout
			(tracks not_allowed)
			(vias allowed)
			(pads allowed)
			(copperpour not_allowed)
			(footprints allowed)
		)
		(placement
			(enabled no)
			(sheetname "")
		)
		(fill yes
			(thermal_gap 0.5)
			(thermal_bridge_width 0.5)
			(island_removal_mode 0)
		)
		(polygon
			(pts
				(arc
					(start 195.78193 -296.121328)
					(mid 195.796809 -296.157249)
					(end 195.83273 -296.172128)
				)
				(arc
					(start 197.23227 -296.172128)
					(mid 197.268191 -296.157249)
					(end 197.28307 -296.121328)
				)
				(arc
					(start 197.28307 -295.712388)
					(mid 197.268191 -295.676467)
					(end 197.23227 -295.661588)
				)
				(arc
					(start 195.83273 -295.661588)
					(mid 195.796809 -295.676467)
					(end 195.78193 -295.712388)
				)
			)
		)
	)
	(zone
		(layers "In1.Cu" "In2.Cu")
		(hatch none 0.5)
		(connect_pads
			(clearance 0)
		)
		(min_thickness 0.25)
		(keepout
			(tracks not_allowed)
			(vias allowed)
			(pads allowed)
			(copperpour not_allowed)
			(footprints allowed)
		)
		(placement
			(enabled no)
			(sheetname "")
		)
		(fill yes
			(thermal_gap 0.5)
			(thermal_bridge_width 0.5)
			(island_removal_mode 0)
		)
		(polygon
			(pts
				(arc
					(start 440.278266 -295.271444)
					(mid 440.293145 -295.307365)
					(end 440.329066 -295.322244)
				)
				(arc
					(start 441.728606 -295.322244)
					(mid 441.764527 -295.307365)
					(end 441.779406 -295.271444)
				)
				(arc
					(start 441.779406 -294.862504)
					(mid 441.764527 -294.826583)
					(end 441.728606 -294.811704)
				)
				(arc
					(start 440.329066 -294.811704)
					(mid 440.293145 -294.826583)
					(end 440.278266 -294.862504)
				)
			)
		)
	)
	(zone
		(layers "In1.Cu" "In2.Cu")
		(hatch none 0.5)
		(connect_pads
			(clearance 0)
		)
		(min_thickness 0.25)
		(keepout
			(tracks not_allowed)
			(vias allowed)
			(pads allowed)
			(copperpour not_allowed)
			(footprints allowed)
		)
		(placement
			(enabled no)
			(sheetname "")
		)
		(fill yes
			(thermal_gap 0.5)
			(thermal_bridge_width 0.5)
			(island_removal_mode 0)
		)
		(polygon
			(pts
				(arc
					(start 289.605466 -212.82152)
					(mid 289.620345 -212.857441)
					(end 289.656266 -212.87232)
				)
				(arc
					(start 291.055806 -212.87232)
					(mid 291.091727 -212.857441)
					(end 291.106606 -212.82152)
				)
				(arc
					(start 291.106606 -212.41258)
					(mid 291.091727 -212.376659)
					(end 291.055806 -212.36178)
				)
				(arc
					(start 289.656266 -212.36178)
					(mid 289.620345 -212.376659)
					(end 289.605466 -212.41258)
				)
			)
		)
	)
	(zone
		(layers "In1.Cu" "In2.Cu")
		(hatch none 0.5)
		(connect_pads
			(clearance 0)
		)
		(min_thickness 0.25)
		(keepout
			(tracks not_allowed)
			(vias allowed)
			(pads allowed)
			(copperpour not_allowed)
			(footprints allowed)
		)
		(placement
			(enabled no)
			(sheetname "")
		)
		(fill yes
			(thermal_gap 0.5)
			(thermal_bridge_width 0.5)
			(island_removal_mode 0)
		)
		(polygon
			(pts
				(arc
					(start 165.60673 -316.521338)
					(mid 165.621609 -316.557259)
					(end 165.65753 -316.572138)
				)
				(arc
					(start 167.05707 -316.572138)
					(mid 167.092991 -316.557259)
					(end 167.10787 -316.521338)
				)
				(arc
					(start 167.10787 -316.112398)
					(mid 167.092991 -316.076477)
					(end 167.05707 -316.061598)
				)
				(arc
					(start 165.65753 -316.061598)
					(mid 165.621609 -316.076477)
					(end 165.60673 -316.112398)
				)
			)
		)
	)
	(zone
		(layers "In1.Cu" "In2.Cu")
		(hatch none 0.5)
		(connect_pads
			(clearance 0)
		)
		(min_thickness 0.25)
		(keepout
			(tracks not_allowed)
			(vias allowed)
			(pads allowed)
			(copperpour not_allowed)
			(footprints allowed)
		)
		(placement
			(enabled no)
			(sheetname "")
		)
		(fill yes
			(thermal_gap 0.5)
			(thermal_bridge_width 0.5)
			(island_removal_mode 0)
		)
		(polygon
			(pts
				(arc
					(start 308.136798 -314.821316)
					(mid 308.151677 -314.857237)
					(end 308.187598 -314.872116)
				)
				(arc
					(start 309.587138 -314.872116)
					(mid 309.623059 -314.857237)
					(end 309.637938 -314.821316)
				)
				(arc
					(start 309.637938 -314.412376)
					(mid 309.623059 -314.376455)
					(end 309.587138 -314.361576)
				)
				(arc
					(start 308.187598 -314.361576)
					(mid 308.151677 -314.376455)
					(end 308.136798 -314.412376)
				)
			)
		)
	)
	(zone
		(layers "In1.Cu" "In2.Cu")
		(hatch none 0.5)
		(connect_pads
			(clearance 0)
		)
		(min_thickness 0.25)
		(keepout
			(tracks not_allowed)
			(vias allowed)
			(pads allowed)
			(copperpour not_allowed)
			(footprints allowed)
		)
		(placement
			(enabled no)
			(sheetname "")
		)
		(fill yes
			(thermal_gap 0.5)
			(thermal_bridge_width 0.5)
			(island_removal_mode 0)
		)
		(polygon
			(pts
				(arc
					(start 184.794398 -209.421476)
					(mid 184.809277 -209.457397)
					(end 184.845198 -209.472276)
				)
				(arc
					(start 186.244738 -209.472276)
					(mid 186.280659 -209.457397)
					(end 186.295538 -209.421476)
				)
				(arc
					(start 186.295538 -209.012536)
					(mid 186.280659 -208.976615)
					(end 186.244738 -208.961736)
				)
				(arc
					(start 184.845198 -208.961736)
					(mid 184.809277 -208.976615)
					(end 184.794398 -209.012536)
				)
			)
		)
	)
	(zone
		(layers "In1.Cu" "In2.Cu")
		(hatch none 0.5)
		(connect_pads
			(clearance 0)
		)
		(min_thickness 0.25)
		(keepout
			(tracks not_allowed)
			(vias allowed)
			(pads allowed)
			(copperpour not_allowed)
			(footprints allowed)
		)
		(placement
			(enabled no)
			(sheetname "")
		)
		(fill yes
			(thermal_gap 0.5)
			(thermal_bridge_width 0.5)
			(island_removal_mode 0)
		)
		(polygon
			(pts
				(arc
					(start 451.265798 -264.671302)
					(mid 451.280677 -264.707223)
					(end 451.316598 -264.722102)
				)
				(arc
					(start 452.716138 -264.722102)
					(mid 452.752059 -264.707223)
					(end 452.766938 -264.671302)
				)
				(arc
					(start 452.766938 -264.262362)
					(mid 452.752059 -264.226441)
					(end 452.716138 -264.211562)
				)
				(arc
					(start 451.316598 -264.211562)
					(mid 451.280677 -264.226441)
					(end 451.265798 -264.262362)
				)
			)
		)
	)
	(zone
		(layers "In1.Cu" "In2.Cu")
		(hatch none 0.5)
		(connect_pads
			(clearance 0)
		)
		(min_thickness 0.25)
		(keepout
			(tracks not_allowed)
			(vias allowed)
			(pads allowed)
			(copperpour not_allowed)
			(footprints allowed)
		)
		(placement
			(enabled no)
			(sheetname "")
		)
		(fill yes
			(thermal_gap 0.5)
			(thermal_bridge_width 0.5)
			(island_removal_mode 0)
		)
		(polygon
			(pts
				(arc
					(start 19.033998 -209.421476)
					(mid 19.048877 -209.457397)
					(end 19.084798 -209.472276)
				)
				(arc
					(start 20.484338 -209.472276)
					(mid 20.520259 -209.457397)
					(end 20.535138 -209.421476)
				)
				(arc
					(start 20.535138 -209.012536)
					(mid 20.520259 -208.976615)
					(end 20.484338 -208.961736)
				)
				(arc
					(start 19.084798 -208.961736)
					(mid 19.048877 -208.976615)
					(end 19.033998 -209.012536)
				)
			)
		)
	)
	(zone
		(layers "In1.Cu" "In2.Cu")
		(hatch none 0.5)
		(connect_pads
			(clearance 0)
		)
		(min_thickness 0.25)
		(keepout
			(tracks not_allowed)
			(vias allowed)
			(pads allowed)
			(copperpour not_allowed)
			(footprints allowed)
		)
		(placement
			(enabled no)
			(sheetname "")
		)
		(fill yes
			(thermal_gap 0.5)
			(thermal_bridge_width 0.5)
			(island_removal_mode 0)
		)
		(polygon
			(pts
				(arc
					(start 14.93393 -252.771402)
					(mid 14.948809 -252.807323)
					(end 14.98473 -252.822202)
				)
				(arc
					(start 16.38427 -252.822202)
					(mid 16.420191 -252.807323)
					(end 16.43507 -252.771402)
				)
				(arc
					(start 16.43507 -252.362462)
					(mid 16.420191 -252.326541)
					(end 16.38427 -252.311662)
				)
				(arc
					(start 14.98473 -252.311662)
					(mid 14.948809 -252.326541)
					(end 14.93393 -252.362462)
				)
			)
		)
	)
	(zone
		(layers "In1.Cu" "In2.Cu")
		(hatch none 0.5)
		(connect_pads
			(clearance 0)
		)
		(min_thickness 0.25)
		(keepout
			(tracks not_allowed)
			(vias allowed)
			(pads allowed)
			(copperpour not_allowed)
			(footprints allowed)
		)
		(placement
			(enabled no)
			(sheetname "")
		)
		(fill yes
			(thermal_gap 0.5)
			(thermal_bridge_width 0.5)
			(island_removal_mode 0)
		)
		(polygon
			(pts
				(arc
					(start 184.794398 -300.37151)
					(mid 184.809277 -300.407431)
					(end 184.845198 -300.42231)
				)
				(arc
					(start 186.244738 -300.42231)
					(mid 186.280659 -300.407431)
					(end 186.295538 -300.37151)
				)
				(arc
					(start 186.295538 -299.96257)
					(mid 186.280659 -299.926649)
					(end 186.244738 -299.91177)
				)
				(arc
					(start 184.845198 -299.91177)
					(mid 184.809277 -299.926649)
					(end 184.794398 -299.96257)
				)
			)
		)
	)
	(zone
		(layers "In1.Cu" "In2.Cu")
		(hatch none 0.5)
		(connect_pads
			(clearance 0)
		)
		(min_thickness 0.25)
		(keepout
			(tracks not_allowed)
			(vias allowed)
			(pads allowed)
			(copperpour not_allowed)
			(footprints allowed)
		)
		(placement
			(enabled no)
			(sheetname "")
		)
		(fill yes
			(thermal_gap 0.5)
			(thermal_bridge_width 0.5)
			(island_removal_mode 0)
		)
		(polygon
			(pts
				(arc
					(start 162.162998 -199.221344)
					(mid 162.177877 -199.257265)
					(end 162.213798 -199.272144)
				)
				(arc
					(start 163.613338 -199.272144)
					(mid 163.649259 -199.257265)
					(end 163.664138 -199.221344)
				)
				(arc
					(start 163.664138 -198.812404)
					(mid 163.649259 -198.776483)
					(end 163.613338 -198.761604)
				)
				(arc
					(start 162.213798 -198.761604)
					(mid 162.177877 -198.776483)
					(end 162.162998 -198.812404)
				)
			)
		)
	)
	(zone
		(layers "In1.Cu" "In2.Cu")
		(hatch none 0.5)
		(connect_pads
			(clearance 0)
		)
		(min_thickness 0.25)
		(keepout
			(tracks not_allowed)
			(vias allowed)
			(pads allowed)
			(copperpour not_allowed)
			(footprints allowed)
		)
		(placement
			(enabled no)
			(sheetname "")
		)
		(fill yes
			(thermal_gap 0.5)
			(thermal_bridge_width 0.5)
			(island_removal_mode 0)
		)
		(polygon
			(pts
				(arc
					(start 184.794398 -279.9715)
					(mid 184.809277 -280.007421)
					(end 184.845198 -280.0223)
				)
				(arc
					(start 186.244738 -280.0223)
					(mid 186.280659 -280.007421)
					(end 186.295538 -279.9715)
				)
				(arc
					(start 186.295538 -279.56256)
					(mid 186.280659 -279.526639)
					(end 186.244738 -279.51176)
				)
				(arc
					(start 184.845198 -279.51176)
					(mid 184.809277 -279.526639)
					(end 184.794398 -279.56256)
				)
			)
		)
	)
	(zone
		(layers "In1.Cu" "In2.Cu")
		(hatch none 0.5)
		(connect_pads
			(clearance 0)
		)
		(min_thickness 0.25)
		(keepout
			(tracks not_allowed)
			(vias allowed)
			(pads allowed)
			(copperpour not_allowed)
			(footprints allowed)
		)
		(placement
			(enabled no)
			(sheetname "")
		)
		(fill yes
			(thermal_gap 0.5)
			(thermal_bridge_width 0.5)
			(island_removal_mode 0)
		)
		(polygon
			(pts
				(arc
					(start 440.278266 -289.321494)
					(mid 440.293145 -289.357415)
					(end 440.329066 -289.372294)
				)
				(arc
					(start 441.728606 -289.372294)
					(mid 441.764527 -289.357415)
					(end 441.779406 -289.321494)
				)
				(arc
					(start 441.779406 -288.912554)
					(mid 441.764527 -288.876633)
					(end 441.728606 -288.861754)
				)
				(arc
					(start 440.329066 -288.861754)
					(mid 440.293145 -288.876633)
					(end 440.278266 -288.912554)
				)
			)
		)
	)
	(zone
		(layers "In1.Cu" "In2.Cu")
		(hatch none 0.5)
		(connect_pads
			(clearance 0)
		)
		(min_thickness 0.25)
		(keepout
			(tracks not_allowed)
			(vias allowed)
			(pads allowed)
			(copperpour not_allowed)
			(footprints allowed)
		)
		(placement
			(enabled no)
			(sheetname "")
		)
		(fill yes
			(thermal_gap 0.5)
			(thermal_bridge_width 0.5)
			(island_removal_mode 0)
		)
		(polygon
			(pts
				(arc
					(start 169.706798 -302.921416)
					(mid 169.721677 -302.957337)
					(end 169.757598 -302.972216)
				)
				(arc
					(start 171.157138 -302.972216)
					(mid 171.193059 -302.957337)
					(end 171.207938 -302.921416)
				)
				(arc
					(start 171.207938 -302.512476)
					(mid 171.193059 -302.476555)
					(end 171.157138 -302.461676)
				)
				(arc
					(start 169.757598 -302.461676)
					(mid 169.721677 -302.476555)
					(end 169.706798 -302.512476)
				)
			)
		)
	)
	(zone
		(layers "In1.Cu" "In2.Cu")
		(hatch none 0.5)
		(connect_pads
			(clearance 0)
		)
		(min_thickness 0.25)
		(keepout
			(tracks not_allowed)
			(vias allowed)
			(pads allowed)
			(copperpour not_allowed)
			(footprints allowed)
		)
		(placement
			(enabled no)
			(sheetname "")
		)
		(fill yes
			(thermal_gap 0.5)
			(thermal_bridge_width 0.5)
			(island_removal_mode 0)
		)
		(polygon
			(pts
				(arc
					(start 214.969598 -306.32146)
					(mid 214.984477 -306.357381)
					(end 215.020398 -306.37226)
				)
				(arc
					(start 216.419938 -306.37226)
					(mid 216.455859 -306.357381)
					(end 216.470738 -306.32146)
				)
				(arc
					(start 216.470738 -305.91252)
					(mid 216.455859 -305.876599)
					(end 216.419938 -305.86172)
				)
				(arc
					(start 215.020398 -305.86172)
					(mid 214.984477 -305.876599)
					(end 214.969598 -305.91252)
				)
			)
		)
	)
	(zone
		(layers "In1.Cu" "In2.Cu")
		(hatch none 0.5)
		(connect_pads
			(clearance 0)
		)
		(min_thickness 0.25)
		(keepout
			(tracks not_allowed)
			(vias allowed)
			(pads allowed)
			(copperpour not_allowed)
			(footprints allowed)
		)
		(placement
			(enabled no)
			(sheetname "")
		)
		(fill yes
			(thermal_gap 0.5)
			(thermal_bridge_width 0.5)
			(island_removal_mode 0)
		)
		(polygon
			(pts
				(arc
					(start 443.721998 -291.8714)
					(mid 443.736877 -291.907321)
					(end 443.772798 -291.9222)
				)
				(arc
					(start 445.172338 -291.9222)
					(mid 445.208259 -291.907321)
					(end 445.223138 -291.8714)
				)
				(arc
					(start 445.223138 -291.46246)
					(mid 445.208259 -291.426539)
					(end 445.172338 -291.41166)
				)
				(arc
					(start 443.772798 -291.41166)
					(mid 443.736877 -291.426539)
					(end 443.721998 -291.46246)
				)
			)
		)
	)
	(zone
		(layers "In1.Cu" "In2.Cu")
		(hatch none 0.5)
		(connect_pads
			(clearance 0)
		)
		(min_thickness 0.25)
		(keepout
			(tracks not_allowed)
			(vias allowed)
			(pads allowed)
			(copperpour not_allowed)
			(footprints allowed)
		)
		(placement
			(enabled no)
			(sheetname "")
		)
		(fill yes
			(thermal_gap 0.5)
			(thermal_bridge_width 0.5)
			(island_removal_mode 0)
		)
		(polygon
			(pts
				(arc
					(start 52.65293 -211.971382)
					(mid 52.667809 -212.007303)
					(end 52.70373 -212.022182)
				)
				(arc
					(start 54.10327 -212.022182)
					(mid 54.139191 -212.007303)
					(end 54.15407 -211.971382)
				)
				(arc
					(start 54.15407 -211.562442)
					(mid 54.139191 -211.526521)
					(end 54.10327 -211.511642)
				)
				(arc
					(start 52.70373 -211.511642)
					(mid 52.667809 -211.526521)
					(end 52.65293 -211.562442)
				)
			)
		)
	)
	(zone
		(layers "In1.Cu" "In2.Cu")
		(hatch none 0.5)
		(connect_pads
			(clearance 0)
		)
		(min_thickness 0.25)
		(keepout
			(tracks not_allowed)
			(vias allowed)
			(pads allowed)
			(copperpour not_allowed)
			(footprints allowed)
		)
		(placement
			(enabled no)
			(sheetname "")
		)
		(fill yes
			(thermal_gap 0.5)
			(thermal_bridge_width 0.5)
			(island_removal_mode 0)
		)
		(polygon
			(pts
				(arc
					(start 266.974066 -298.671488)
					(mid 266.988945 -298.707409)
					(end 267.024866 -298.722288)
				)
				(arc
					(start 268.424406 -298.722288)
					(mid 268.460327 -298.707409)
					(end 268.475206 -298.671488)
				)
				(arc
					(start 268.475206 -298.262548)
					(mid 268.460327 -298.226627)
					(end 268.424406 -298.211748)
				)
				(arc
					(start 267.024866 -298.211748)
					(mid 266.988945 -298.226627)
					(end 266.974066 -298.262548)
				)
			)
		)
	)
	(zone
		(layers "In1.Cu" "In2.Cu")
		(hatch none 0.5)
		(connect_pads
			(clearance 0)
		)
		(min_thickness 0.25)
		(keepout
			(tracks not_allowed)
			(vias allowed)
			(pads allowed)
			(copperpour not_allowed)
			(footprints allowed)
		)
		(placement
			(enabled no)
			(sheetname "")
		)
		(fill yes
			(thermal_gap 0.5)
			(thermal_bridge_width 0.5)
			(island_removal_mode 0)
		)
		(polygon
			(pts
				(arc
					(start 410.103066 -220.471492)
					(mid 410.117945 -220.507413)
					(end 410.153866 -220.522292)
				)
				(arc
					(start 411.553406 -220.522292)
					(mid 411.589327 -220.507413)
					(end 411.604206 -220.471492)
				)
				(arc
					(start 411.604206 -220.062552)
					(mid 411.589327 -220.026631)
					(end 411.553406 -220.011752)
				)
				(arc
					(start 410.153866 -220.011752)
					(mid 410.117945 -220.026631)
					(end 410.103066 -220.062552)
				)
			)
		)
	)
	(zone
		(layers "In1.Cu" "In2.Cu")
		(hatch none 0.5)
		(connect_pads
			(clearance 0)
		)
		(min_thickness 0.25)
		(keepout
			(tracks not_allowed)
			(vias allowed)
			(pads allowed)
			(copperpour not_allowed)
			(footprints allowed)
		)
		(placement
			(enabled no)
			(sheetname "")
		)
		(fill yes
			(thermal_gap 0.5)
			(thermal_bridge_width 0.5)
			(island_removal_mode 0)
		)
		(polygon
			(pts
				(arc
					(start 451.265798 -245.971314)
					(mid 451.280677 -246.007235)
					(end 451.316598 -246.022114)
				)
				(arc
					(start 452.716138 -246.022114)
					(mid 452.752059 -246.007235)
					(end 452.766938 -245.971314)
				)
				(arc
					(start 452.766938 -245.562374)
					(mid 452.752059 -245.526453)
					(end 452.716138 -245.511574)
				)
				(arc
					(start 451.316598 -245.511574)
					(mid 451.280677 -245.526453)
					(end 451.265798 -245.562374)
				)
			)
		)
	)
	(zone
		(layers "In1.Cu" "In2.Cu")
		(hatch none 0.5)
		(connect_pads
			(clearance 0)
		)
		(min_thickness 0.25)
		(keepout
			(tracks not_allowed)
			(vias allowed)
			(pads allowed)
			(copperpour not_allowed)
			(footprints allowed)
		)
		(placement
			(enabled no)
			(sheetname "")
		)
		(fill yes
			(thermal_gap 0.5)
			(thermal_bridge_width 0.5)
			(island_removal_mode 0)
		)
		(polygon
			(pts
				(arc
					(start 188.23813 -228.971348)
					(mid 188.253009 -229.007269)
					(end 188.28893 -229.022148)
				)
				(arc
					(start 189.68847 -229.022148)
					(mid 189.724391 -229.007269)
					(end 189.73927 -228.971348)
				)
				(arc
					(start 189.73927 -228.562408)
					(mid 189.724391 -228.526487)
					(end 189.68847 -228.511608)
				)
				(arc
					(start 188.28893 -228.511608)
					(mid 188.253009 -228.526487)
					(end 188.23813 -228.562408)
				)
			)
		)
	)
	(zone
		(layers "In1.Cu" "In2.Cu")
		(hatch none 0.5)
		(connect_pads
			(clearance 0)
		)
		(min_thickness 0.25)
		(keepout
			(tracks not_allowed)
			(vias allowed)
			(pads allowed)
			(copperpour not_allowed)
			(footprints allowed)
		)
		(placement
			(enabled no)
			(sheetname "")
		)
		(fill yes
			(thermal_gap 0.5)
			(thermal_bridge_width 0.5)
			(island_removal_mode 0)
		)
		(polygon
			(pts
				(arc
					(start 255.330198 -308.871366)
					(mid 255.345077 -308.907287)
					(end 255.380998 -308.922166)
				)
				(arc
					(start 256.780538 -308.922166)
					(mid 256.816459 -308.907287)
					(end 256.831338 -308.871366)
				)
				(arc
					(start 256.831338 -308.462426)
					(mid 256.816459 -308.426505)
					(end 256.780538 -308.411626)
				)
				(arc
					(start 255.380998 -308.411626)
					(mid 255.345077 -308.426505)
					(end 255.330198 -308.462426)
				)
			)
		)
	)
	(zone
		(layers "In1.Cu" "In2.Cu")
		(hatch none 0.5)
		(connect_pads
			(clearance 0)
		)
		(min_thickness 0.25)
		(keepout
			(tracks not_allowed)
			(vias allowed)
			(pads allowed)
			(copperpour not_allowed)
			(footprints allowed)
		)
		(placement
			(enabled no)
			(sheetname "")
		)
		(fill yes
			(thermal_gap 0.5)
			(thermal_bridge_width 0.5)
			(island_removal_mode 0)
		)
		(polygon
			(pts
				(arc
					(start 162.162998 -233.22153)
					(mid 162.177877 -233.257451)
					(end 162.213798 -233.27233)
				)
				(arc
					(start 163.613338 -233.27233)
					(mid 163.649259 -233.257451)
					(end 163.664138 -233.22153)
				)
				(arc
					(start 163.664138 -232.81259)
					(mid 163.649259 -232.776669)
					(end 163.613338 -232.76179)
				)
				(arc
					(start 162.213798 -232.76179)
					(mid 162.177877 -232.776669)
					(end 162.162998 -232.81259)
				)
			)
		)
	)
	(zone
		(layers "In1.Cu" "In2.Cu")
		(hatch none 0.5)
		(connect_pads
			(clearance 0)
		)
		(min_thickness 0.25)
		(keepout
			(tracks not_allowed)
			(vias allowed)
			(pads allowed)
			(copperpour not_allowed)
			(footprints allowed)
		)
		(placement
			(enabled no)
			(sheetname "")
		)
		(fill yes
			(thermal_gap 0.5)
			(thermal_bridge_width 0.5)
			(island_removal_mode 0)
		)
		(polygon
			(pts
				(arc
					(start 308.136798 -200.071482)
					(mid 308.151677 -200.107403)
					(end 308.187598 -200.122282)
				)
				(arc
					(start 309.587138 -200.122282)
					(mid 309.623059 -200.107403)
					(end 309.637938 -200.071482)
				)
				(arc
					(start 309.637938 -199.662542)
					(mid 309.623059 -199.626621)
					(end 309.587138 -199.611742)
				)
				(arc
					(start 308.187598 -199.611742)
					(mid 308.151677 -199.626621)
					(end 308.136798 -199.662542)
				)
			)
		)
	)
	(zone
		(layers "In1.Cu" "In2.Cu")
		(hatch none 0.5)
		(connect_pads
			(clearance 0)
		)
		(min_thickness 0.25)
		(keepout
			(tracks not_allowed)
			(vias allowed)
			(pads allowed)
			(copperpour not_allowed)
			(footprints allowed)
		)
		(placement
			(enabled no)
			(sheetname "")
		)
		(fill yes
			(thermal_gap 0.5)
			(thermal_bridge_width 0.5)
			(island_removal_mode 0)
		)
		(polygon
			(pts
				(arc
					(start 214.969598 -295.271444)
					(mid 214.984477 -295.307365)
					(end 215.020398 -295.322244)
				)
				(arc
					(start 216.419938 -295.322244)
					(mid 216.455859 -295.307365)
					(end 216.470738 -295.271444)
				)
				(arc
					(start 216.470738 -294.862504)
					(mid 216.455859 -294.826583)
					(end 216.419938 -294.811704)
				)
				(arc
					(start 215.020398 -294.811704)
					(mid 214.984477 -294.826583)
					(end 214.969598 -294.862504)
				)
			)
		)
	)
	(zone
		(layers "In1.Cu" "In2.Cu")
		(hatch none 0.5)
		(connect_pads
			(clearance 0)
		)
		(min_thickness 0.25)
		(keepout
			(tracks not_allowed)
			(vias allowed)
			(pads allowed)
			(copperpour not_allowed)
			(footprints allowed)
		)
		(placement
			(enabled no)
			(sheetname "")
		)
		(fill yes
			(thermal_gap 0.5)
			(thermal_bridge_width 0.5)
			(island_removal_mode 0)
		)
		(polygon
			(pts
				(arc
					(start 285.505398 -245.971314)
					(mid 285.520277 -246.007235)
					(end 285.556198 -246.022114)
				)
				(arc
					(start 286.955738 -246.022114)
					(mid 286.991659 -246.007235)
					(end 287.006538 -245.971314)
				)
				(arc
					(start 287.006538 -245.562374)
					(mid 286.991659 -245.526453)
					(end 286.955738 -245.511574)
				)
				(arc
					(start 285.556198 -245.511574)
					(mid 285.520277 -245.526453)
					(end 285.505398 -245.562374)
				)
			)
		)
	)
	(zone
		(layers "In1.Cu" "In2.Cu")
		(hatch none 0.5)
		(connect_pads
			(clearance 0)
		)
		(min_thickness 0.25)
		(keepout
			(tracks not_allowed)
			(vias allowed)
			(pads allowed)
			(copperpour not_allowed)
			(footprints allowed)
		)
		(placement
			(enabled no)
			(sheetname "")
		)
		(fill yes
			(thermal_gap 0.5)
			(thermal_bridge_width 0.5)
			(island_removal_mode 0)
		)
		(polygon
			(pts
				(arc
					(start 255.330198 -230.67137)
					(mid 255.345077 -230.707291)
					(end 255.380998 -230.72217)
				)
				(arc
					(start 256.780538 -230.72217)
					(mid 256.816459 -230.707291)
					(end 256.831338 -230.67137)
				)
				(arc
					(start 256.831338 -230.26243)
					(mid 256.816459 -230.226509)
					(end 256.780538 -230.21163)
				)
				(arc
					(start 255.380998 -230.21163)
					(mid 255.345077 -230.226509)
					(end 255.330198 -230.26243)
				)
			)
		)
	)
	(zone
		(layers "In1.Cu" "In2.Cu")
		(hatch none 0.5)
		(connect_pads
			(clearance 0)
		)
		(min_thickness 0.25)
		(keepout
			(tracks not_allowed)
			(vias allowed)
			(pads allowed)
			(copperpour not_allowed)
			(footprints allowed)
		)
		(placement
			(enabled no)
			(sheetname "")
		)
		(fill yes
			(thermal_gap 0.5)
			(thermal_bridge_width 0.5)
			(island_removal_mode 0)
		)
		(polygon
			(pts
				(arc
					(start 45.10913 -237.471458)
					(mid 45.124009 -237.507379)
					(end 45.15993 -237.522258)
				)
				(arc
					(start 46.55947 -237.522258)
					(mid 46.595391 -237.507379)
					(end 46.61027 -237.471458)
				)
				(arc
					(start 46.61027 -237.062518)
					(mid 46.595391 -237.026597)
					(end 46.55947 -237.011718)
				)
				(arc
					(start 45.15993 -237.011718)
					(mid 45.124009 -237.026597)
					(end 45.10913 -237.062518)
				)
			)
		)
	)
	(zone
		(layers "In1.Cu" "In2.Cu")
		(hatch none 0.5)
		(connect_pads
			(clearance 0)
		)
		(min_thickness 0.25)
		(keepout
			(tracks not_allowed)
			(vias allowed)
			(pads allowed)
			(copperpour not_allowed)
			(footprints allowed)
		)
		(placement
			(enabled no)
			(sheetname "")
		)
		(fill yes
			(thermal_gap 0.5)
			(thermal_bridge_width 0.5)
			(island_removal_mode 0)
		)
		(polygon
			(pts
				(arc
					(start 192.338198 -223.871536)
					(mid 192.353077 -223.907457)
					(end 192.388998 -223.922336)
				)
				(arc
					(start 193.788538 -223.922336)
					(mid 193.824459 -223.907457)
					(end 193.839338 -223.871536)
				)
				(arc
					(start 193.839338 -223.462596)
					(mid 193.824459 -223.426675)
					(end 193.788538 -223.411796)
				)
				(arc
					(start 192.388998 -223.411796)
					(mid 192.353077 -223.426675)
					(end 192.338198 -223.462596)
				)
			)
		)
	)
	(zone
		(layers "In1.Cu" "In2.Cu")
		(hatch none 0.5)
		(connect_pads
			(clearance 0)
		)
		(min_thickness 0.25)
		(keepout
			(tracks not_allowed)
			(vias allowed)
			(pads allowed)
			(copperpour not_allowed)
			(footprints allowed)
		)
		(placement
			(enabled no)
			(sheetname "")
		)
		(fill yes
			(thermal_gap 0.5)
			(thermal_bridge_width 0.5)
			(island_removal_mode 0)
		)
		(polygon
			(pts
				(arc
					(start 22.47773 -206.021432)
					(mid 22.492609 -206.057353)
					(end 22.52853 -206.072232)
				)
				(arc
					(start 23.92807 -206.072232)
					(mid 23.963991 -206.057353)
					(end 23.97887 -206.021432)
				)
				(arc
					(start 23.97887 -205.612492)
					(mid 23.963991 -205.576571)
					(end 23.92807 -205.561692)
				)
				(arc
					(start 22.52853 -205.561692)
					(mid 22.492609 -205.576571)
					(end 22.47773 -205.612492)
				)
			)
		)
	)
	(zone
		(layers "In1.Cu" "In2.Cu")
		(hatch none 0.5)
		(connect_pads
			(clearance 0)
		)
		(min_thickness 0.25)
		(keepout
			(tracks not_allowed)
			(vias allowed)
			(pads allowed)
			(copperpour not_allowed)
			(footprints allowed)
		)
		(placement
			(enabled no)
			(sheetname "")
		)
		(fill yes
			(thermal_gap 0.5)
			(thermal_bridge_width 0.5)
			(island_removal_mode 0)
		)
		(polygon
			(pts
				(arc
					(start 165.60673 -226.421442)
					(mid 165.621609 -226.457363)
					(end 165.65753 -226.472242)
				)
				(arc
					(start 167.05707 -226.472242)
					(mid 167.092991 -226.457363)
					(end 167.10787 -226.421442)
				)
				(arc
					(start 167.10787 -226.012502)
					(mid 167.092991 -225.976581)
					(end 167.05707 -225.961702)
				)
				(arc
					(start 165.65753 -225.961702)
					(mid 165.621609 -225.976581)
					(end 165.60673 -226.012502)
				)
			)
		)
	)
	(zone
		(layers "In1.Cu" "In2.Cu")
		(hatch none 0.5)
		(connect_pads
			(clearance 0)
		)
		(min_thickness 0.25)
		(keepout
			(tracks not_allowed)
			(vias allowed)
			(pads allowed)
			(copperpour not_allowed)
			(footprints allowed)
		)
		(placement
			(enabled no)
			(sheetname "")
		)
		(fill yes
			(thermal_gap 0.5)
			(thermal_bridge_width 0.5)
			(island_removal_mode 0)
		)
		(polygon
			(pts
				(arc
					(start 300.592998 -301.221394)
					(mid 300.607877 -301.257315)
					(end 300.643798 -301.272194)
				)
				(arc
					(start 302.043338 -301.272194)
					(mid 302.079259 -301.257315)
					(end 302.094138 -301.221394)
				)
				(arc
					(start 302.094138 -300.812454)
					(mid 302.079259 -300.776533)
					(end 302.043338 -300.761654)
				)
				(arc
					(start 300.643798 -300.761654)
					(mid 300.607877 -300.776533)
					(end 300.592998 -300.812454)
				)
			)
		)
	)
	(zone
		(layers "In1.Cu" "In2.Cu")
		(hatch none 0.5)
		(connect_pads
			(clearance 0)
		)
		(min_thickness 0.25)
		(keepout
			(tracks not_allowed)
			(vias allowed)
			(pads allowed)
			(copperpour not_allowed)
			(footprints allowed)
		)
		(placement
			(enabled no)
			(sheetname "")
		)
		(fill yes
			(thermal_gap 0.5)
			(thermal_bridge_width 0.5)
			(island_removal_mode 0)
		)
		(polygon
			(pts
				(arc
					(start 262.873998 -198.37146)
					(mid 262.888877 -198.407381)
					(end 262.924798 -198.42226)
				)
				(arc
					(start 264.324338 -198.42226)
					(mid 264.360259 -198.407381)
					(end 264.375138 -198.37146)
				)
				(arc
					(start 264.375138 -197.96252)
					(mid 264.360259 -197.926599)
					(end 264.324338 -197.91172)
				)
				(arc
					(start 262.924798 -197.91172)
					(mid 262.888877 -197.926599)
					(end 262.873998 -197.96252)
				)
			)
		)
	)
	(zone
		(layers "In1.Cu" "In2.Cu")
		(hatch none 0.5)
		(connect_pads
			(clearance 0)
		)
		(min_thickness 0.25)
		(keepout
			(tracks not_allowed)
			(vias allowed)
			(pads allowed)
			(copperpour not_allowed)
			(footprints allowed)
		)
		(placement
			(enabled no)
			(sheetname "")
		)
		(fill yes
			(thermal_gap 0.5)
			(thermal_bridge_width 0.5)
			(island_removal_mode 0)
		)
		(polygon
			(pts
				(arc
					(start 177.250598 -223.871536)
					(mid 177.265477 -223.907457)
					(end 177.301398 -223.922336)
				)
				(arc
					(start 178.700938 -223.922336)
					(mid 178.736859 -223.907457)
					(end 178.751738 -223.871536)
				)
				(arc
					(start 178.751738 -223.462596)
					(mid 178.736859 -223.426675)
					(end 178.700938 -223.411796)
				)
				(arc
					(start 177.301398 -223.411796)
					(mid 177.265477 -223.426675)
					(end 177.250598 -223.462596)
				)
			)
		)
	)
	(zone
		(layers "In1.Cu" "In2.Cu")
		(hatch none 0.5)
		(connect_pads
			(clearance 0)
		)
		(min_thickness 0.25)
		(keepout
			(tracks not_allowed)
			(vias allowed)
			(pads allowed)
			(copperpour not_allowed)
			(footprints allowed)
		)
		(placement
			(enabled no)
			(sheetname "")
		)
		(fill yes
			(thermal_gap 0.5)
			(thermal_bridge_width 0.5)
			(island_removal_mode 0)
		)
		(polygon
			(pts
				(arc
					(start 56.752998 -312.27141)
					(mid 56.767877 -312.307331)
					(end 56.803798 -312.32221)
				)
				(arc
					(start 58.203338 -312.32221)
					(mid 58.239259 -312.307331)
					(end 58.254138 -312.27141)
				)
				(arc
					(start 58.254138 -311.86247)
					(mid 58.239259 -311.826549)
					(end 58.203338 -311.81167)
				)
				(arc
					(start 56.803798 -311.81167)
					(mid 56.767877 -311.826549)
					(end 56.752998 -311.86247)
				)
			)
		)
	)
	(zone
		(layers "In1.Cu" "In2.Cu")
		(hatch none 0.5)
		(connect_pads
			(clearance 0)
		)
		(min_thickness 0.25)
		(keepout
			(tracks not_allowed)
			(vias allowed)
			(pads allowed)
			(copperpour not_allowed)
			(footprints allowed)
		)
		(placement
			(enabled no)
			(sheetname "")
		)
		(fill yes
			(thermal_gap 0.5)
			(thermal_bridge_width 0.5)
			(island_removal_mode 0)
		)
		(polygon
			(pts
				(arc
					(start 432.734466 -217.921332)
					(mid 432.749345 -217.957253)
					(end 432.785266 -217.972132)
				)
				(arc
					(start 434.184806 -217.972132)
					(mid 434.220727 -217.957253)
					(end 434.235606 -217.921332)
				)
				(arc
					(start 434.235606 -217.512392)
					(mid 434.220727 -217.476471)
					(end 434.184806 -217.461592)
				)
				(arc
					(start 432.785266 -217.461592)
					(mid 432.749345 -217.476471)
					(end 432.734466 -217.512392)
				)
			)
		)
	)
	(zone
		(layers "In1.Cu" "In2.Cu")
		(hatch none 0.5)
		(connect_pads
			(clearance 0)
		)
		(min_thickness 0.25)
		(keepout
			(tracks not_allowed)
			(vias allowed)
			(pads allowed)
			(copperpour not_allowed)
			(footprints allowed)
		)
		(placement
			(enabled no)
			(sheetname "")
		)
		(fill yes
			(thermal_gap 0.5)
			(thermal_bridge_width 0.5)
			(island_removal_mode 0)
		)
		(polygon
			(pts
				(arc
					(start 14.93393 -249.371358)
					(mid 14.948809 -249.407279)
					(end 14.98473 -249.422158)
				)
				(arc
					(start 16.38427 -249.422158)
					(mid 16.420191 -249.407279)
					(end 16.43507 -249.371358)
				)
				(arc
					(start 16.43507 -248.962418)
					(mid 16.420191 -248.926497)
					(end 16.38427 -248.911618)
				)
				(arc
					(start 14.98473 -248.911618)
					(mid 14.948809 -248.926497)
					(end 14.93393 -248.962418)
				)
			)
		)
	)
	(zone
		(layers "In1.Cu" "In2.Cu")
		(hatch none 0.5)
		(connect_pads
			(clearance 0)
		)
		(min_thickness 0.25)
		(keepout
			(tracks not_allowed)
			(vias allowed)
			(pads allowed)
			(copperpour not_allowed)
			(footprints allowed)
		)
		(placement
			(enabled no)
			(sheetname "")
		)
		(fill yes
			(thermal_gap 0.5)
			(thermal_bridge_width 0.5)
			(island_removal_mode 0)
		)
		(polygon
			(pts
				(arc
					(start 177.250598 -248.521474)
					(mid 177.265477 -248.557395)
					(end 177.301398 -248.572274)
				)
				(arc
					(start 178.700938 -248.572274)
					(mid 178.736859 -248.557395)
					(end 178.751738 -248.521474)
				)
				(arc
					(start 178.751738 -248.112534)
					(mid 178.736859 -248.076613)
					(end 178.700938 -248.061734)
				)
				(arc
					(start 177.301398 -248.061734)
					(mid 177.265477 -248.076613)
					(end 177.250598 -248.112534)
				)
			)
		)
	)
	(zone
		(layers "In1.Cu" "In2.Cu")
		(hatch none 0.5)
		(connect_pads
			(clearance 0)
		)
		(min_thickness 0.25)
		(keepout
			(tracks not_allowed)
			(vias allowed)
			(pads allowed)
			(copperpour not_allowed)
			(footprints allowed)
		)
		(placement
			(enabled no)
			(sheetname "")
		)
		(fill yes
			(thermal_gap 0.5)
			(thermal_bridge_width 0.5)
			(island_removal_mode 0)
		)
		(polygon
			(pts
				(arc
					(start 56.752998 -296.971466)
					(mid 56.767877 -297.007387)
					(end 56.803798 -297.022266)
				)
				(arc
					(start 58.203338 -297.022266)
					(mid 58.239259 -297.007387)
					(end 58.254138 -296.971466)
				)
				(arc
					(start 58.254138 -296.562526)
					(mid 58.239259 -296.526605)
					(end 58.203338 -296.511726)
				)
				(arc
					(start 56.803798 -296.511726)
					(mid 56.767877 -296.526605)
					(end 56.752998 -296.562526)
				)
			)
		)
	)
	(zone
		(layers "In1.Cu" "In2.Cu")
		(hatch none 0.5)
		(connect_pads
			(clearance 0)
		)
		(min_thickness 0.25)
		(keepout
			(tracks not_allowed)
			(vias allowed)
			(pads allowed)
			(copperpour not_allowed)
			(footprints allowed)
		)
		(placement
			(enabled no)
			(sheetname "")
		)
		(fill yes
			(thermal_gap 0.5)
			(thermal_bridge_width 0.5)
			(island_removal_mode 0)
		)
		(polygon
			(pts
				(arc
					(start 274.517866 -308.021482)
					(mid 274.532745 -308.057403)
					(end 274.568666 -308.072282)
				)
				(arc
					(start 275.968206 -308.072282)
					(mid 276.004127 -308.057403)
					(end 276.019006 -308.021482)
				)
				(arc
					(start 276.019006 -307.612542)
					(mid 276.004127 -307.576621)
					(end 275.968206 -307.561742)
				)
				(arc
					(start 274.568666 -307.561742)
					(mid 274.532745 -307.576621)
					(end 274.517866 -307.612542)
				)
			)
		)
	)
	(zone
		(layers "In1.Cu" "In2.Cu")
		(hatch none 0.5)
		(connect_pads
			(clearance 0)
		)
		(min_thickness 0.25)
		(keepout
			(tracks not_allowed)
			(vias allowed)
			(pads allowed)
			(copperpour not_allowed)
			(footprints allowed)
		)
		(placement
			(enabled no)
			(sheetname "")
		)
		(fill yes
			(thermal_gap 0.5)
			(thermal_bridge_width 0.5)
			(island_removal_mode 0)
		)
		(polygon
			(pts
				(arc
					(start 49.209198 -295.271444)
					(mid 49.224077 -295.307365)
					(end 49.259998 -295.322244)
				)
				(arc
					(start 50.659538 -295.322244)
					(mid 50.695459 -295.307365)
					(end 50.710338 -295.271444)
				)
				(arc
					(start 50.710338 -294.862504)
					(mid 50.695459 -294.826583)
					(end 50.659538 -294.811704)
				)
				(arc
					(start 49.259998 -294.811704)
					(mid 49.224077 -294.826583)
					(end 49.209198 -294.862504)
				)
			)
		)
	)
	(zone
		(layers "In1.Cu" "In2.Cu")
		(hatch none 0.5)
		(connect_pads
			(clearance 0)
		)
		(min_thickness 0.25)
		(keepout
			(tracks not_allowed)
			(vias allowed)
			(pads allowed)
			(copperpour not_allowed)
			(footprints allowed)
		)
		(placement
			(enabled no)
			(sheetname "")
		)
		(fill yes
			(thermal_gap 0.5)
			(thermal_bridge_width 0.5)
			(island_removal_mode 0)
		)
		(polygon
			(pts
				(arc
					(start 169.706798 -209.421476)
					(mid 169.721677 -209.457397)
					(end 169.757598 -209.472276)
				)
				(arc
					(start 171.157138 -209.472276)
					(mid 171.193059 -209.457397)
					(end 171.207938 -209.421476)
				)
				(arc
					(start 171.207938 -209.012536)
					(mid 171.193059 -208.976615)
					(end 171.157138 -208.961736)
				)
				(arc
					(start 169.757598 -208.961736)
					(mid 169.721677 -208.976615)
					(end 169.706798 -209.012536)
				)
			)
		)
	)
	(zone
		(layers "In1.Cu" "In2.Cu")
		(hatch none 0.5)
		(connect_pads
			(clearance 0)
		)
		(min_thickness 0.25)
		(keepout
			(tracks not_allowed)
			(vias allowed)
			(pads allowed)
			(copperpour not_allowed)
			(footprints allowed)
		)
		(placement
			(enabled no)
			(sheetname "")
		)
		(fill yes
			(thermal_gap 0.5)
			(thermal_bridge_width 0.5)
			(island_removal_mode 0)
		)
		(polygon
			(pts
				(arc
					(start 177.250598 -200.071482)
					(mid 177.265477 -200.107403)
					(end 177.301398 -200.122282)
				)
				(arc
					(start 178.700938 -200.122282)
					(mid 178.736859 -200.107403)
					(end 178.751738 -200.071482)
				)
				(arc
					(start 178.751738 -199.662542)
					(mid 178.736859 -199.626621)
					(end 178.700938 -199.611742)
				)
				(arc
					(start 177.301398 -199.611742)
					(mid 177.265477 -199.626621)
					(end 177.250598 -199.662542)
				)
			)
		)
	)
	(zone
		(layers "In1.Cu" "In2.Cu")
		(hatch none 0.5)
		(connect_pads
			(clearance 0)
		)
		(min_thickness 0.25)
		(keepout
			(tracks not_allowed)
			(vias allowed)
			(pads allowed)
			(copperpour not_allowed)
			(footprints allowed)
		)
		(placement
			(enabled no)
			(sheetname "")
		)
		(fill yes
			(thermal_gap 0.5)
			(thermal_bridge_width 0.5)
			(island_removal_mode 0)
		)
		(polygon
			(pts
				(arc
					(start 30.02153 -277.42134)
					(mid 30.036409 -277.457261)
					(end 30.07233 -277.47214)
				)
				(arc
					(start 31.47187 -277.47214)
					(mid 31.507791 -277.457261)
					(end 31.52267 -277.42134)
				)
				(arc
					(start 31.52267 -277.0124)
					(mid 31.507791 -276.976479)
					(end 31.47187 -276.9616)
				)
				(arc
					(start 30.07233 -276.9616)
					(mid 30.036409 -276.976479)
					(end 30.02153 -277.0124)
				)
			)
		)
	)
	(zone
		(layers "In1.Cu" "In2.Cu")
		(hatch none 0.5)
		(connect_pads
			(clearance 0)
		)
		(min_thickness 0.25)
		(keepout
			(tracks not_allowed)
			(vias allowed)
			(pads allowed)
			(copperpour not_allowed)
			(footprints allowed)
		)
		(placement
			(enabled no)
			(sheetname "")
		)
		(fill yes
			(thermal_gap 0.5)
			(thermal_bridge_width 0.5)
			(island_removal_mode 0)
		)
		(polygon
			(pts
				(arc
					(start 173.15053 -285.071312)
					(mid 173.165409 -285.107233)
					(end 173.20133 -285.122112)
				)
				(arc
					(start 174.60087 -285.122112)
					(mid 174.636791 -285.107233)
					(end 174.65167 -285.071312)
				)
				(arc
					(start 174.65167 -284.662372)
					(mid 174.636791 -284.626451)
					(end 174.60087 -284.611572)
				)
				(arc
					(start 173.20133 -284.611572)
					(mid 173.165409 -284.626451)
					(end 173.15053 -284.662372)
				)
			)
		)
	)
	(zone
		(layers "In1.Cu" "In2.Cu")
		(hatch none 0.5)
		(connect_pads
			(clearance 0)
		)
		(min_thickness 0.25)
		(keepout
			(tracks not_allowed)
			(vias allowed)
			(pads allowed)
			(copperpour not_allowed)
			(footprints allowed)
		)
		(placement
			(enabled no)
			(sheetname "")
		)
		(fill yes
			(thermal_gap 0.5)
			(thermal_bridge_width 0.5)
			(island_removal_mode 0)
		)
		(polygon
			(pts
				(arc
					(start 49.209198 -315.671454)
					(mid 49.224077 -315.707375)
					(end 49.259998 -315.722254)
				)
				(arc
					(start 50.659538 -315.722254)
					(mid 50.695459 -315.707375)
					(end 50.710338 -315.671454)
				)
				(arc
					(start 50.710338 -315.262514)
					(mid 50.695459 -315.226593)
					(end 50.659538 -315.211714)
				)
				(arc
					(start 49.259998 -315.211714)
					(mid 49.224077 -315.226593)
					(end 49.209198 -315.262514)
				)
			)
		)
	)
	(zone
		(layers "In1.Cu" "In2.Cu")
		(hatch none 0.5)
		(connect_pads
			(clearance 0)
		)
		(min_thickness 0.25)
		(keepout
			(tracks not_allowed)
			(vias allowed)
			(pads allowed)
			(copperpour not_allowed)
			(footprints allowed)
		)
		(placement
			(enabled no)
			(sheetname "")
		)
		(fill yes
			(thermal_gap 0.5)
			(thermal_bridge_width 0.5)
			(island_removal_mode 0)
		)
		(polygon
			(pts
				(arc
					(start 192.338198 -287.621472)
					(mid 192.353077 -287.657393)
					(end 192.388998 -287.672272)
				)
				(arc
					(start 193.788538 -287.672272)
					(mid 193.824459 -287.657393)
					(end 193.839338 -287.621472)
				)
				(arc
					(start 193.839338 -287.212532)
					(mid 193.824459 -287.176611)
					(end 193.788538 -287.161732)
				)
				(arc
					(start 192.388998 -287.161732)
					(mid 192.353077 -287.176611)
					(end 192.338198 -287.212532)
				)
			)
		)
	)
	(zone
		(layers "In1.Cu" "In2.Cu")
		(hatch none 0.5)
		(connect_pads
			(clearance 0)
		)
		(min_thickness 0.25)
		(keepout
			(tracks not_allowed)
			(vias allowed)
			(pads allowed)
			(copperpour not_allowed)
			(footprints allowed)
		)
		(placement
			(enabled no)
			(sheetname "")
		)
		(fill yes
			(thermal_gap 0.5)
			(thermal_bridge_width 0.5)
			(island_removal_mode 0)
		)
		(polygon
			(pts
				(arc
					(start 162.162998 -300.37151)
					(mid 162.177877 -300.407431)
					(end 162.213798 -300.42231)
				)
				(arc
					(start 163.613338 -300.42231)
					(mid 163.649259 -300.407431)
					(end 163.664138 -300.37151)
				)
				(arc
					(start 163.664138 -299.96257)
					(mid 163.649259 -299.926649)
					(end 163.613338 -299.91177)
				)
				(arc
					(start 162.213798 -299.91177)
					(mid 162.177877 -299.926649)
					(end 162.162998 -299.96257)
				)
			)
		)
	)
	(zone
		(layers "In1.Cu" "In2.Cu")
		(hatch none 0.5)
		(connect_pads
			(clearance 0)
		)
		(min_thickness 0.25)
		(keepout
			(tracks not_allowed)
			(vias allowed)
			(pads allowed)
			(copperpour not_allowed)
			(footprints allowed)
		)
		(placement
			(enabled no)
			(sheetname "")
		)
		(fill yes
			(thermal_gap 0.5)
			(thermal_bridge_width 0.5)
			(island_removal_mode 0)
		)
		(polygon
			(pts
				(arc
					(start 177.250598 -240.871502)
					(mid 177.265477 -240.907423)
					(end 177.301398 -240.922302)
				)
				(arc
					(start 178.700938 -240.922302)
					(mid 178.736859 -240.907423)
					(end 178.751738 -240.871502)
				)
				(arc
					(start 178.751738 -240.462562)
					(mid 178.736859 -240.426641)
					(end 178.700938 -240.411762)
				)
				(arc
					(start 177.301398 -240.411762)
					(mid 177.265477 -240.426641)
					(end 177.250598 -240.462562)
				)
			)
		)
	)
	(zone
		(layers "In1.Cu" "In2.Cu")
		(hatch none 0.5)
		(connect_pads
			(clearance 0)
		)
		(min_thickness 0.25)
		(keepout
			(tracks not_allowed)
			(vias allowed)
			(pads allowed)
			(copperpour not_allowed)
			(footprints allowed)
		)
		(placement
			(enabled no)
			(sheetname "")
		)
		(fill yes
			(thermal_gap 0.5)
			(thermal_bridge_width 0.5)
			(island_removal_mode 0)
		)
		(polygon
			(pts
				(arc
					(start 203.32573 -243.421408)
					(mid 203.340609 -243.457329)
					(end 203.37653 -243.472208)
				)
				(arc
					(start 204.77607 -243.472208)
					(mid 204.811991 -243.457329)
					(end 204.82687 -243.421408)
				)
				(arc
					(start 204.82687 -243.012468)
					(mid 204.811991 -242.976547)
					(end 204.77607 -242.961668)
				)
				(arc
					(start 203.37653 -242.961668)
					(mid 203.340609 -242.976547)
					(end 203.32573 -243.012468)
				)
			)
		)
	)
	(zone
		(layers "In1.Cu" "In2.Cu")
		(hatch none 0.5)
		(connect_pads
			(clearance 0)
		)
		(min_thickness 0.25)
		(keepout
			(tracks not_allowed)
			(vias allowed)
			(pads allowed)
			(copperpour not_allowed)
			(footprints allowed)
		)
		(placement
			(enabled no)
			(sheetname "")
		)
		(fill yes
			(thermal_gap 0.5)
			(thermal_bridge_width 0.5)
			(island_removal_mode 0)
		)
		(polygon
			(pts
				(arc
					(start 274.517866 -223.871536)
					(mid 274.532745 -223.907457)
					(end 274.568666 -223.922336)
				)
				(arc
					(start 275.968206 -223.922336)
					(mid 276.004127 -223.907457)
					(end 276.019006 -223.871536)
				)
				(arc
					(start 276.019006 -223.462596)
					(mid 276.004127 -223.426675)
					(end 275.968206 -223.411796)
				)
				(arc
					(start 274.568666 -223.411796)
					(mid 274.532745 -223.426675)
					(end 274.517866 -223.462596)
				)
			)
		)
	)
	(zone
		(layers "In1.Cu" "In2.Cu")
		(hatch none 0.5)
		(connect_pads
			(clearance 0)
		)
		(min_thickness 0.25)
		(keepout
			(tracks not_allowed)
			(vias allowed)
			(pads allowed)
			(copperpour not_allowed)
			(footprints allowed)
		)
		(placement
			(enabled no)
			(sheetname "")
		)
		(fill yes
			(thermal_gap 0.5)
			(thermal_bridge_width 0.5)
			(island_removal_mode 0)
		)
		(polygon
			(pts
				(arc
					(start 447.822066 -236.62132)
					(mid 447.836945 -236.657241)
					(end 447.872866 -236.67212)
				)
				(arc
					(start 449.272406 -236.67212)
					(mid 449.308327 -236.657241)
					(end 449.323206 -236.62132)
				)
				(arc
					(start 449.323206 -236.21238)
					(mid 449.308327 -236.176459)
					(end 449.272406 -236.16158)
				)
				(arc
					(start 447.872866 -236.16158)
					(mid 447.836945 -236.176459)
					(end 447.822066 -236.21238)
				)
			)
		)
	)
	(zone
		(layers "In1.Cu" "In2.Cu")
		(hatch none 0.5)
		(connect_pads
			(clearance 0)
		)
		(min_thickness 0.25)
		(keepout
			(tracks not_allowed)
			(vias allowed)
			(pads allowed)
			(copperpour not_allowed)
			(footprints allowed)
		)
		(placement
			(enabled no)
			(sheetname "")
		)
		(fill yes
			(thermal_gap 0.5)
			(thermal_bridge_width 0.5)
			(island_removal_mode 0)
		)
		(polygon
			(pts
				(arc
					(start 60.19673 -299.521372)
					(mid 60.211609 -299.557293)
					(end 60.24753 -299.572172)
				)
				(arc
					(start 61.64707 -299.572172)
					(mid 61.682991 -299.557293)
					(end 61.69787 -299.521372)
				)
				(arc
					(start 61.69787 -299.112432)
					(mid 61.682991 -299.076511)
					(end 61.64707 -299.061632)
				)
				(arc
					(start 60.24753 -299.061632)
					(mid 60.211609 -299.076511)
					(end 60.19673 -299.112432)
				)
			)
		)
	)
	(zone
		(layers "In1.Cu" "In2.Cu")
		(hatch none 0.5)
		(connect_pads
			(clearance 0)
		)
		(min_thickness 0.25)
		(keepout
			(tracks not_allowed)
			(vias allowed)
			(pads allowed)
			(copperpour not_allowed)
			(footprints allowed)
		)
		(placement
			(enabled no)
			(sheetname "")
		)
		(fill yes
			(thermal_gap 0.5)
			(thermal_bridge_width 0.5)
			(island_removal_mode 0)
		)
		(polygon
			(pts
				(arc
					(start 277.961598 -259.57149)
					(mid 277.976477 -259.607411)
					(end 278.012398 -259.62229)
				)
				(arc
					(start 279.411938 -259.62229)
					(mid 279.447859 -259.607411)
					(end 279.462738 -259.57149)
				)
				(arc
					(start 279.462738 -259.16255)
					(mid 279.447859 -259.126629)
					(end 279.411938 -259.11175)
				)
				(arc
					(start 278.012398 -259.11175)
					(mid 277.976477 -259.126629)
					(end 277.961598 -259.16255)
				)
			)
		)
	)
	(zone
		(layers "In1.Cu" "In2.Cu")
		(hatch none 0.5)
		(connect_pads
			(clearance 0)
		)
		(min_thickness 0.25)
		(keepout
			(tracks not_allowed)
			(vias allowed)
			(pads allowed)
			(copperpour not_allowed)
			(footprints allowed)
		)
		(placement
			(enabled no)
			(sheetname "")
		)
		(fill yes
			(thermal_gap 0.5)
			(thermal_bridge_width 0.5)
			(island_removal_mode 0)
		)
		(polygon
			(pts
				(arc
					(start 436.178198 -274.871434)
					(mid 436.193077 -274.907355)
					(end 436.228998 -274.922234)
				)
				(arc
					(start 437.628538 -274.922234)
					(mid 437.664459 -274.907355)
					(end 437.679338 -274.871434)
				)
				(arc
					(start 437.679338 -274.462494)
					(mid 437.664459 -274.426573)
					(end 437.628538 -274.411694)
				)
				(arc
					(start 436.228998 -274.411694)
					(mid 436.193077 -274.426573)
					(end 436.178198 -274.462494)
				)
			)
		)
	)
	(zone
		(layers "In1.Cu" "In2.Cu")
		(hatch none 0.5)
		(connect_pads
			(clearance 0)
		)
		(min_thickness 0.25)
		(keepout
			(tracks not_allowed)
			(vias allowed)
			(pads allowed)
			(copperpour not_allowed)
			(footprints allowed)
		)
		(placement
			(enabled no)
			(sheetname "")
		)
		(fill yes
			(thermal_gap 0.5)
			(thermal_bridge_width 0.5)
			(island_removal_mode 0)
		)
		(polygon
			(pts
				(arc
					(start 451.265798 -235.771436)
					(mid 451.280677 -235.807357)
					(end 451.316598 -235.822236)
				)
				(arc
					(start 452.716138 -235.822236)
					(mid 452.752059 -235.807357)
					(end 452.766938 -235.771436)
				)
				(arc
					(start 452.766938 -235.362496)
					(mid 452.752059 -235.326575)
					(end 452.716138 -235.311696)
				)
				(arc
					(start 451.316598 -235.311696)
					(mid 451.280677 -235.326575)
					(end 451.265798 -235.362496)
				)
			)
		)
	)
	(zone
		(layers "In1.Cu" "In2.Cu")
		(hatch none 0.5)
		(connect_pads
			(clearance 0)
		)
		(min_thickness 0.25)
		(keepout
			(tracks not_allowed)
			(vias allowed)
			(pads allowed)
			(copperpour not_allowed)
			(footprints allowed)
		)
		(placement
			(enabled no)
			(sheetname "")
		)
		(fill yes
			(thermal_gap 0.5)
			(thermal_bridge_width 0.5)
			(island_removal_mode 0)
		)
		(polygon
			(pts
				(arc
					(start 436.178198 -294.421306)
					(mid 436.193077 -294.457227)
					(end 436.228998 -294.472106)
				)
				(arc
					(start 437.628538 -294.472106)
					(mid 437.664459 -294.457227)
					(end 437.679338 -294.421306)
				)
				(arc
					(start 437.679338 -294.012366)
					(mid 437.664459 -293.976445)
					(end 437.628538 -293.961566)
				)
				(arc
					(start 436.228998 -293.961566)
					(mid 436.193077 -293.976445)
					(end 436.178198 -294.012366)
				)
			)
		)
	)
	(zone
		(layers "In1.Cu" "In2.Cu")
		(hatch none 0.5)
		(connect_pads
			(clearance 0)
		)
		(min_thickness 0.25)
		(keepout
			(tracks not_allowed)
			(vias allowed)
			(pads allowed)
			(copperpour not_allowed)
			(footprints allowed)
		)
		(placement
			(enabled no)
			(sheetname "")
		)
		(fill yes
			(thermal_gap 0.5)
			(thermal_bridge_width 0.5)
			(island_removal_mode 0)
		)
		(polygon
			(pts
				(arc
					(start 417.646866 -268.921484)
					(mid 417.661745 -268.957405)
					(end 417.697666 -268.972284)
				)
				(arc
					(start 419.097206 -268.972284)
					(mid 419.133127 -268.957405)
					(end 419.148006 -268.921484)
				)
				(arc
					(start 419.148006 -268.512544)
					(mid 419.133127 -268.476623)
					(end 419.097206 -268.461744)
				)
				(arc
					(start 417.697666 -268.461744)
					(mid 417.661745 -268.476623)
					(end 417.646866 -268.512544)
				)
			)
		)
	)
	(zone
		(layers "In1.Cu" "In2.Cu")
		(hatch none 0.5)
		(connect_pads
			(clearance 0)
		)
		(min_thickness 0.25)
		(keepout
			(tracks not_allowed)
			(vias allowed)
			(pads allowed)
			(copperpour not_allowed)
			(footprints allowed)
		)
		(placement
			(enabled no)
			(sheetname "")
		)
		(fill yes
			(thermal_gap 0.5)
			(thermal_bridge_width 0.5)
			(island_removal_mode 0)
		)
		(polygon
			(pts
				(arc
					(start 56.752998 -265.52144)
					(mid 56.767877 -265.557361)
					(end 56.803798 -265.57224)
				)
				(arc
					(start 58.203338 -265.57224)
					(mid 58.239259 -265.557361)
					(end 58.254138 -265.52144)
				)
				(arc
					(start 58.254138 -265.1125)
					(mid 58.239259 -265.076579)
					(end 58.203338 -265.0617)
				)
				(arc
					(start 56.803798 -265.0617)
					(mid 56.767877 -265.076579)
					(end 56.752998 -265.1125)
				)
			)
		)
	)
	(zone
		(layers "In1.Cu" "In2.Cu")
		(hatch none 0.5)
		(connect_pads
			(clearance 0)
		)
		(min_thickness 0.25)
		(keepout
			(tracks not_allowed)
			(vias allowed)
			(pads allowed)
			(copperpour not_allowed)
			(footprints allowed)
		)
		(placement
			(enabled no)
			(sheetname "")
		)
		(fill yes
			(thermal_gap 0.5)
			(thermal_bridge_width 0.5)
			(island_removal_mode 0)
		)
		(polygon
			(pts
				(arc
					(start 162.162998 -209.421476)
					(mid 162.177877 -209.457397)
					(end 162.213798 -209.472276)
				)
				(arc
					(start 163.613338 -209.472276)
					(mid 163.649259 -209.457397)
					(end 163.664138 -209.421476)
				)
				(arc
					(start 163.664138 -209.012536)
					(mid 163.649259 -208.976615)
					(end 163.613338 -208.961736)
				)
				(arc
					(start 162.213798 -208.961736)
					(mid 162.177877 -208.976615)
					(end 162.162998 -209.012536)
				)
			)
		)
	)
	(zone
		(layers "In1.Cu" "In2.Cu")
		(hatch none 0.5)
		(connect_pads
			(clearance 0)
		)
		(min_thickness 0.25)
		(keepout
			(tracks not_allowed)
			(vias allowed)
			(pads allowed)
			(copperpour not_allowed)
			(footprints allowed)
		)
		(placement
			(enabled no)
			(sheetname "")
		)
		(fill yes
			(thermal_gap 0.5)
			(thermal_bridge_width 0.5)
			(island_removal_mode 0)
		)
		(polygon
			(pts
				(arc
					(start 462.909666 -214.521542)
					(mid 462.924545 -214.557463)
					(end 462.960466 -214.572342)
				)
				(arc
					(start 464.360006 -214.572342)
					(mid 464.395927 -214.557463)
					(end 464.410806 -214.521542)
				)
				(arc
					(start 464.410806 -214.112602)
					(mid 464.395927 -214.076681)
					(end 464.360006 -214.061802)
				)
				(arc
					(start 462.960466 -214.061802)
					(mid 462.924545 -214.076681)
					(end 462.909666 -214.112602)
				)
			)
		)
	)
	(zone
		(layers "In1.Cu" "In2.Cu")
		(hatch none 0.5)
		(connect_pads
			(clearance 0)
		)
		(min_thickness 0.25)
		(keepout
			(tracks not_allowed)
			(vias allowed)
			(pads allowed)
			(copperpour not_allowed)
			(footprints allowed)
		)
		(placement
			(enabled no)
			(sheetname "")
		)
		(fill yes
			(thermal_gap 0.5)
			(thermal_bridge_width 0.5)
			(island_removal_mode 0)
		)
		(polygon
			(pts
				(arc
					(start 162.162998 -200.071482)
					(mid 162.177877 -200.107403)
					(end 162.213798 -200.122282)
				)
				(arc
					(start 163.613338 -200.122282)
					(mid 163.649259 -200.107403)
					(end 163.664138 -200.071482)
				)
				(arc
					(start 163.664138 -199.662542)
					(mid 163.649259 -199.626621)
					(end 163.613338 -199.611742)
				)
				(arc
					(start 162.213798 -199.611742)
					(mid 162.177877 -199.626621)
					(end 162.162998 -199.662542)
				)
			)
		)
	)
	(zone
		(layers "In1.Cu" "In2.Cu")
		(hatch none 0.5)
		(connect_pads
			(clearance 0)
		)
		(min_thickness 0.25)
		(keepout
			(tracks not_allowed)
			(vias allowed)
			(pads allowed)
			(copperpour not_allowed)
			(footprints allowed)
		)
		(placement
			(enabled no)
			(sheetname "")
		)
		(fill yes
			(thermal_gap 0.5)
			(thermal_bridge_width 0.5)
			(island_removal_mode 0)
		)
		(polygon
			(pts
				(arc
					(start 41.665398 -274.871434)
					(mid 41.680277 -274.907355)
					(end 41.716198 -274.922234)
				)
				(arc
					(start 43.115738 -274.922234)
					(mid 43.151659 -274.907355)
					(end 43.166538 -274.871434)
				)
				(arc
					(start 43.166538 -274.462494)
					(mid 43.151659 -274.426573)
					(end 43.115738 -274.411694)
				)
				(arc
					(start 41.716198 -274.411694)
					(mid 41.680277 -274.426573)
					(end 41.665398 -274.462494)
				)
			)
		)
	)
	(zone
		(layers "In1.Cu" "In2.Cu")
		(hatch none 0.5)
		(connect_pads
			(clearance 0)
		)
		(min_thickness 0.25)
		(keepout
			(tracks not_allowed)
			(vias allowed)
			(pads allowed)
			(copperpour not_allowed)
			(footprints allowed)
		)
		(placement
			(enabled no)
			(sheetname "")
		)
		(fill yes
			(thermal_gap 0.5)
			(thermal_bridge_width 0.5)
			(island_removal_mode 0)
		)
		(polygon
			(pts
				(arc
					(start 19.033998 -278.271478)
					(mid 19.048877 -278.307399)
					(end 19.084798 -278.322278)
				)
				(arc
					(start 20.484338 -278.322278)
					(mid 20.520259 -278.307399)
					(end 20.535138 -278.271478)
				)
				(arc
					(start 20.535138 -277.862538)
					(mid 20.520259 -277.826617)
					(end 20.484338 -277.811738)
				)
				(arc
					(start 19.084798 -277.811738)
					(mid 19.048877 -277.826617)
					(end 19.033998 -277.862538)
				)
			)
		)
	)
	(zone
		(layers "In1.Cu" "In2.Cu")
		(hatch none 0.5)
		(connect_pads
			(clearance 0)
		)
		(min_thickness 0.25)
		(keepout
			(tracks not_allowed)
			(vias allowed)
			(pads allowed)
			(copperpour not_allowed)
			(footprints allowed)
		)
		(placement
			(enabled no)
			(sheetname "")
		)
		(fill yes
			(thermal_gap 0.5)
			(thermal_bridge_width 0.5)
			(island_removal_mode 0)
		)
		(polygon
			(pts
				(arc
					(start 274.517866 -246.821452)
					(mid 274.532745 -246.857373)
					(end 274.568666 -246.872252)
				)
				(arc
					(start 275.968206 -246.872252)
					(mid 276.004127 -246.857373)
					(end 276.019006 -246.821452)
				)
				(arc
					(start 276.019006 -246.412512)
					(mid 276.004127 -246.376591)
					(end 275.968206 -246.361712)
				)
				(arc
					(start 274.568666 -246.361712)
					(mid 274.532745 -246.376591)
					(end 274.517866 -246.412512)
				)
			)
		)
	)
	(zone
		(layers "In1.Cu" "In2.Cu")
		(hatch none 0.5)
		(connect_pads
			(clearance 0)
		)
		(min_thickness 0.25)
		(keepout
			(tracks not_allowed)
			(vias allowed)
			(pads allowed)
			(copperpour not_allowed)
			(footprints allowed)
		)
		(placement
			(enabled no)
			(sheetname "")
		)
		(fill yes
			(thermal_gap 0.5)
			(thermal_bridge_width 0.5)
			(island_removal_mode 0)
		)
		(polygon
			(pts
				(arc
					(start 455.365866 -283.371544)
					(mid 455.380745 -283.407465)
					(end 455.416666 -283.422344)
				)
				(arc
					(start 456.816206 -283.422344)
					(mid 456.852127 -283.407465)
					(end 456.867006 -283.371544)
				)
				(arc
					(start 456.867006 -282.962604)
					(mid 456.852127 -282.926683)
					(end 456.816206 -282.911804)
				)
				(arc
					(start 455.416666 -282.911804)
					(mid 455.380745 -282.926683)
					(end 455.365866 -282.962604)
				)
			)
		)
	)
	(zone
		(layers "In1.Cu" "In2.Cu")
		(hatch none 0.5)
		(connect_pads
			(clearance 0)
		)
		(min_thickness 0.25)
		(keepout
			(tracks not_allowed)
			(vias allowed)
			(pads allowed)
			(copperpour not_allowed)
			(footprints allowed)
		)
		(placement
			(enabled no)
			(sheetname "")
		)
		(fill yes
			(thermal_gap 0.5)
			(thermal_bridge_width 0.5)
			(island_removal_mode 0)
		)
		(polygon
			(pts
				(arc
					(start 270.417798 -314.821316)
					(mid 270.432677 -314.857237)
					(end 270.468598 -314.872116)
				)
				(arc
					(start 271.868138 -314.872116)
					(mid 271.904059 -314.857237)
					(end 271.918938 -314.821316)
				)
				(arc
					(start 271.918938 -314.412376)
					(mid 271.904059 -314.376455)
					(end 271.868138 -314.361576)
				)
				(arc
					(start 270.468598 -314.361576)
					(mid 270.432677 -314.376455)
					(end 270.417798 -314.412376)
				)
			)
		)
	)
	(zone
		(layers "In1.Cu" "In2.Cu")
		(hatch none 0.5)
		(connect_pads
			(clearance 0)
		)
		(min_thickness 0.25)
		(keepout
			(tracks not_allowed)
			(vias allowed)
			(pads allowed)
			(copperpour not_allowed)
			(footprints allowed)
		)
		(placement
			(enabled no)
			(sheetname "")
		)
		(fill yes
			(thermal_gap 0.5)
			(thermal_bridge_width 0.5)
			(island_removal_mode 0)
		)
		(polygon
			(pts
				(arc
					(start 60.19673 -266.371324)
					(mid 60.211609 -266.407245)
					(end 60.24753 -266.422124)
				)
				(arc
					(start 61.64707 -266.422124)
					(mid 61.682991 -266.407245)
					(end 61.69787 -266.371324)
				)
				(arc
					(start 61.69787 -265.962384)
					(mid 61.682991 -265.926463)
					(end 61.64707 -265.911584)
				)
				(arc
					(start 60.24753 -265.911584)
					(mid 60.211609 -265.926463)
					(end 60.19673 -265.962384)
				)
			)
		)
	)
	(zone
		(layers "In1.Cu" "In2.Cu")
		(hatch none 0.5)
		(connect_pads
			(clearance 0)
		)
		(min_thickness 0.25)
		(keepout
			(tracks not_allowed)
			(vias allowed)
			(pads allowed)
			(copperpour not_allowed)
			(footprints allowed)
		)
		(placement
			(enabled no)
			(sheetname "")
		)
		(fill yes
			(thermal_gap 0.5)
			(thermal_bridge_width 0.5)
			(island_removal_mode 0)
		)
		(polygon
			(pts
				(arc
					(start 192.338198 -236.62132)
					(mid 192.353077 -236.657241)
					(end 192.388998 -236.67212)
				)
				(arc
					(start 193.788538 -236.67212)
					(mid 193.824459 -236.657241)
					(end 193.839338 -236.62132)
				)
				(arc
					(start 193.839338 -236.21238)
					(mid 193.824459 -236.176459)
					(end 193.788538 -236.16158)
				)
				(arc
					(start 192.388998 -236.16158)
					(mid 192.353077 -236.176459)
					(end 192.338198 -236.21238)
				)
			)
		)
	)
	(zone
		(layers "In1.Cu" "In2.Cu")
		(hatch none 0.5)
		(connect_pads
			(clearance 0)
		)
		(min_thickness 0.25)
		(keepout
			(tracks not_allowed)
			(vias allowed)
			(pads allowed)
			(copperpour not_allowed)
			(footprints allowed)
		)
		(placement
			(enabled no)
			(sheetname "")
		)
		(fill yes
			(thermal_gap 0.5)
			(thermal_bridge_width 0.5)
			(island_removal_mode 0)
		)
		(polygon
			(pts
				(arc
					(start 45.10913 -271.47139)
					(mid 45.124009 -271.507311)
					(end 45.15993 -271.52219)
				)
				(arc
					(start 46.55947 -271.52219)
					(mid 46.595391 -271.507311)
					(end 46.61027 -271.47139)
				)
				(arc
					(start 46.61027 -271.06245)
					(mid 46.595391 -271.026529)
					(end 46.55947 -271.01165)
				)
				(arc
					(start 45.15993 -271.01165)
					(mid 45.124009 -271.026529)
					(end 45.10913 -271.06245)
				)
			)
		)
	)
	(zone
		(layers "In1.Cu" "In2.Cu")
		(hatch none 0.5)
		(connect_pads
			(clearance 0)
		)
		(min_thickness 0.25)
		(keepout
			(tracks not_allowed)
			(vias allowed)
			(pads allowed)
			(copperpour not_allowed)
			(footprints allowed)
		)
		(placement
			(enabled no)
			(sheetname "")
		)
		(fill yes
			(thermal_gap 0.5)
			(thermal_bridge_width 0.5)
			(island_removal_mode 0)
		)
		(polygon
			(pts
				(arc
					(start 56.752998 -284.221428)
					(mid 56.767877 -284.257349)
					(end 56.803798 -284.272228)
				)
				(arc
					(start 58.203338 -284.272228)
					(mid 58.239259 -284.257349)
					(end 58.254138 -284.221428)
				)
				(arc
					(start 58.254138 -283.812488)
					(mid 58.239259 -283.776567)
					(end 58.203338 -283.761688)
				)
				(arc
					(start 56.803798 -283.761688)
					(mid 56.767877 -283.776567)
					(end 56.752998 -283.812488)
				)
			)
		)
	)
	(zone
		(layers "In1.Cu" "In2.Cu")
		(hatch none 0.5)
		(connect_pads
			(clearance 0)
		)
		(min_thickness 0.25)
		(keepout
			(tracks not_allowed)
			(vias allowed)
			(pads allowed)
			(copperpour not_allowed)
			(footprints allowed)
		)
		(placement
			(enabled no)
			(sheetname "")
		)
		(fill yes
			(thermal_gap 0.5)
			(thermal_bridge_width 0.5)
			(island_removal_mode 0)
		)
		(polygon
			(pts
				(arc
					(start 458.809598 -224.72142)
					(mid 458.824477 -224.757341)
					(end 458.860398 -224.77222)
				)
				(arc
					(start 460.259938 -224.77222)
					(mid 460.295859 -224.757341)
					(end 460.310738 -224.72142)
				)
				(arc
					(start 460.310738 -224.31248)
					(mid 460.295859 -224.276559)
					(end 460.259938 -224.26168)
				)
				(arc
					(start 458.860398 -224.26168)
					(mid 458.824477 -224.276559)
					(end 458.809598 -224.31248)
				)
			)
		)
	)
	(zone
		(layers "In1.Cu" "In2.Cu")
		(hatch none 0.5)
		(connect_pads
			(clearance 0)
		)
		(min_thickness 0.25)
		(keepout
			(tracks not_allowed)
			(vias allowed)
			(pads allowed)
			(copperpour not_allowed)
			(footprints allowed)
		)
		(placement
			(enabled no)
			(sheetname "")
		)
		(fill yes
			(thermal_gap 0.5)
			(thermal_bridge_width 0.5)
			(island_removal_mode 0)
		)
		(polygon
			(pts
				(arc
					(start 293.049198 -280.821384)
					(mid 293.064077 -280.857305)
					(end 293.099998 -280.872184)
				)
				(arc
					(start 294.499538 -280.872184)
					(mid 294.535459 -280.857305)
					(end 294.550338 -280.821384)
				)
				(arc
					(start 294.550338 -280.412444)
					(mid 294.535459 -280.376523)
					(end 294.499538 -280.361644)
				)
				(arc
					(start 293.099998 -280.361644)
					(mid 293.064077 -280.376523)
					(end 293.049198 -280.412444)
				)
			)
		)
	)
	(zone
		(layers "In1.Cu" "In2.Cu")
		(hatch none 0.5)
		(connect_pads
			(clearance 0)
		)
		(min_thickness 0.25)
		(keepout
			(tracks not_allowed)
			(vias allowed)
			(pads allowed)
			(copperpour not_allowed)
			(footprints allowed)
		)
		(placement
			(enabled no)
			(sheetname "")
		)
		(fill yes
			(thermal_gap 0.5)
			(thermal_bridge_width 0.5)
			(island_removal_mode 0)
		)
		(polygon
			(pts
				(arc
					(start 60.19673 -215.371426)
					(mid 60.211609 -215.407347)
					(end 60.24753 -215.422226)
				)
				(arc
					(start 61.64707 -215.422226)
					(mid 61.682991 -215.407347)
					(end 61.69787 -215.371426)
				)
				(arc
					(start 61.69787 -214.962486)
					(mid 61.682991 -214.926565)
					(end 61.64707 -214.911686)
				)
				(arc
					(start 60.24753 -214.911686)
					(mid 60.211609 -214.926565)
					(end 60.19673 -214.962486)
				)
			)
		)
	)
	(zone
		(layers "In1.Cu" "In2.Cu")
		(hatch none 0.5)
		(connect_pads
			(clearance 0)
		)
		(min_thickness 0.25)
		(keepout
			(tracks not_allowed)
			(vias allowed)
			(pads allowed)
			(copperpour not_allowed)
			(footprints allowed)
		)
		(placement
			(enabled no)
			(sheetname "")
		)
		(fill yes
			(thermal_gap 0.5)
			(thermal_bridge_width 0.5)
			(island_removal_mode 0)
		)
		(polygon
			(pts
				(arc
					(start 64.296798 -284.221428)
					(mid 64.311677 -284.257349)
					(end 64.347598 -284.272228)
				)
				(arc
					(start 65.747138 -284.272228)
					(mid 65.783059 -284.257349)
					(end 65.797938 -284.221428)
				)
				(arc
					(start 65.797938 -283.812488)
					(mid 65.783059 -283.776567)
					(end 65.747138 -283.761688)
				)
				(arc
					(start 64.347598 -283.761688)
					(mid 64.311677 -283.776567)
					(end 64.296798 -283.812488)
				)
			)
		)
	)
	(zone
		(layers "In1.Cu" "In2.Cu")
		(hatch none 0.5)
		(connect_pads
			(clearance 0)
		)
		(min_thickness 0.25)
		(keepout
			(tracks not_allowed)
			(vias allowed)
			(pads allowed)
			(copperpour not_allowed)
			(footprints allowed)
		)
		(placement
			(enabled no)
			(sheetname "")
		)
		(fill yes
			(thermal_gap 0.5)
			(thermal_bridge_width 0.5)
			(island_removal_mode 0)
		)
		(polygon
			(pts
				(arc
					(start 22.47773 -211.971382)
					(mid 22.492609 -212.007303)
					(end 22.52853 -212.022182)
				)
				(arc
					(start 23.92807 -212.022182)
					(mid 23.963991 -212.007303)
					(end 23.97887 -211.971382)
				)
				(arc
					(start 23.97887 -211.562442)
					(mid 23.963991 -211.526521)
					(end 23.92807 -211.511642)
				)
				(arc
					(start 22.52853 -211.511642)
					(mid 22.492609 -211.526521)
					(end 22.47773 -211.562442)
				)
			)
		)
	)
	(zone
		(layers "In1.Cu" "In2.Cu")
		(hatch none 0.5)
		(connect_pads
			(clearance 0)
		)
		(min_thickness 0.25)
		(keepout
			(tracks not_allowed)
			(vias allowed)
			(pads allowed)
			(copperpour not_allowed)
			(footprints allowed)
		)
		(placement
			(enabled no)
			(sheetname "")
		)
		(fill yes
			(thermal_gap 0.5)
			(thermal_bridge_width 0.5)
			(island_removal_mode 0)
		)
		(polygon
			(pts
				(arc
					(start 34.121598 -217.921332)
					(mid 34.136477 -217.957253)
					(end 34.172398 -217.972132)
				)
				(arc
					(start 35.571938 -217.972132)
					(mid 35.607859 -217.957253)
					(end 35.622738 -217.921332)
				)
				(arc
					(start 35.622738 -217.512392)
					(mid 35.607859 -217.476471)
					(end 35.571938 -217.461592)
				)
				(arc
					(start 34.172398 -217.461592)
					(mid 34.136477 -217.476471)
					(end 34.121598 -217.512392)
				)
			)
		)
	)
	(zone
		(layers "In1.Cu" "In2.Cu")
		(hatch none 0.5)
		(connect_pads
			(clearance 0)
		)
		(min_thickness 0.25)
		(keepout
			(tracks not_allowed)
			(vias allowed)
			(pads allowed)
			(copperpour not_allowed)
			(footprints allowed)
		)
		(placement
			(enabled no)
			(sheetname "")
		)
		(fill yes
			(thermal_gap 0.5)
			(thermal_bridge_width 0.5)
			(island_removal_mode 0)
		)
		(polygon
			(pts
				(arc
					(start 49.209198 -216.22131)
					(mid 49.224077 -216.257231)
					(end 49.259998 -216.27211)
				)
				(arc
					(start 50.659538 -216.27211)
					(mid 50.695459 -216.257231)
					(end 50.710338 -216.22131)
				)
				(arc
					(start 50.710338 -215.81237)
					(mid 50.695459 -215.776449)
					(end 50.659538 -215.76157)
				)
				(arc
					(start 49.259998 -215.76157)
					(mid 49.224077 -215.776449)
					(end 49.209198 -215.81237)
				)
			)
		)
	)
	(zone
		(layers "In1.Cu" "In2.Cu")
		(hatch none 0.5)
		(connect_pads
			(clearance 0)
		)
		(min_thickness 0.25)
		(keepout
			(tracks not_allowed)
			(vias allowed)
			(pads allowed)
			(copperpour not_allowed)
			(footprints allowed)
		)
		(placement
			(enabled no)
			(sheetname "")
		)
		(fill yes
			(thermal_gap 0.5)
			(thermal_bridge_width 0.5)
			(island_removal_mode 0)
		)
		(polygon
			(pts
				(arc
					(start 300.592998 -207.721454)
					(mid 300.607877 -207.757375)
					(end 300.643798 -207.772254)
				)
				(arc
					(start 302.043338 -207.772254)
					(mid 302.079259 -207.757375)
					(end 302.094138 -207.721454)
				)
				(arc
					(start 302.094138 -207.312514)
					(mid 302.079259 -207.276593)
					(end 302.043338 -207.261714)
				)
				(arc
					(start 300.643798 -207.261714)
					(mid 300.607877 -207.276593)
					(end 300.592998 -207.312514)
				)
			)
		)
	)
	(zone
		(layers "In1.Cu" "In2.Cu")
		(hatch none 0.5)
		(connect_pads
			(clearance 0)
		)
		(min_thickness 0.25)
		(keepout
			(tracks not_allowed)
			(vias allowed)
			(pads allowed)
			(copperpour not_allowed)
			(footprints allowed)
		)
		(placement
			(enabled no)
			(sheetname "")
		)
		(fill yes
			(thermal_gap 0.5)
			(thermal_bridge_width 0.5)
			(island_removal_mode 0)
		)
		(polygon
			(pts
				(arc
					(start 289.605466 -248.521474)
					(mid 289.620345 -248.557395)
					(end 289.656266 -248.572274)
				)
				(arc
					(start 291.055806 -248.572274)
					(mid 291.091727 -248.557395)
					(end 291.106606 -248.521474)
				)
				(arc
					(start 291.106606 -248.112534)
					(mid 291.091727 -248.076613)
					(end 291.055806 -248.061734)
				)
				(arc
					(start 289.656266 -248.061734)
					(mid 289.620345 -248.076613)
					(end 289.605466 -248.112534)
				)
			)
		)
	)
	(zone
		(layers "In1.Cu" "In2.Cu")
		(hatch none 0.5)
		(connect_pads
			(clearance 0)
		)
		(min_thickness 0.25)
		(keepout
			(tracks not_allowed)
			(vias allowed)
			(pads allowed)
			(copperpour not_allowed)
			(footprints allowed)
		)
		(placement
			(enabled no)
			(sheetname "")
		)
		(fill yes
			(thermal_gap 0.5)
			(thermal_bridge_width 0.5)
			(island_removal_mode 0)
		)
		(polygon
			(pts
				(arc
					(start 177.250598 -311.421526)
					(mid 177.265477 -311.457447)
					(end 177.301398 -311.472326)
				)
				(arc
					(start 178.700938 -311.472326)
					(mid 178.736859 -311.457447)
					(end 178.751738 -311.421526)
				)
				(arc
					(start 178.751738 -311.012586)
					(mid 178.736859 -310.976665)
					(end 178.700938 -310.961786)
				)
				(arc
					(start 177.301398 -310.961786)
					(mid 177.265477 -310.976665)
					(end 177.250598 -311.012586)
				)
			)
		)
	)
	(zone
		(layers "In1.Cu" "In2.Cu")
		(hatch none 0.5)
		(connect_pads
			(clearance 0)
		)
		(min_thickness 0.25)
		(keepout
			(tracks not_allowed)
			(vias allowed)
			(pads allowed)
			(copperpour not_allowed)
			(footprints allowed)
		)
		(placement
			(enabled no)
			(sheetname "")
		)
		(fill yes
			(thermal_gap 0.5)
			(thermal_bridge_width 0.5)
			(island_removal_mode 0)
		)
		(polygon
			(pts
				(arc
					(start 436.178198 -262.971534)
					(mid 436.193077 -263.007455)
					(end 436.228998 -263.022334)
				)
				(arc
					(start 437.628538 -263.022334)
					(mid 437.664459 -263.007455)
					(end 437.679338 -262.971534)
				)
				(arc
					(start 437.679338 -262.562594)
					(mid 437.664459 -262.526673)
					(end 437.628538 -262.511794)
				)
				(arc
					(start 436.228998 -262.511794)
					(mid 436.193077 -262.526673)
					(end 436.178198 -262.562594)
				)
			)
		)
	)
	(zone
		(layers "In1.Cu" "In2.Cu")
		(hatch none 0.5)
		(connect_pads
			(clearance 0)
		)
		(min_thickness 0.25)
		(keepout
			(tracks not_allowed)
			(vias allowed)
			(pads allowed)
			(copperpour not_allowed)
			(footprints allowed)
		)
		(placement
			(enabled no)
			(sheetname "")
		)
		(fill yes
			(thermal_gap 0.5)
			(thermal_bridge_width 0.5)
			(island_removal_mode 0)
		)
		(polygon
			(pts
				(arc
					(start 177.250598 -281.671522)
					(mid 177.265477 -281.707443)
					(end 177.301398 -281.722322)
				)
				(arc
					(start 178.700938 -281.722322)
					(mid 178.736859 -281.707443)
					(end 178.751738 -281.671522)
				)
				(arc
					(start 178.751738 -281.262582)
					(mid 178.736859 -281.226661)
					(end 178.700938 -281.211782)
				)
				(arc
					(start 177.301398 -281.211782)
					(mid 177.265477 -281.226661)
					(end 177.250598 -281.262582)
				)
			)
		)
	)
	(zone
		(layers "In1.Cu" "In2.Cu")
		(hatch none 0.5)
		(connect_pads
			(clearance 0)
		)
		(min_thickness 0.25)
		(keepout
			(tracks not_allowed)
			(vias allowed)
			(pads allowed)
			(copperpour not_allowed)
			(footprints allowed)
		)
		(placement
			(enabled no)
			(sheetname "")
		)
		(fill yes
			(thermal_gap 0.5)
			(thermal_bridge_width 0.5)
			(island_removal_mode 0)
		)
		(polygon
			(pts
				(arc
					(start 60.19673 -285.071312)
					(mid 60.211609 -285.107233)
					(end 60.24753 -285.122112)
				)
				(arc
					(start 61.64707 -285.122112)
					(mid 61.682991 -285.107233)
					(end 61.69787 -285.071312)
				)
				(arc
					(start 61.69787 -284.662372)
					(mid 61.682991 -284.626451)
					(end 61.64707 -284.611572)
				)
				(arc
					(start 60.24753 -284.611572)
					(mid 60.211609 -284.626451)
					(end 60.19673 -284.662372)
				)
			)
		)
	)
	(zone
		(layers "In1.Cu" "In2.Cu")
		(hatch none 0.5)
		(connect_pads
			(clearance 0)
		)
		(min_thickness 0.25)
		(keepout
			(tracks not_allowed)
			(vias allowed)
			(pads allowed)
			(copperpour not_allowed)
			(footprints allowed)
		)
		(placement
			(enabled no)
			(sheetname "")
		)
		(fill yes
			(thermal_gap 0.5)
			(thermal_bridge_width 0.5)
			(island_removal_mode 0)
		)
		(polygon
			(pts
				(arc
					(start 22.47773 -204.32141)
					(mid 22.492609 -204.357331)
					(end 22.52853 -204.37221)
				)
				(arc
					(start 23.92807 -204.37221)
					(mid 23.963991 -204.357331)
					(end 23.97887 -204.32141)
				)
				(arc
					(start 23.97887 -203.91247)
					(mid 23.963991 -203.876549)
					(end 23.92807 -203.86167)
				)
				(arc
					(start 22.52853 -203.86167)
					(mid 22.492609 -203.876549)
					(end 22.47773 -203.91247)
				)
			)
		)
	)
	(zone
		(layers "In1.Cu" "In2.Cu")
		(hatch none 0.5)
		(connect_pads
			(clearance 0)
		)
		(min_thickness 0.25)
		(keepout
			(tracks not_allowed)
			(vias allowed)
			(pads allowed)
			(copperpour not_allowed)
			(footprints allowed)
		)
		(placement
			(enabled no)
			(sheetname "")
		)
		(fill yes
			(thermal_gap 0.5)
			(thermal_bridge_width 0.5)
			(island_removal_mode 0)
		)
		(polygon
			(pts
				(arc
					(start 180.69433 -232.371392)
					(mid 180.709209 -232.407313)
					(end 180.74513 -232.422192)
				)
				(arc
					(start 182.14467 -232.422192)
					(mid 182.180591 -232.407313)
					(end 182.19547 -232.371392)
				)
				(arc
					(start 182.19547 -231.962452)
					(mid 182.180591 -231.926531)
					(end 182.14467 -231.911652)
				)
				(arc
					(start 180.74513 -231.911652)
					(mid 180.709209 -231.926531)
					(end 180.69433 -231.962452)
				)
			)
		)
	)
	(zone
		(layers "In1.Cu" "In2.Cu")
		(hatch none 0.5)
		(connect_pads
			(clearance 0)
		)
		(min_thickness 0.25)
		(keepout
			(tracks not_allowed)
			(vias allowed)
			(pads allowed)
			(copperpour not_allowed)
			(footprints allowed)
		)
		(placement
			(enabled no)
			(sheetname "")
		)
		(fill yes
			(thermal_gap 0.5)
			(thermal_bridge_width 0.5)
			(island_removal_mode 0)
		)
		(polygon
			(pts
				(arc
					(start 37.56533 -286.771334)
					(mid 37.580209 -286.807255)
					(end 37.61613 -286.822134)
				)
				(arc
					(start 39.01567 -286.822134)
					(mid 39.051591 -286.807255)
					(end 39.06647 -286.771334)
				)
				(arc
					(start 39.06647 -286.362394)
					(mid 39.051591 -286.326473)
					(end 39.01567 -286.311594)
				)
				(arc
					(start 37.61613 -286.311594)
					(mid 37.580209 -286.326473)
					(end 37.56533 -286.362394)
				)
			)
		)
	)
	(zone
		(layers "In1.Cu" "In2.Cu")
		(hatch none 0.5)
		(connect_pads
			(clearance 0)
		)
		(min_thickness 0.25)
		(keepout
			(tracks not_allowed)
			(vias allowed)
			(pads allowed)
			(copperpour not_allowed)
			(footprints allowed)
		)
		(placement
			(enabled no)
			(sheetname "")
		)
		(fill yes
			(thermal_gap 0.5)
			(thermal_bridge_width 0.5)
			(island_removal_mode 0)
		)
		(polygon
			(pts
				(arc
					(start 413.546798 -237.471458)
					(mid 413.561677 -237.507379)
					(end 413.597598 -237.522258)
				)
				(arc
					(start 414.997138 -237.522258)
					(mid 415.033059 -237.507379)
					(end 415.047938 -237.471458)
				)
				(arc
					(start 415.047938 -237.062518)
					(mid 415.033059 -237.026597)
					(end 414.997138 -237.011718)
				)
				(arc
					(start 413.597598 -237.011718)
					(mid 413.561677 -237.026597)
					(end 413.546798 -237.062518)
				)
			)
		)
	)
	(zone
		(layers "In1.Cu" "In2.Cu")
		(hatch none 0.5)
		(connect_pads
			(clearance 0)
		)
		(min_thickness 0.25)
		(keepout
			(tracks not_allowed)
			(vias allowed)
			(pads allowed)
			(copperpour not_allowed)
			(footprints allowed)
		)
		(placement
			(enabled no)
			(sheetname "")
		)
		(fill yes
			(thermal_gap 0.5)
			(thermal_bridge_width 0.5)
			(island_removal_mode 0)
		)
		(polygon
			(pts
				(arc
					(start 52.65293 -200.071482)
					(mid 52.667809 -200.107403)
					(end 52.70373 -200.122282)
				)
				(arc
					(start 54.10327 -200.122282)
					(mid 54.139191 -200.107403)
					(end 54.15407 -200.071482)
				)
				(arc
					(start 54.15407 -199.662542)
					(mid 54.139191 -199.626621)
					(end 54.10327 -199.611742)
				)
				(arc
					(start 52.70373 -199.611742)
					(mid 52.667809 -199.626621)
					(end 52.65293 -199.662542)
				)
			)
		)
	)
	(zone
		(layers "In1.Cu" "In2.Cu")
		(hatch none 0.5)
		(connect_pads
			(clearance 0)
		)
		(min_thickness 0.25)
		(keepout
			(tracks not_allowed)
			(vias allowed)
			(pads allowed)
			(copperpour not_allowed)
			(footprints allowed)
		)
		(placement
			(enabled no)
			(sheetname "")
		)
		(fill yes
			(thermal_gap 0.5)
			(thermal_bridge_width 0.5)
			(island_removal_mode 0)
		)
		(polygon
			(pts
				(arc
					(start 432.734466 -259.57149)
					(mid 432.749345 -259.607411)
					(end 432.785266 -259.62229)
				)
				(arc
					(start 434.184806 -259.62229)
					(mid 434.220727 -259.607411)
					(end 434.235606 -259.57149)
				)
				(arc
					(start 434.235606 -259.16255)
					(mid 434.220727 -259.126629)
					(end 434.184806 -259.11175)
				)
				(arc
					(start 432.785266 -259.11175)
					(mid 432.749345 -259.126629)
					(end 432.734466 -259.16255)
				)
			)
		)
	)
	(zone
		(layers "In1.Cu" "In2.Cu")
		(hatch none 0.5)
		(connect_pads
			(clearance 0)
		)
		(min_thickness 0.25)
		(keepout
			(tracks not_allowed)
			(vias allowed)
			(pads allowed)
			(copperpour not_allowed)
			(footprints allowed)
		)
		(placement
			(enabled no)
			(sheetname "")
		)
		(fill yes
			(thermal_gap 0.5)
			(thermal_bridge_width 0.5)
			(island_removal_mode 0)
		)
		(polygon
			(pts
				(arc
					(start 421.090598 -238.321342)
					(mid 421.105477 -238.357263)
					(end 421.141398 -238.372142)
				)
				(arc
					(start 422.540938 -238.372142)
					(mid 422.576859 -238.357263)
					(end 422.591738 -238.321342)
				)
				(arc
					(start 422.591738 -237.912402)
					(mid 422.576859 -237.876481)
					(end 422.540938 -237.861602)
				)
				(arc
					(start 421.141398 -237.861602)
					(mid 421.105477 -237.876481)
					(end 421.090598 -237.912402)
				)
			)
		)
	)
	(zone
		(layers "In1.Cu" "In2.Cu")
		(hatch none 0.5)
		(connect_pads
			(clearance 0)
		)
		(min_thickness 0.25)
		(keepout
			(tracks not_allowed)
			(vias allowed)
			(pads allowed)
			(copperpour not_allowed)
			(footprints allowed)
		)
		(placement
			(enabled no)
			(sheetname "")
		)
		(fill yes
			(thermal_gap 0.5)
			(thermal_bridge_width 0.5)
			(island_removal_mode 0)
		)
		(polygon
			(pts
				(arc
					(start 180.69433 -244.271292)
					(mid 180.709209 -244.307213)
					(end 180.74513 -244.322092)
				)
				(arc
					(start 182.14467 -244.322092)
					(mid 182.180591 -244.307213)
					(end 182.19547 -244.271292)
				)
				(arc
					(start 182.19547 -243.862352)
					(mid 182.180591 -243.826431)
					(end 182.14467 -243.811552)
				)
				(arc
					(start 180.74513 -243.811552)
					(mid 180.709209 -243.826431)
					(end 180.69433 -243.862352)
				)
			)
		)
	)
	(zone
		(layers "In1.Cu" "In2.Cu")
		(hatch none 0.5)
		(connect_pads
			(clearance 0)
		)
		(min_thickness 0.25)
		(keepout
			(tracks not_allowed)
			(vias allowed)
			(pads allowed)
			(copperpour not_allowed)
			(footprints allowed)
		)
		(placement
			(enabled no)
			(sheetname "")
		)
		(fill yes
			(thermal_gap 0.5)
			(thermal_bridge_width 0.5)
			(island_removal_mode 0)
		)
		(polygon
			(pts
				(arc
					(start 255.330198 -266.371324)
					(mid 255.345077 -266.407245)
					(end 255.380998 -266.422124)
				)
				(arc
					(start 256.780538 -266.422124)
					(mid 256.816459 -266.407245)
					(end 256.831338 -266.371324)
				)
				(arc
					(start 256.831338 -265.962384)
					(mid 256.816459 -265.926463)
					(end 256.780538 -265.911584)
				)
				(arc
					(start 255.380998 -265.911584)
					(mid 255.345077 -265.926463)
					(end 255.330198 -265.962384)
				)
			)
		)
	)
	(zone
		(layers "In1.Cu" "In2.Cu")
		(hatch none 0.5)
		(connect_pads
			(clearance 0)
		)
		(min_thickness 0.25)
		(keepout
			(tracks not_allowed)
			(vias allowed)
			(pads allowed)
			(copperpour not_allowed)
			(footprints allowed)
		)
		(placement
			(enabled no)
			(sheetname "")
		)
		(fill yes
			(thermal_gap 0.5)
			(thermal_bridge_width 0.5)
			(island_removal_mode 0)
		)
		(polygon
			(pts
				(arc
					(start 199.881998 -287.621472)
					(mid 199.896877 -287.657393)
					(end 199.932798 -287.672272)
				)
				(arc
					(start 201.332338 -287.672272)
					(mid 201.368259 -287.657393)
					(end 201.383138 -287.621472)
				)
				(arc
					(start 201.383138 -287.212532)
					(mid 201.368259 -287.176611)
					(end 201.332338 -287.161732)
				)
				(arc
					(start 199.932798 -287.161732)
					(mid 199.896877 -287.176611)
					(end 199.881998 -287.212532)
				)
			)
		)
	)
	(zone
		(layers "In1.Cu" "In2.Cu")
		(hatch none 0.5)
		(connect_pads
			(clearance 0)
		)
		(min_thickness 0.25)
		(keepout
			(tracks not_allowed)
			(vias allowed)
			(pads allowed)
			(copperpour not_allowed)
			(footprints allowed)
		)
		(placement
			(enabled no)
			(sheetname "")
		)
		(fill yes
			(thermal_gap 0.5)
			(thermal_bridge_width 0.5)
			(island_removal_mode 0)
		)
		(polygon
			(pts
				(arc
					(start 214.969598 -313.971432)
					(mid 214.984477 -314.007353)
					(end 215.020398 -314.022232)
				)
				(arc
					(start 216.419938 -314.022232)
					(mid 216.455859 -314.007353)
					(end 216.470738 -313.971432)
				)
				(arc
					(start 216.470738 -313.562492)
					(mid 216.455859 -313.526571)
					(end 216.419938 -313.511692)
				)
				(arc
					(start 215.020398 -313.511692)
					(mid 214.984477 -313.526571)
					(end 214.969598 -313.562492)
				)
			)
		)
	)
	(zone
		(layers "In1.Cu" "In2.Cu")
		(hatch none 0.5)
		(connect_pads
			(clearance 0)
		)
		(min_thickness 0.25)
		(keepout
			(tracks not_allowed)
			(vias allowed)
			(pads allowed)
			(copperpour not_allowed)
			(footprints allowed)
		)
		(placement
			(enabled no)
			(sheetname "")
		)
		(fill yes
			(thermal_gap 0.5)
			(thermal_bridge_width 0.5)
			(island_removal_mode 0)
		)
		(polygon
			(pts
				(arc
					(start 30.02153 -296.121328)
					(mid 30.036409 -296.157249)
					(end 30.07233 -296.172128)
				)
				(arc
					(start 31.47187 -296.172128)
					(mid 31.507791 -296.157249)
					(end 31.52267 -296.121328)
				)
				(arc
					(start 31.52267 -295.712388)
					(mid 31.507791 -295.676467)
					(end 31.47187 -295.661588)
				)
				(arc
					(start 30.07233 -295.661588)
					(mid 30.036409 -295.676467)
					(end 30.02153 -295.712388)
				)
			)
		)
	)
	(zone
		(layers "In1.Cu" "In2.Cu")
		(hatch none 0.5)
		(connect_pads
			(clearance 0)
		)
		(min_thickness 0.25)
		(keepout
			(tracks not_allowed)
			(vias allowed)
			(pads allowed)
			(copperpour not_allowed)
			(footprints allowed)
		)
		(placement
			(enabled no)
			(sheetname "")
		)
		(fill yes
			(thermal_gap 0.5)
			(thermal_bridge_width 0.5)
			(island_removal_mode 0)
		)
		(polygon
			(pts
				(arc
					(start 199.881998 -281.671522)
					(mid 199.896877 -281.707443)
					(end 199.932798 -281.722322)
				)
				(arc
					(start 201.332338 -281.722322)
					(mid 201.368259 -281.707443)
					(end 201.383138 -281.671522)
				)
				(arc
					(start 201.383138 -281.262582)
					(mid 201.368259 -281.226661)
					(end 201.332338 -281.211782)
				)
				(arc
					(start 199.932798 -281.211782)
					(mid 199.896877 -281.226661)
					(end 199.881998 -281.262582)
				)
			)
		)
	)
	(zone
		(layers "In1.Cu" "In2.Cu")
		(hatch none 0.5)
		(connect_pads
			(clearance 0)
		)
		(min_thickness 0.25)
		(keepout
			(tracks not_allowed)
			(vias allowed)
			(pads allowed)
			(copperpour not_allowed)
			(footprints allowed)
		)
		(placement
			(enabled no)
			(sheetname "")
		)
		(fill yes
			(thermal_gap 0.5)
			(thermal_bridge_width 0.5)
			(island_removal_mode 0)
		)
		(polygon
			(pts
				(arc
					(start 440.278266 -233.22153)
					(mid 440.293145 -233.257451)
					(end 440.329066 -233.27233)
				)
				(arc
					(start 441.728606 -233.27233)
					(mid 441.764527 -233.257451)
					(end 441.779406 -233.22153)
				)
				(arc
					(start 441.779406 -232.81259)
					(mid 441.764527 -232.776669)
					(end 441.728606 -232.76179)
				)
				(arc
					(start 440.329066 -232.76179)
					(mid 440.293145 -232.776669)
					(end 440.278266 -232.81259)
				)
			)
		)
	)
	(zone
		(layers "In1.Cu" "In2.Cu")
		(hatch none 0.5)
		(connect_pads
			(clearance 0)
		)
		(min_thickness 0.25)
		(keepout
			(tracks not_allowed)
			(vias allowed)
			(pads allowed)
			(copperpour not_allowed)
			(footprints allowed)
		)
		(placement
			(enabled no)
			(sheetname "")
		)
		(fill yes
			(thermal_gap 0.5)
			(thermal_bridge_width 0.5)
			(island_removal_mode 0)
		)
		(polygon
			(pts
				(arc
					(start 282.061666 -304.621438)
					(mid 282.076545 -304.657359)
					(end 282.112466 -304.672238)
				)
				(arc
					(start 283.512006 -304.672238)
					(mid 283.547927 -304.657359)
					(end 283.562806 -304.621438)
				)
				(arc
					(start 283.562806 -304.212498)
					(mid 283.547927 -304.176577)
					(end 283.512006 -304.161698)
				)
				(arc
					(start 282.112466 -304.161698)
					(mid 282.076545 -304.176577)
					(end 282.061666 -304.212498)
				)
			)
		)
	)
	(zone
		(layers "In1.Cu" "In2.Cu")
		(hatch none 0.5)
		(connect_pads
			(clearance 0)
		)
		(min_thickness 0.25)
		(keepout
			(tracks not_allowed)
			(vias allowed)
			(pads allowed)
			(copperpour not_allowed)
			(footprints allowed)
		)
		(placement
			(enabled no)
			(sheetname "")
		)
		(fill yes
			(thermal_gap 0.5)
			(thermal_bridge_width 0.5)
			(island_removal_mode 0)
		)
		(polygon
			(pts
				(arc
					(start 184.794398 -302.071532)
					(mid 184.809277 -302.107453)
					(end 184.845198 -302.122332)
				)
				(arc
					(start 186.244738 -302.122332)
					(mid 186.280659 -302.107453)
					(end 186.295538 -302.071532)
				)
				(arc
					(start 186.295538 -301.662592)
					(mid 186.280659 -301.626671)
					(end 186.244738 -301.611792)
				)
				(arc
					(start 184.845198 -301.611792)
					(mid 184.809277 -301.626671)
					(end 184.794398 -301.662592)
				)
			)
		)
	)
	(zone
		(layers "In1.Cu" "In2.Cu")
		(hatch none 0.5)
		(connect_pads
			(clearance 0)
		)
		(min_thickness 0.25)
		(keepout
			(tracks not_allowed)
			(vias allowed)
			(pads allowed)
			(copperpour not_allowed)
			(footprints allowed)
		)
		(placement
			(enabled no)
			(sheetname "")
		)
		(fill yes
			(thermal_gap 0.5)
			(thermal_bridge_width 0.5)
			(island_removal_mode 0)
		)
		(polygon
			(pts
				(arc
					(start 277.961598 -218.77147)
					(mid 277.976477 -218.807391)
					(end 278.012398 -218.82227)
				)
				(arc
					(start 279.411938 -218.82227)
					(mid 279.447859 -218.807391)
					(end 279.462738 -218.77147)
				)
				(arc
					(start 279.462738 -218.36253)
					(mid 279.447859 -218.326609)
					(end 279.411938 -218.31173)
				)
				(arc
					(start 278.012398 -218.31173)
					(mid 277.976477 -218.326609)
					(end 277.961598 -218.36253)
				)
			)
		)
	)
	(zone
		(layers "In1.Cu" "In2.Cu")
		(hatch none 0.5)
		(connect_pads
			(clearance 0)
		)
		(min_thickness 0.25)
		(keepout
			(tracks not_allowed)
			(vias allowed)
			(pads allowed)
			(copperpour not_allowed)
			(footprints allowed)
		)
		(placement
			(enabled no)
			(sheetname "")
		)
		(fill yes
			(thermal_gap 0.5)
			(thermal_bridge_width 0.5)
			(island_removal_mode 0)
		)
		(polygon
			(pts
				(arc
					(start 41.665398 -246.821452)
					(mid 41.680277 -246.857373)
					(end 41.716198 -246.872252)
				)
				(arc
					(start 43.115738 -246.872252)
					(mid 43.151659 -246.857373)
					(end 43.166538 -246.821452)
				)
				(arc
					(start 43.166538 -246.412512)
					(mid 43.151659 -246.376591)
					(end 43.115738 -246.361712)
				)
				(arc
					(start 41.716198 -246.361712)
					(mid 41.680277 -246.376591)
					(end 41.665398 -246.412512)
				)
			)
		)
	)
	(zone
		(layers "In1.Cu" "In2.Cu")
		(hatch none 0.5)
		(connect_pads
			(clearance 0)
		)
		(min_thickness 0.25)
		(keepout
			(tracks not_allowed)
			(vias allowed)
			(pads allowed)
			(copperpour not_allowed)
			(footprints allowed)
		)
		(placement
			(enabled no)
			(sheetname "")
		)
		(fill yes
			(thermal_gap 0.5)
			(thermal_bridge_width 0.5)
			(island_removal_mode 0)
		)
		(polygon
			(pts
				(arc
					(start 285.505398 -241.721386)
					(mid 285.520277 -241.757307)
					(end 285.556198 -241.772186)
				)
				(arc
					(start 286.955738 -241.772186)
					(mid 286.991659 -241.757307)
					(end 287.006538 -241.721386)
				)
				(arc
					(start 287.006538 -241.312446)
					(mid 286.991659 -241.276525)
					(end 286.955738 -241.261646)
				)
				(arc
					(start 285.556198 -241.261646)
					(mid 285.520277 -241.276525)
					(end 285.505398 -241.312446)
				)
			)
		)
	)
	(zone
		(layers "In1.Cu" "In2.Cu")
		(hatch none 0.5)
		(connect_pads
			(clearance 0)
		)
		(min_thickness 0.25)
		(keepout
			(tracks not_allowed)
			(vias allowed)
			(pads allowed)
			(copperpour not_allowed)
			(footprints allowed)
		)
		(placement
			(enabled no)
			(sheetname "")
		)
		(fill yes
			(thermal_gap 0.5)
			(thermal_bridge_width 0.5)
			(island_removal_mode 0)
		)
		(polygon
			(pts
				(arc
					(start 270.417798 -312.27141)
					(mid 270.432677 -312.307331)
					(end 270.468598 -312.32221)
				)
				(arc
					(start 271.868138 -312.32221)
					(mid 271.904059 -312.307331)
					(end 271.918938 -312.27141)
				)
				(arc
					(start 271.918938 -311.86247)
					(mid 271.904059 -311.826549)
					(end 271.868138 -311.81167)
				)
				(arc
					(start 270.468598 -311.81167)
					(mid 270.432677 -311.826549)
					(end 270.417798 -311.86247)
				)
			)
		)
	)
	(zone
		(layers "In1.Cu" "In2.Cu")
		(hatch none 0.5)
		(connect_pads
			(clearance 0)
		)
		(min_thickness 0.25)
		(keepout
			(tracks not_allowed)
			(vias allowed)
			(pads allowed)
			(copperpour not_allowed)
			(footprints allowed)
		)
		(placement
			(enabled no)
			(sheetname "")
		)
		(fill yes
			(thermal_gap 0.5)
			(thermal_bridge_width 0.5)
			(island_removal_mode 0)
		)
		(polygon
			(pts
				(arc
					(start 180.69433 -204.32141)
					(mid 180.709209 -204.357331)
					(end 180.74513 -204.37221)
				)
				(arc
					(start 182.14467 -204.37221)
					(mid 182.180591 -204.357331)
					(end 182.19547 -204.32141)
				)
				(arc
					(start 182.19547 -203.91247)
					(mid 182.180591 -203.876549)
					(end 182.14467 -203.86167)
				)
				(arc
					(start 180.74513 -203.86167)
					(mid 180.709209 -203.876549)
					(end 180.69433 -203.91247)
				)
			)
		)
	)
	(zone
		(layers "In1.Cu" "In2.Cu")
		(hatch none 0.5)
		(connect_pads
			(clearance 0)
		)
		(min_thickness 0.25)
		(keepout
			(tracks not_allowed)
			(vias allowed)
			(pads allowed)
			(copperpour not_allowed)
			(footprints allowed)
		)
		(placement
			(enabled no)
			(sheetname "")
		)
		(fill yes
			(thermal_gap 0.5)
			(thermal_bridge_width 0.5)
			(island_removal_mode 0)
		)
		(polygon
			(pts
				(arc
					(start 199.881998 -272.321528)
					(mid 199.896877 -272.357449)
					(end 199.932798 -272.372328)
				)
				(arc
					(start 201.332338 -272.372328)
					(mid 201.368259 -272.357449)
					(end 201.383138 -272.321528)
				)
				(arc
					(start 201.383138 -271.912588)
					(mid 201.368259 -271.876667)
					(end 201.332338 -271.861788)
				)
				(arc
					(start 199.932798 -271.861788)
					(mid 199.896877 -271.876667)
					(end 199.881998 -271.912588)
				)
			)
		)
	)
	(zone
		(layers "In1.Cu" "In2.Cu")
		(hatch none 0.5)
		(connect_pads
			(clearance 0)
		)
		(min_thickness 0.25)
		(keepout
			(tracks not_allowed)
			(vias allowed)
			(pads allowed)
			(copperpour not_allowed)
			(footprints allowed)
		)
		(placement
			(enabled no)
			(sheetname "")
		)
		(fill yes
			(thermal_gap 0.5)
			(thermal_bridge_width 0.5)
			(island_removal_mode 0)
		)
		(polygon
			(pts
				(arc
					(start 177.250598 -218.77147)
					(mid 177.265477 -218.807391)
					(end 177.301398 -218.82227)
				)
				(arc
					(start 178.700938 -218.82227)
					(mid 178.736859 -218.807391)
					(end 178.751738 -218.77147)
				)
				(arc
					(start 178.751738 -218.36253)
					(mid 178.736859 -218.326609)
					(end 178.700938 -218.31173)
				)
				(arc
					(start 177.301398 -218.31173)
					(mid 177.265477 -218.326609)
					(end 177.250598 -218.36253)
				)
			)
		)
	)
	(zone
		(layers "In1.Cu" "In2.Cu")
		(hatch none 0.5)
		(connect_pads
			(clearance 0)
		)
		(min_thickness 0.25)
		(keepout
			(tracks not_allowed)
			(vias allowed)
			(pads allowed)
			(copperpour not_allowed)
			(footprints allowed)
		)
		(placement
			(enabled no)
			(sheetname "")
		)
		(fill yes
			(thermal_gap 0.5)
			(thermal_bridge_width 0.5)
			(island_removal_mode 0)
		)
		(polygon
			(pts
				(arc
					(start 270.417798 -308.871366)
					(mid 270.432677 -308.907287)
					(end 270.468598 -308.922166)
				)
				(arc
					(start 271.868138 -308.922166)
					(mid 271.904059 -308.907287)
					(end 271.918938 -308.871366)
				)
				(arc
					(start 271.918938 -308.462426)
					(mid 271.904059 -308.426505)
					(end 271.868138 -308.411626)
				)
				(arc
					(start 270.468598 -308.411626)
					(mid 270.432677 -308.426505)
					(end 270.417798 -308.462426)
				)
			)
		)
	)
	(zone
		(layers "In1.Cu" "In2.Cu")
		(hatch none 0.5)
		(connect_pads
			(clearance 0)
		)
		(min_thickness 0.25)
		(keepout
			(tracks not_allowed)
			(vias allowed)
			(pads allowed)
			(copperpour not_allowed)
			(footprints allowed)
		)
		(placement
			(enabled no)
			(sheetname "")
		)
		(fill yes
			(thermal_gap 0.5)
			(thermal_bridge_width 0.5)
			(island_removal_mode 0)
		)
		(polygon
			(pts
				(arc
					(start 413.546798 -211.971382)
					(mid 413.561677 -212.007303)
					(end 413.597598 -212.022182)
				)
				(arc
					(start 414.997138 -212.022182)
					(mid 415.033059 -212.007303)
					(end 415.047938 -211.971382)
				)
				(arc
					(start 415.047938 -211.562442)
					(mid 415.033059 -211.526521)
					(end 414.997138 -211.511642)
				)
				(arc
					(start 413.597598 -211.511642)
					(mid 413.561677 -211.526521)
					(end 413.546798 -211.562442)
				)
			)
		)
	)
	(zone
		(layers "In1.Cu" "In2.Cu")
		(hatch none 0.5)
		(connect_pads
			(clearance 0)
		)
		(min_thickness 0.25)
		(keepout
			(tracks not_allowed)
			(vias allowed)
			(pads allowed)
			(copperpour not_allowed)
			(footprints allowed)
		)
		(placement
			(enabled no)
			(sheetname "")
		)
		(fill yes
			(thermal_gap 0.5)
			(thermal_bridge_width 0.5)
			(island_removal_mode 0)
		)
		(polygon
			(pts
				(arc
					(start 304.693066 -274.871434)
					(mid 304.707945 -274.907355)
					(end 304.743866 -274.922234)
				)
				(arc
					(start 306.143406 -274.922234)
					(mid 306.179327 -274.907355)
					(end 306.194206 -274.871434)
				)
				(arc
					(start 306.194206 -274.462494)
					(mid 306.179327 -274.426573)
					(end 306.143406 -274.411694)
				)
				(arc
					(start 304.743866 -274.411694)
					(mid 304.707945 -274.426573)
					(end 304.693066 -274.462494)
				)
			)
		)
	)
	(zone
		(layers "In1.Cu" "In2.Cu")
		(hatch none 0.5)
		(connect_pads
			(clearance 0)
		)
		(min_thickness 0.25)
		(keepout
			(tracks not_allowed)
			(vias allowed)
			(pads allowed)
			(copperpour not_allowed)
			(footprints allowed)
		)
		(placement
			(enabled no)
			(sheetname "")
		)
		(fill yes
			(thermal_gap 0.5)
			(thermal_bridge_width 0.5)
			(island_removal_mode 0)
		)
		(polygon
			(pts
				(arc
					(start 270.417798 -209.421476)
					(mid 270.432677 -209.457397)
					(end 270.468598 -209.472276)
				)
				(arc
					(start 271.868138 -209.472276)
					(mid 271.904059 -209.457397)
					(end 271.918938 -209.421476)
				)
				(arc
					(start 271.918938 -209.012536)
					(mid 271.904059 -208.976615)
					(end 271.868138 -208.961736)
				)
				(arc
					(start 270.468598 -208.961736)
					(mid 270.432677 -208.976615)
					(end 270.417798 -209.012536)
				)
			)
		)
	)
	(zone
		(layers "In1.Cu" "In2.Cu")
		(hatch none 0.5)
		(connect_pads
			(clearance 0)
		)
		(min_thickness 0.25)
		(keepout
			(tracks not_allowed)
			(vias allowed)
			(pads allowed)
			(copperpour not_allowed)
			(footprints allowed)
		)
		(placement
			(enabled no)
			(sheetname "")
		)
		(fill yes
			(thermal_gap 0.5)
			(thermal_bridge_width 0.5)
			(island_removal_mode 0)
		)
		(polygon
			(pts
				(arc
					(start 417.646866 -246.821452)
					(mid 417.661745 -246.857373)
					(end 417.697666 -246.872252)
				)
				(arc
					(start 419.097206 -246.872252)
					(mid 419.133127 -246.857373)
					(end 419.148006 -246.821452)
				)
				(arc
					(start 419.148006 -246.412512)
					(mid 419.133127 -246.376591)
					(end 419.097206 -246.361712)
				)
				(arc
					(start 417.697666 -246.361712)
					(mid 417.661745 -246.376591)
					(end 417.646866 -246.412512)
				)
			)
		)
	)
	(zone
		(layers "In1.Cu" "In2.Cu")
		(hatch none 0.5)
		(connect_pads
			(clearance 0)
		)
		(min_thickness 0.25)
		(keepout
			(tracks not_allowed)
			(vias allowed)
			(pads allowed)
			(copperpour not_allowed)
			(footprints allowed)
		)
		(placement
			(enabled no)
			(sheetname "")
		)
		(fill yes
			(thermal_gap 0.5)
			(thermal_bridge_width 0.5)
			(island_removal_mode 0)
		)
		(polygon
			(pts
				(arc
					(start 11.490198 -228.121464)
					(mid 11.505077 -228.157385)
					(end 11.540998 -228.172264)
				)
				(arc
					(start 12.940538 -228.172264)
					(mid 12.976459 -228.157385)
					(end 12.991338 -228.121464)
				)
				(arc
					(start 12.991338 -227.712524)
					(mid 12.976459 -227.676603)
					(end 12.940538 -227.661724)
				)
				(arc
					(start 11.540998 -227.661724)
					(mid 11.505077 -227.676603)
					(end 11.490198 -227.712524)
				)
			)
		)
	)
	(zone
		(layers "In1.Cu" "In2.Cu")
		(hatch none 0.5)
		(connect_pads
			(clearance 0)
		)
		(min_thickness 0.25)
		(keepout
			(tracks not_allowed)
			(vias allowed)
			(pads allowed)
			(copperpour not_allowed)
			(footprints allowed)
		)
		(placement
			(enabled no)
			(sheetname "")
		)
		(fill yes
			(thermal_gap 0.5)
			(thermal_bridge_width 0.5)
			(island_removal_mode 0)
		)
		(polygon
			(pts
				(arc
					(start 37.56533 -259.57149)
					(mid 37.580209 -259.607411)
					(end 37.61613 -259.62229)
				)
				(arc
					(start 39.01567 -259.62229)
					(mid 39.051591 -259.607411)
					(end 39.06647 -259.57149)
				)
				(arc
					(start 39.06647 -259.16255)
					(mid 39.051591 -259.126629)
					(end 39.01567 -259.11175)
				)
				(arc
					(start 37.61613 -259.11175)
					(mid 37.580209 -259.126629)
					(end 37.56533 -259.16255)
				)
			)
		)
	)
	(zone
		(layers "In1.Cu" "In2.Cu")
		(hatch none 0.5)
		(connect_pads
			(clearance 0)
		)
		(min_thickness 0.25)
		(keepout
			(tracks not_allowed)
			(vias allowed)
			(pads allowed)
			(copperpour not_allowed)
			(footprints allowed)
		)
		(placement
			(enabled no)
			(sheetname "")
		)
		(fill yes
			(thermal_gap 0.5)
			(thermal_bridge_width 0.5)
			(island_removal_mode 0)
		)
		(polygon
			(pts
				(arc
					(start 421.090598 -241.721386)
					(mid 421.105477 -241.757307)
					(end 421.141398 -241.772186)
				)
				(arc
					(start 422.540938 -241.772186)
					(mid 422.576859 -241.757307)
					(end 422.591738 -241.721386)
				)
				(arc
					(start 422.591738 -241.312446)
					(mid 422.576859 -241.276525)
					(end 422.540938 -241.261646)
				)
				(arc
					(start 421.141398 -241.261646)
					(mid 421.105477 -241.276525)
					(end 421.090598 -241.312446)
				)
			)
		)
	)
	(zone
		(layers "In1.Cu" "In2.Cu")
		(hatch none 0.5)
		(connect_pads
			(clearance 0)
		)
		(min_thickness 0.25)
		(keepout
			(tracks not_allowed)
			(vias allowed)
			(pads allowed)
			(copperpour not_allowed)
			(footprints allowed)
		)
		(placement
			(enabled no)
			(sheetname "")
		)
		(fill yes
			(thermal_gap 0.5)
			(thermal_bridge_width 0.5)
			(island_removal_mode 0)
		)
		(polygon
			(pts
				(arc
					(start 180.69433 -296.121328)
					(mid 180.709209 -296.157249)
					(end 180.74513 -296.172128)
				)
				(arc
					(start 182.14467 -296.172128)
					(mid 182.180591 -296.157249)
					(end 182.19547 -296.121328)
				)
				(arc
					(start 182.19547 -295.712388)
					(mid 182.180591 -295.676467)
					(end 182.14467 -295.661588)
				)
				(arc
					(start 180.74513 -295.661588)
					(mid 180.709209 -295.676467)
					(end 180.69433 -295.712388)
				)
			)
		)
	)
	(zone
		(layers "In1.Cu" "In2.Cu")
		(hatch none 0.5)
		(connect_pads
			(clearance 0)
		)
		(min_thickness 0.25)
		(keepout
			(tracks not_allowed)
			(vias allowed)
			(pads allowed)
			(copperpour not_allowed)
			(footprints allowed)
		)
		(placement
			(enabled no)
			(sheetname "")
		)
		(fill yes
			(thermal_gap 0.5)
			(thermal_bridge_width 0.5)
			(island_removal_mode 0)
		)
		(polygon
			(pts
				(arc
					(start 14.93393 -230.67137)
					(mid 14.948809 -230.707291)
					(end 14.98473 -230.72217)
				)
				(arc
					(start 16.38427 -230.72217)
					(mid 16.420191 -230.707291)
					(end 16.43507 -230.67137)
				)
				(arc
					(start 16.43507 -230.26243)
					(mid 16.420191 -230.226509)
					(end 16.38427 -230.21163)
				)
				(arc
					(start 14.98473 -230.21163)
					(mid 14.948809 -230.226509)
					(end 14.93393 -230.26243)
				)
			)
		)
	)
	(zone
		(layers "In1.Cu" "In2.Cu")
		(hatch none 0.5)
		(connect_pads
			(clearance 0)
		)
		(min_thickness 0.25)
		(keepout
			(tracks not_allowed)
			(vias allowed)
			(pads allowed)
			(copperpour not_allowed)
			(footprints allowed)
		)
		(placement
			(enabled no)
			(sheetname "")
		)
		(fill yes
			(thermal_gap 0.5)
			(thermal_bridge_width 0.5)
			(island_removal_mode 0)
		)
		(polygon
			(pts
				(arc
					(start 14.93393 -241.721386)
					(mid 14.948809 -241.757307)
					(end 14.98473 -241.772186)
				)
				(arc
					(start 16.38427 -241.772186)
					(mid 16.420191 -241.757307)
					(end 16.43507 -241.721386)
				)
				(arc
					(start 16.43507 -241.312446)
					(mid 16.420191 -241.276525)
					(end 16.38427 -241.261646)
				)
				(arc
					(start 14.98473 -241.261646)
					(mid 14.948809 -241.276525)
					(end 14.93393 -241.312446)
				)
			)
		)
	)
	(zone
		(layers "In1.Cu" "In2.Cu")
		(hatch none 0.5)
		(connect_pads
			(clearance 0)
		)
		(min_thickness 0.25)
		(keepout
			(tracks not_allowed)
			(vias allowed)
			(pads allowed)
			(copperpour not_allowed)
			(footprints allowed)
		)
		(placement
			(enabled no)
			(sheetname "")
		)
		(fill yes
			(thermal_gap 0.5)
			(thermal_bridge_width 0.5)
			(island_removal_mode 0)
		)
		(polygon
			(pts
				(arc
					(start 259.430266 -296.971466)
					(mid 259.445145 -297.007387)
					(end 259.481066 -297.022266)
				)
				(arc
					(start 260.880606 -297.022266)
					(mid 260.916527 -297.007387)
					(end 260.931406 -296.971466)
				)
				(arc
					(start 260.931406 -296.562526)
					(mid 260.916527 -296.526605)
					(end 260.880606 -296.511726)
				)
				(arc
					(start 259.481066 -296.511726)
					(mid 259.445145 -296.526605)
					(end 259.430266 -296.562526)
				)
			)
		)
	)
	(zone
		(layers "In1.Cu" "In2.Cu")
		(hatch none 0.5)
		(connect_pads
			(clearance 0)
		)
		(min_thickness 0.25)
		(keepout
			(tracks not_allowed)
			(vias allowed)
			(pads allowed)
			(copperpour not_allowed)
			(footprints allowed)
		)
		(placement
			(enabled no)
			(sheetname "")
		)
		(fill yes
			(thermal_gap 0.5)
			(thermal_bridge_width 0.5)
			(island_removal_mode 0)
		)
		(polygon
			(pts
				(arc
					(start 297.149266 -309.721504)
					(mid 297.164145 -309.757425)
					(end 297.200066 -309.772304)
				)
				(arc
					(start 298.599606 -309.772304)
					(mid 298.635527 -309.757425)
					(end 298.650406 -309.721504)
				)
				(arc
					(start 298.650406 -309.312564)
					(mid 298.635527 -309.276643)
					(end 298.599606 -309.261764)
				)
				(arc
					(start 297.200066 -309.261764)
					(mid 297.164145 -309.276643)
					(end 297.149266 -309.312564)
				)
			)
		)
	)
	(zone
		(layers "In1.Cu" "In2.Cu")
		(hatch none 0.5)
		(connect_pads
			(clearance 0)
		)
		(min_thickness 0.25)
		(keepout
			(tracks not_allowed)
			(vias allowed)
			(pads allowed)
			(copperpour not_allowed)
			(footprints allowed)
		)
		(placement
			(enabled no)
			(sheetname "")
		)
		(fill yes
			(thermal_gap 0.5)
			(thermal_bridge_width 0.5)
			(island_removal_mode 0)
		)
		(polygon
			(pts
				(arc
					(start 300.592998 -291.8714)
					(mid 300.607877 -291.907321)
					(end 300.643798 -291.9222)
				)
				(arc
					(start 302.043338 -291.9222)
					(mid 302.079259 -291.907321)
					(end 302.094138 -291.8714)
				)
				(arc
					(start 302.094138 -291.46246)
					(mid 302.079259 -291.426539)
					(end 302.043338 -291.41166)
				)
				(arc
					(start 300.643798 -291.41166)
					(mid 300.607877 -291.426539)
					(end 300.592998 -291.46246)
				)
			)
		)
	)
	(zone
		(layers "In1.Cu" "In2.Cu")
		(hatch none 0.5)
		(connect_pads
			(clearance 0)
		)
		(min_thickness 0.25)
		(keepout
			(tracks not_allowed)
			(vias allowed)
			(pads allowed)
			(copperpour not_allowed)
			(footprints allowed)
		)
		(placement
			(enabled no)
			(sheetname "")
		)
		(fill yes
			(thermal_gap 0.5)
			(thermal_bridge_width 0.5)
			(island_removal_mode 0)
		)
		(polygon
			(pts
				(arc
					(start 277.961598 -228.971348)
					(mid 277.976477 -229.007269)
					(end 278.012398 -229.022148)
				)
				(arc
					(start 279.411938 -229.022148)
					(mid 279.447859 -229.007269)
					(end 279.462738 -228.971348)
				)
				(arc
					(start 279.462738 -228.562408)
					(mid 279.447859 -228.526487)
					(end 279.411938 -228.511608)
				)
				(arc
					(start 278.012398 -228.511608)
					(mid 277.976477 -228.526487)
					(end 277.961598 -228.562408)
				)
			)
		)
	)
	(zone
		(layers "In1.Cu" "In2.Cu")
		(hatch none 0.5)
		(connect_pads
			(clearance 0)
		)
		(min_thickness 0.25)
		(keepout
			(tracks not_allowed)
			(vias allowed)
			(pads allowed)
			(copperpour not_allowed)
			(footprints allowed)
		)
		(placement
			(enabled no)
			(sheetname "")
		)
		(fill yes
			(thermal_gap 0.5)
			(thermal_bridge_width 0.5)
			(island_removal_mode 0)
		)
		(polygon
			(pts
				(arc
					(start 440.278266 -308.021482)
					(mid 440.293145 -308.057403)
					(end 440.329066 -308.072282)
				)
				(arc
					(start 441.728606 -308.072282)
					(mid 441.764527 -308.057403)
					(end 441.779406 -308.021482)
				)
				(arc
					(start 441.779406 -307.612542)
					(mid 441.764527 -307.576621)
					(end 441.728606 -307.561742)
				)
				(arc
					(start 440.329066 -307.561742)
					(mid 440.293145 -307.576621)
					(end 440.278266 -307.612542)
				)
			)
		)
	)
	(zone
		(layers "In1.Cu" "In2.Cu")
		(hatch none 0.5)
		(connect_pads
			(clearance 0)
		)
		(min_thickness 0.25)
		(keepout
			(tracks not_allowed)
			(vias allowed)
			(pads allowed)
			(copperpour not_allowed)
			(footprints allowed)
		)
		(placement
			(enabled no)
			(sheetname "")
		)
		(fill yes
			(thermal_gap 0.5)
			(thermal_bridge_width 0.5)
			(island_removal_mode 0)
		)
		(polygon
			(pts
				(arc
					(start 7.39013 -238.321342)
					(mid 7.405009 -238.357263)
					(end 7.44093 -238.372142)
				)
				(arc
					(start 8.84047 -238.372142)
					(mid 8.876391 -238.357263)
					(end 8.89127 -238.321342)
				)
				(arc
					(start 8.89127 -237.912402)
					(mid 8.876391 -237.876481)
					(end 8.84047 -237.861602)
				)
				(arc
					(start 7.44093 -237.861602)
					(mid 7.405009 -237.876481)
					(end 7.39013 -237.912402)
				)
			)
		)
	)
	(zone
		(layers "In1.Cu" "In2.Cu")
		(hatch none 0.5)
		(connect_pads
			(clearance 0)
		)
		(min_thickness 0.25)
		(keepout
			(tracks not_allowed)
			(vias allowed)
			(pads allowed)
			(copperpour not_allowed)
			(footprints allowed)
		)
		(placement
			(enabled no)
			(sheetname "")
		)
		(fill yes
			(thermal_gap 0.5)
			(thermal_bridge_width 0.5)
			(island_removal_mode 0)
		)
		(polygon
			(pts
				(arc
					(start 428.634398 -234.071414)
					(mid 428.649277 -234.107335)
					(end 428.685198 -234.122214)
				)
				(arc
					(start 430.084738 -234.122214)
					(mid 430.120659 -234.107335)
					(end 430.135538 -234.071414)
				)
				(arc
					(start 430.135538 -233.662474)
					(mid 430.120659 -233.626553)
					(end 430.084738 -233.611674)
				)
				(arc
					(start 428.685198 -233.611674)
					(mid 428.649277 -233.626553)
					(end 428.634398 -233.662474)
				)
			)
		)
	)
	(zone
		(layers "In1.Cu" "In2.Cu")
		(hatch none 0.5)
		(connect_pads
			(clearance 0)
		)
		(min_thickness 0.25)
		(keepout
			(tracks not_allowed)
			(vias allowed)
			(pads allowed)
			(copperpour not_allowed)
			(footprints allowed)
		)
		(placement
			(enabled no)
			(sheetname "")
		)
		(fill yes
			(thermal_gap 0.5)
			(thermal_bridge_width 0.5)
			(island_removal_mode 0)
		)
		(polygon
			(pts
				(arc
					(start 169.706798 -245.12143)
					(mid 169.721677 -245.157351)
					(end 169.757598 -245.17223)
				)
				(arc
					(start 171.157138 -245.17223)
					(mid 171.193059 -245.157351)
					(end 171.207938 -245.12143)
				)
				(arc
					(start 171.207938 -244.71249)
					(mid 171.193059 -244.676569)
					(end 171.157138 -244.66169)
				)
				(arc
					(start 169.757598 -244.66169)
					(mid 169.721677 -244.676569)
					(end 169.706798 -244.71249)
				)
			)
		)
	)
	(zone
		(layers "In1.Cu" "In2.Cu")
		(hatch none 0.5)
		(connect_pads
			(clearance 0)
		)
		(min_thickness 0.25)
		(keepout
			(tracks not_allowed)
			(vias allowed)
			(pads allowed)
			(copperpour not_allowed)
			(footprints allowed)
		)
		(placement
			(enabled no)
			(sheetname "")
		)
		(fill yes
			(thermal_gap 0.5)
			(thermal_bridge_width 0.5)
			(island_removal_mode 0)
		)
		(polygon
			(pts
				(arc
					(start 165.60673 -232.371392)
					(mid 165.621609 -232.407313)
					(end 165.65753 -232.422192)
				)
				(arc
					(start 167.05707 -232.422192)
					(mid 167.092991 -232.407313)
					(end 167.10787 -232.371392)
				)
				(arc
					(start 167.10787 -231.962452)
					(mid 167.092991 -231.926531)
					(end 167.05707 -231.911652)
				)
				(arc
					(start 165.65753 -231.911652)
					(mid 165.621609 -231.926531)
					(end 165.60673 -231.962452)
				)
			)
		)
	)
	(zone
		(layers "In1.Cu" "In2.Cu")
		(hatch none 0.5)
		(connect_pads
			(clearance 0)
		)
		(min_thickness 0.25)
		(keepout
			(tracks not_allowed)
			(vias allowed)
			(pads allowed)
			(copperpour not_allowed)
			(footprints allowed)
		)
		(placement
			(enabled no)
			(sheetname "")
		)
		(fill yes
			(thermal_gap 0.5)
			(thermal_bridge_width 0.5)
			(island_removal_mode 0)
		)
		(polygon
			(pts
				(arc
					(start 7.39013 -228.971348)
					(mid 7.405009 -229.007269)
					(end 7.44093 -229.022148)
				)
				(arc
					(start 8.84047 -229.022148)
					(mid 8.876391 -229.007269)
					(end 8.89127 -228.971348)
				)
				(arc
					(start 8.89127 -228.562408)
					(mid 8.876391 -228.526487)
					(end 8.84047 -228.511608)
				)
				(arc
					(start 7.44093 -228.511608)
					(mid 7.405009 -228.526487)
					(end 7.39013 -228.562408)
				)
			)
		)
	)
	(zone
		(layers "In1.Cu" "In2.Cu")
		(hatch none 0.5)
		(connect_pads
			(clearance 0)
		)
		(min_thickness 0.25)
		(keepout
			(tracks not_allowed)
			(vias allowed)
			(pads allowed)
			(copperpour not_allowed)
			(footprints allowed)
		)
		(placement
			(enabled no)
			(sheetname "")
		)
		(fill yes
			(thermal_gap 0.5)
			(thermal_bridge_width 0.5)
			(island_removal_mode 0)
		)
		(polygon
			(pts
				(arc
					(start 7.39013 -196.671438)
					(mid 7.405009 -196.707359)
					(end 7.44093 -196.722238)
				)
				(arc
					(start 8.84047 -196.722238)
					(mid 8.876391 -196.707359)
					(end 8.89127 -196.671438)
				)
				(arc
					(start 8.89127 -196.262498)
					(mid 8.876391 -196.226577)
					(end 8.84047 -196.211698)
				)
				(arc
					(start 7.44093 -196.211698)
					(mid 7.405009 -196.226577)
					(end 7.39013 -196.262498)
				)
			)
		)
	)
	(zone
		(layers "In1.Cu" "In2.Cu")
		(hatch none 0.5)
		(connect_pads
			(clearance 0)
		)
		(min_thickness 0.25)
		(keepout
			(tracks not_allowed)
			(vias allowed)
			(pads allowed)
			(copperpour not_allowed)
			(footprints allowed)
		)
		(placement
			(enabled no)
			(sheetname "")
		)
		(fill yes
			(thermal_gap 0.5)
			(thermal_bridge_width 0.5)
			(island_removal_mode 0)
		)
		(polygon
			(pts
				(arc
					(start 177.250598 -274.871434)
					(mid 177.265477 -274.907355)
					(end 177.301398 -274.922234)
				)
				(arc
					(start 178.700938 -274.922234)
					(mid 178.736859 -274.907355)
					(end 178.751738 -274.871434)
				)
				(arc
					(start 178.751738 -274.462494)
					(mid 178.736859 -274.426573)
					(end 178.700938 -274.411694)
				)
				(arc
					(start 177.301398 -274.411694)
					(mid 177.265477 -274.426573)
					(end 177.250598 -274.462494)
				)
			)
		)
	)
	(zone
		(layers "In1.Cu" "In2.Cu")
		(hatch none 0.5)
		(connect_pads
			(clearance 0)
		)
		(min_thickness 0.25)
		(keepout
			(tracks not_allowed)
			(vias allowed)
			(pads allowed)
			(copperpour not_allowed)
			(footprints allowed)
		)
		(placement
			(enabled no)
			(sheetname "")
		)
		(fill yes
			(thermal_gap 0.5)
			(thermal_bridge_width 0.5)
			(island_removal_mode 0)
		)
		(polygon
			(pts
				(arc
					(start 455.365866 -291.021516)
					(mid 455.380745 -291.057437)
					(end 455.416666 -291.072316)
				)
				(arc
					(start 456.816206 -291.072316)
					(mid 456.852127 -291.057437)
					(end 456.867006 -291.021516)
				)
				(arc
					(start 456.867006 -290.612576)
					(mid 456.852127 -290.576655)
					(end 456.816206 -290.561776)
				)
				(arc
					(start 455.416666 -290.561776)
					(mid 455.380745 -290.576655)
					(end 455.365866 -290.612576)
				)
			)
		)
	)
	(zone
		(layers "In1.Cu" "In2.Cu")
		(hatch none 0.5)
		(connect_pads
			(clearance 0)
		)
		(min_thickness 0.25)
		(keepout
			(tracks not_allowed)
			(vias allowed)
			(pads allowed)
			(copperpour not_allowed)
			(footprints allowed)
		)
		(placement
			(enabled no)
			(sheetname "")
		)
		(fill yes
			(thermal_gap 0.5)
			(thermal_bridge_width 0.5)
			(island_removal_mode 0)
		)
		(polygon
			(pts
				(arc
					(start 11.490198 -274.871434)
					(mid 11.505077 -274.907355)
					(end 11.540998 -274.922234)
				)
				(arc
					(start 12.940538 -274.922234)
					(mid 12.976459 -274.907355)
					(end 12.991338 -274.871434)
				)
				(arc
					(start 12.991338 -274.462494)
					(mid 12.976459 -274.426573)
					(end 12.940538 -274.411694)
				)
				(arc
					(start 11.540998 -274.411694)
					(mid 11.505077 -274.426573)
					(end 11.490198 -274.462494)
				)
			)
		)
	)
	(zone
		(layers "In1.Cu" "In2.Cu")
		(hatch none 0.5)
		(connect_pads
			(clearance 0)
		)
		(min_thickness 0.25)
		(keepout
			(tracks not_allowed)
			(vias allowed)
			(pads allowed)
			(copperpour not_allowed)
			(footprints allowed)
		)
		(placement
			(enabled no)
			(sheetname "")
		)
		(fill yes
			(thermal_gap 0.5)
			(thermal_bridge_width 0.5)
			(island_removal_mode 0)
		)
		(polygon
			(pts
				(arc
					(start 282.061666 -209.421476)
					(mid 282.076545 -209.457397)
					(end 282.112466 -209.472276)
				)
				(arc
					(start 283.512006 -209.472276)
					(mid 283.547927 -209.457397)
					(end 283.562806 -209.421476)
				)
				(arc
					(start 283.562806 -209.012536)
					(mid 283.547927 -208.976615)
					(end 283.512006 -208.961736)
				)
				(arc
					(start 282.112466 -208.961736)
					(mid 282.076545 -208.976615)
					(end 282.061666 -209.012536)
				)
			)
		)
	)
	(zone
		(layers "In1.Cu" "In2.Cu")
		(hatch none 0.5)
		(connect_pads
			(clearance 0)
		)
		(min_thickness 0.25)
		(keepout
			(tracks not_allowed)
			(vias allowed)
			(pads allowed)
			(copperpour not_allowed)
			(footprints allowed)
		)
		(placement
			(enabled no)
			(sheetname "")
		)
		(fill yes
			(thermal_gap 0.5)
			(thermal_bridge_width 0.5)
			(island_removal_mode 0)
		)
		(polygon
			(pts
				(arc
					(start 443.721998 -211.971382)
					(mid 443.736877 -212.007303)
					(end 443.772798 -212.022182)
				)
				(arc
					(start 445.172338 -212.022182)
					(mid 445.208259 -212.007303)
					(end 445.223138 -211.971382)
				)
				(arc
					(start 445.223138 -211.562442)
					(mid 445.208259 -211.526521)
					(end 445.172338 -211.511642)
				)
				(arc
					(start 443.772798 -211.511642)
					(mid 443.736877 -211.526521)
					(end 443.721998 -211.562442)
				)
			)
		)
	)
	(zone
		(layers "In1.Cu" "In2.Cu")
		(hatch none 0.5)
		(connect_pads
			(clearance 0)
		)
		(min_thickness 0.25)
		(keepout
			(tracks not_allowed)
			(vias allowed)
			(pads allowed)
			(copperpour not_allowed)
			(footprints allowed)
		)
		(placement
			(enabled no)
			(sheetname "")
		)
		(fill yes
			(thermal_gap 0.5)
			(thermal_bridge_width 0.5)
			(island_removal_mode 0)
		)
		(polygon
			(pts
				(arc
					(start 262.873998 -232.371392)
					(mid 262.888877 -232.407313)
					(end 262.924798 -232.422192)
				)
				(arc
					(start 264.324338 -232.422192)
					(mid 264.360259 -232.407313)
					(end 264.375138 -232.371392)
				)
				(arc
					(start 264.375138 -231.962452)
					(mid 264.360259 -231.926531)
					(end 264.324338 -231.911652)
				)
				(arc
					(start 262.924798 -231.911652)
					(mid 262.888877 -231.926531)
					(end 262.873998 -231.962452)
				)
			)
		)
	)
	(zone
		(layers "In1.Cu" "In2.Cu")
		(hatch none 0.5)
		(connect_pads
			(clearance 0)
		)
		(min_thickness 0.25)
		(keepout
			(tracks not_allowed)
			(vias allowed)
			(pads allowed)
			(copperpour not_allowed)
			(footprints allowed)
		)
		(placement
			(enabled no)
			(sheetname "")
		)
		(fill yes
			(thermal_gap 0.5)
			(thermal_bridge_width 0.5)
			(island_removal_mode 0)
		)
		(polygon
			(pts
				(arc
					(start 169.706798 -199.221344)
					(mid 169.721677 -199.257265)
					(end 169.757598 -199.272144)
				)
				(arc
					(start 171.157138 -199.272144)
					(mid 171.193059 -199.257265)
					(end 171.207938 -199.221344)
				)
				(arc
					(start 171.207938 -198.812404)
					(mid 171.193059 -198.776483)
					(end 171.157138 -198.761604)
				)
				(arc
					(start 169.757598 -198.761604)
					(mid 169.721677 -198.776483)
					(end 169.706798 -198.812404)
				)
			)
		)
	)
	(zone
		(layers "In1.Cu" "In2.Cu")
		(hatch none 0.5)
		(connect_pads
			(clearance 0)
		)
		(min_thickness 0.25)
		(keepout
			(tracks not_allowed)
			(vias allowed)
			(pads allowed)
			(copperpour not_allowed)
			(footprints allowed)
		)
		(placement
			(enabled no)
			(sheetname "")
		)
		(fill yes
			(thermal_gap 0.5)
			(thermal_bridge_width 0.5)
			(island_removal_mode 0)
		)
		(polygon
			(pts
				(arc
					(start 214.969598 -225.571304)
					(mid 214.984477 -225.607225)
					(end 215.020398 -225.622104)
				)
				(arc
					(start 216.419938 -225.622104)
					(mid 216.455859 -225.607225)
					(end 216.470738 -225.571304)
				)
				(arc
					(start 216.470738 -225.162364)
					(mid 216.455859 -225.126443)
					(end 216.419938 -225.111564)
				)
				(arc
					(start 215.020398 -225.111564)
					(mid 214.984477 -225.126443)
					(end 214.969598 -225.162364)
				)
			)
		)
	)
	(zone
		(layers "In1.Cu" "In2.Cu")
		(hatch none 0.5)
		(connect_pads
			(clearance 0)
		)
		(min_thickness 0.25)
		(keepout
			(tracks not_allowed)
			(vias allowed)
			(pads allowed)
			(copperpour not_allowed)
			(footprints allowed)
		)
		(placement
			(enabled no)
			(sheetname "")
		)
		(fill yes
			(thermal_gap 0.5)
			(thermal_bridge_width 0.5)
			(island_removal_mode 0)
		)
		(polygon
			(pts
				(arc
					(start 443.721998 -218.77147)
					(mid 443.736877 -218.807391)
					(end 443.772798 -218.82227)
				)
				(arc
					(start 445.172338 -218.82227)
					(mid 445.208259 -218.807391)
					(end 445.223138 -218.77147)
				)
				(arc
					(start 445.223138 -218.36253)
					(mid 445.208259 -218.326609)
					(end 445.172338 -218.31173)
				)
				(arc
					(start 443.772798 -218.31173)
					(mid 443.736877 -218.326609)
					(end 443.721998 -218.36253)
				)
			)
		)
	)
	(zone
		(layers "In1.Cu" "In2.Cu")
		(hatch none 0.5)
		(connect_pads
			(clearance 0)
		)
		(min_thickness 0.25)
		(keepout
			(tracks not_allowed)
			(vias allowed)
			(pads allowed)
			(copperpour not_allowed)
			(footprints allowed)
		)
		(placement
			(enabled no)
			(sheetname "")
		)
		(fill yes
			(thermal_gap 0.5)
			(thermal_bridge_width 0.5)
			(island_removal_mode 0)
		)
		(polygon
			(pts
				(arc
					(start 165.60673 -223.021398)
					(mid 165.621609 -223.057319)
					(end 165.65753 -223.072198)
				)
				(arc
					(start 167.05707 -223.072198)
					(mid 167.092991 -223.057319)
					(end 167.10787 -223.021398)
				)
				(arc
					(start 167.10787 -222.612458)
					(mid 167.092991 -222.576537)
					(end 167.05707 -222.561658)
				)
				(arc
					(start 165.65753 -222.561658)
					(mid 165.621609 -222.576537)
					(end 165.60673 -222.612458)
				)
			)
		)
	)
	(zone
		(layers "In1.Cu" "In2.Cu")
		(hatch none 0.5)
		(connect_pads
			(clearance 0)
		)
		(min_thickness 0.25)
		(keepout
			(tracks not_allowed)
			(vias allowed)
			(pads allowed)
			(copperpour not_allowed)
			(footprints allowed)
		)
		(placement
			(enabled no)
			(sheetname "")
		)
		(fill yes
			(thermal_gap 0.5)
			(thermal_bridge_width 0.5)
			(island_removal_mode 0)
		)
		(polygon
			(pts
				(arc
					(start 447.822066 -225.571304)
					(mid 447.836945 -225.607225)
					(end 447.872866 -225.622104)
				)
				(arc
					(start 449.272406 -225.622104)
					(mid 449.308327 -225.607225)
					(end 449.323206 -225.571304)
				)
				(arc
					(start 449.323206 -225.162364)
					(mid 449.308327 -225.126443)
					(end 449.272406 -225.111564)
				)
				(arc
					(start 447.872866 -225.111564)
					(mid 447.836945 -225.126443)
					(end 447.822066 -225.162364)
				)
			)
		)
	)
	(zone
		(layers "In1.Cu" "In2.Cu")
		(hatch none 0.5)
		(connect_pads
			(clearance 0)
		)
		(min_thickness 0.25)
		(keepout
			(tracks not_allowed)
			(vias allowed)
			(pads allowed)
			(copperpour not_allowed)
			(footprints allowed)
		)
		(placement
			(enabled no)
			(sheetname "")
		)
		(fill yes
			(thermal_gap 0.5)
			(thermal_bridge_width 0.5)
			(island_removal_mode 0)
		)
		(polygon
			(pts
				(arc
					(start 300.592998 -245.971314)
					(mid 300.607877 -246.007235)
					(end 300.643798 -246.022114)
				)
				(arc
					(start 302.043338 -246.022114)
					(mid 302.079259 -246.007235)
					(end 302.094138 -245.971314)
				)
				(arc
					(start 302.094138 -245.562374)
					(mid 302.079259 -245.526453)
					(end 302.043338 -245.511574)
				)
				(arc
					(start 300.643798 -245.511574)
					(mid 300.607877 -245.526453)
					(end 300.592998 -245.562374)
				)
			)
		)
	)
	(zone
		(layers "In1.Cu" "In2.Cu")
		(hatch none 0.5)
		(connect_pads
			(clearance 0)
		)
		(min_thickness 0.25)
		(keepout
			(tracks not_allowed)
			(vias allowed)
			(pads allowed)
			(copperpour not_allowed)
			(footprints allowed)
		)
		(placement
			(enabled no)
			(sheetname "")
		)
		(fill yes
			(thermal_gap 0.5)
			(thermal_bridge_width 0.5)
			(island_removal_mode 0)
		)
		(polygon
			(pts
				(arc
					(start 451.265798 -223.021398)
					(mid 451.280677 -223.057319)
					(end 451.316598 -223.072198)
				)
				(arc
					(start 452.716138 -223.072198)
					(mid 452.752059 -223.057319)
					(end 452.766938 -223.021398)
				)
				(arc
					(start 452.766938 -222.612458)
					(mid 452.752059 -222.576537)
					(end 452.716138 -222.561658)
				)
				(arc
					(start 451.316598 -222.561658)
					(mid 451.280677 -222.576537)
					(end 451.265798 -222.612458)
				)
			)
		)
	)
	(zone
		(layers "In1.Cu" "In2.Cu")
		(hatch none 0.5)
		(connect_pads
			(clearance 0)
		)
		(min_thickness 0.25)
		(keepout
			(tracks not_allowed)
			(vias allowed)
			(pads allowed)
			(copperpour not_allowed)
			(footprints allowed)
		)
		(placement
			(enabled no)
			(sheetname "")
		)
		(fill yes
			(thermal_gap 0.5)
			(thermal_bridge_width 0.5)
			(island_removal_mode 0)
		)
		(polygon
			(pts
				(arc
					(start 270.417798 -271.47139)
					(mid 270.432677 -271.507311)
					(end 270.468598 -271.52219)
				)
				(arc
					(start 271.868138 -271.52219)
					(mid 271.904059 -271.507311)
					(end 271.918938 -271.47139)
				)
				(arc
					(start 271.918938 -271.06245)
					(mid 271.904059 -271.026529)
					(end 271.868138 -271.01165)
				)
				(arc
					(start 270.468598 -271.01165)
					(mid 270.432677 -271.026529)
					(end 270.417798 -271.06245)
				)
			)
		)
	)
	(zone
		(layers "In1.Cu" "In2.Cu")
		(hatch none 0.5)
		(connect_pads
			(clearance 0)
		)
		(min_thickness 0.25)
		(keepout
			(tracks not_allowed)
			(vias allowed)
			(pads allowed)
			(copperpour not_allowed)
			(footprints allowed)
		)
		(placement
			(enabled no)
			(sheetname "")
		)
		(fill yes
			(thermal_gap 0.5)
			(thermal_bridge_width 0.5)
			(island_removal_mode 0)
		)
		(polygon
			(pts
				(arc
					(start 274.517866 -263.821418)
					(mid 274.532745 -263.857339)
					(end 274.568666 -263.872218)
				)
				(arc
					(start 275.968206 -263.872218)
					(mid 276.004127 -263.857339)
					(end 276.019006 -263.821418)
				)
				(arc
					(start 276.019006 -263.412478)
					(mid 276.004127 -263.376557)
					(end 275.968206 -263.361678)
				)
				(arc
					(start 274.568666 -263.361678)
					(mid 274.532745 -263.376557)
					(end 274.517866 -263.412478)
				)
			)
		)
	)
	(zone
		(layers "In1.Cu" "In2.Cu")
		(hatch none 0.5)
		(connect_pads
			(clearance 0)
		)
		(min_thickness 0.25)
		(keepout
			(tracks not_allowed)
			(vias allowed)
			(pads allowed)
			(copperpour not_allowed)
			(footprints allowed)
		)
		(placement
			(enabled no)
			(sheetname "")
		)
		(fill yes
			(thermal_gap 0.5)
			(thermal_bridge_width 0.5)
			(island_removal_mode 0)
		)
		(polygon
			(pts
				(arc
					(start 282.061666 -228.121464)
					(mid 282.076545 -228.157385)
					(end 282.112466 -228.172264)
				)
				(arc
					(start 283.512006 -228.172264)
					(mid 283.547927 -228.157385)
					(end 283.562806 -228.121464)
				)
				(arc
					(start 283.562806 -227.712524)
					(mid 283.547927 -227.676603)
					(end 283.512006 -227.661724)
				)
				(arc
					(start 282.112466 -227.661724)
					(mid 282.076545 -227.676603)
					(end 282.061666 -227.712524)
				)
			)
		)
	)
	(zone
		(layers "In1.Cu" "In2.Cu")
		(hatch none 0.5)
		(connect_pads
			(clearance 0)
		)
		(min_thickness 0.25)
		(keepout
			(tracks not_allowed)
			(vias allowed)
			(pads allowed)
			(copperpour not_allowed)
			(footprints allowed)
		)
		(placement
			(enabled no)
			(sheetname "")
		)
		(fill yes
			(thermal_gap 0.5)
			(thermal_bridge_width 0.5)
			(island_removal_mode 0)
		)
		(polygon
			(pts
				(arc
					(start 158.06293 -299.521372)
					(mid 158.077809 -299.557293)
					(end 158.11373 -299.572172)
				)
				(arc
					(start 159.51327 -299.572172)
					(mid 159.549191 -299.557293)
					(end 159.56407 -299.521372)
				)
				(arc
					(start 159.56407 -299.112432)
					(mid 159.549191 -299.076511)
					(end 159.51327 -299.061632)
				)
				(arc
					(start 158.11373 -299.061632)
					(mid 158.077809 -299.076511)
					(end 158.06293 -299.112432)
				)
			)
		)
	)
	(zone
		(layers "In1.Cu" "In2.Cu")
		(hatch none 0.5)
		(connect_pads
			(clearance 0)
		)
		(min_thickness 0.25)
		(keepout
			(tracks not_allowed)
			(vias allowed)
			(pads allowed)
			(copperpour not_allowed)
			(footprints allowed)
		)
		(placement
			(enabled no)
			(sheetname "")
		)
		(fill yes
			(thermal_gap 0.5)
			(thermal_bridge_width 0.5)
			(island_removal_mode 0)
		)
		(polygon
			(pts
				(arc
					(start 207.425798 -306.32146)
					(mid 207.440677 -306.357381)
					(end 207.476598 -306.37226)
				)
				(arc
					(start 208.876138 -306.37226)
					(mid 208.912059 -306.357381)
					(end 208.926938 -306.32146)
				)
				(arc
					(start 208.926938 -305.91252)
					(mid 208.912059 -305.876599)
					(end 208.876138 -305.86172)
				)
				(arc
					(start 207.476598 -305.86172)
					(mid 207.440677 -305.876599)
					(end 207.425798 -305.91252)
				)
			)
		)
	)
	(zone
		(layers "In1.Cu" "In2.Cu")
		(hatch none 0.5)
		(connect_pads
			(clearance 0)
		)
		(min_thickness 0.25)
		(keepout
			(tracks not_allowed)
			(vias allowed)
			(pads allowed)
			(copperpour not_allowed)
			(footprints allowed)
		)
		(placement
			(enabled no)
			(sheetname "")
		)
		(fill yes
			(thermal_gap 0.5)
			(thermal_bridge_width 0.5)
			(island_removal_mode 0)
		)
		(polygon
			(pts
				(arc
					(start 293.049198 -218.77147)
					(mid 293.064077 -218.807391)
					(end 293.099998 -218.82227)
				)
				(arc
					(start 294.499538 -218.82227)
					(mid 294.535459 -218.807391)
					(end 294.550338 -218.77147)
				)
				(arc
					(start 294.550338 -218.36253)
					(mid 294.535459 -218.326609)
					(end 294.499538 -218.31173)
				)
				(arc
					(start 293.099998 -218.31173)
					(mid 293.064077 -218.326609)
					(end 293.049198 -218.36253)
				)
			)
		)
	)
	(zone
		(layers "In1.Cu" "In2.Cu")
		(hatch none 0.5)
		(connect_pads
			(clearance 0)
		)
		(min_thickness 0.25)
		(keepout
			(tracks not_allowed)
			(vias allowed)
			(pads allowed)
			(copperpour not_allowed)
			(footprints allowed)
		)
		(placement
			(enabled no)
			(sheetname "")
		)
		(fill yes
			(thermal_gap 0.5)
			(thermal_bridge_width 0.5)
			(island_removal_mode 0)
		)
		(polygon
			(pts
				(arc
					(start 443.721998 -261.271512)
					(mid 443.736877 -261.307433)
					(end 443.772798 -261.322312)
				)
				(arc
					(start 445.172338 -261.322312)
					(mid 445.208259 -261.307433)
					(end 445.223138 -261.271512)
				)
				(arc
					(start 445.223138 -260.862572)
					(mid 445.208259 -260.826651)
					(end 445.172338 -260.811772)
				)
				(arc
					(start 443.772798 -260.811772)
					(mid 443.736877 -260.826651)
					(end 443.721998 -260.862572)
				)
			)
		)
	)
	(zone
		(layers "In1.Cu" "In2.Cu")
		(hatch none 0.5)
		(connect_pads
			(clearance 0)
		)
		(min_thickness 0.25)
		(keepout
			(tracks not_allowed)
			(vias allowed)
			(pads allowed)
			(copperpour not_allowed)
			(footprints allowed)
		)
		(placement
			(enabled no)
			(sheetname "")
		)
		(fill yes
			(thermal_gap 0.5)
			(thermal_bridge_width 0.5)
			(island_removal_mode 0)
		)
		(polygon
			(pts
				(arc
					(start 432.734466 -292.721538)
					(mid 432.749345 -292.757459)
					(end 432.785266 -292.772338)
				)
				(arc
					(start 434.184806 -292.772338)
					(mid 434.220727 -292.757459)
					(end 434.235606 -292.721538)
				)
				(arc
					(start 434.235606 -292.312598)
					(mid 434.220727 -292.276677)
					(end 434.184806 -292.261798)
				)
				(arc
					(start 432.785266 -292.261798)
					(mid 432.749345 -292.276677)
					(end 432.734466 -292.312598)
				)
			)
		)
	)
	(zone
		(layers "In1.Cu" "In2.Cu")
		(hatch none 0.5)
		(connect_pads
			(clearance 0)
		)
		(min_thickness 0.25)
		(keepout
			(tracks not_allowed)
			(vias allowed)
			(pads allowed)
			(copperpour not_allowed)
			(footprints allowed)
		)
		(placement
			(enabled no)
			(sheetname "")
		)
		(fill yes
			(thermal_gap 0.5)
			(thermal_bridge_width 0.5)
			(island_removal_mode 0)
		)
		(polygon
			(pts
				(arc
					(start 192.338198 -293.571422)
					(mid 192.353077 -293.607343)
					(end 192.388998 -293.622222)
				)
				(arc
					(start 193.788538 -293.622222)
					(mid 193.824459 -293.607343)
					(end 193.839338 -293.571422)
				)
				(arc
					(start 193.839338 -293.162482)
					(mid 193.824459 -293.126561)
					(end 193.788538 -293.111682)
				)
				(arc
					(start 192.388998 -293.111682)
					(mid 192.353077 -293.126561)
					(end 192.338198 -293.162482)
				)
			)
		)
	)
	(zone
		(layers "In1.Cu" "In2.Cu")
		(hatch none 0.5)
		(connect_pads
			(clearance 0)
		)
		(min_thickness 0.25)
		(keepout
			(tracks not_allowed)
			(vias allowed)
			(pads allowed)
			(copperpour not_allowed)
			(footprints allowed)
		)
		(placement
			(enabled no)
			(sheetname "")
		)
		(fill yes
			(thermal_gap 0.5)
			(thermal_bridge_width 0.5)
			(island_removal_mode 0)
		)
		(polygon
			(pts
				(arc
					(start 184.794398 -276.571456)
					(mid 184.809277 -276.607377)
					(end 184.845198 -276.622256)
				)
				(arc
					(start 186.244738 -276.622256)
					(mid 186.280659 -276.607377)
					(end 186.295538 -276.571456)
				)
				(arc
					(start 186.295538 -276.162516)
					(mid 186.280659 -276.126595)
					(end 186.244738 -276.111716)
				)
				(arc
					(start 184.845198 -276.111716)
					(mid 184.809277 -276.126595)
					(end 184.794398 -276.162516)
				)
			)
		)
	)
	(zone
		(layers "In1.Cu" "In2.Cu")
		(hatch none 0.5)
		(connect_pads
			(clearance 0)
		)
		(min_thickness 0.25)
		(keepout
			(tracks not_allowed)
			(vias allowed)
			(pads allowed)
			(copperpour not_allowed)
			(footprints allowed)
		)
		(placement
			(enabled no)
			(sheetname "")
		)
		(fill yes
			(thermal_gap 0.5)
			(thermal_bridge_width 0.5)
			(island_removal_mode 0)
		)
		(polygon
			(pts
				(arc
					(start 45.10913 -230.67137)
					(mid 45.124009 -230.707291)
					(end 45.15993 -230.72217)
				)
				(arc
					(start 46.55947 -230.72217)
					(mid 46.595391 -230.707291)
					(end 46.61027 -230.67137)
				)
				(arc
					(start 46.61027 -230.26243)
					(mid 46.595391 -230.226509)
					(end 46.55947 -230.21163)
				)
				(arc
					(start 45.15993 -230.21163)
					(mid 45.124009 -230.226509)
					(end 45.10913 -230.26243)
				)
			)
		)
	)
	(zone
		(layers "In1.Cu" "In2.Cu")
		(hatch none 0.5)
		(connect_pads
			(clearance 0)
		)
		(min_thickness 0.25)
		(keepout
			(tracks not_allowed)
			(vias allowed)
			(pads allowed)
			(copperpour not_allowed)
			(footprints allowed)
		)
		(placement
			(enabled no)
			(sheetname "")
		)
		(fill yes
			(thermal_gap 0.5)
			(thermal_bridge_width 0.5)
			(island_removal_mode 0)
		)
		(polygon
			(pts
				(arc
					(start 443.721998 -293.571422)
					(mid 443.736877 -293.607343)
					(end 443.772798 -293.622222)
				)
				(arc
					(start 445.172338 -293.622222)
					(mid 445.208259 -293.607343)
					(end 445.223138 -293.571422)
				)
				(arc
					(start 445.223138 -293.162482)
					(mid 445.208259 -293.126561)
					(end 445.172338 -293.111682)
				)
				(arc
					(start 443.772798 -293.111682)
					(mid 443.736877 -293.126561)
					(end 443.721998 -293.162482)
				)
			)
		)
	)
	(zone
		(layers "In1.Cu" "In2.Cu")
		(hatch none 0.5)
		(connect_pads
			(clearance 0)
		)
		(min_thickness 0.25)
		(keepout
			(tracks not_allowed)
			(vias allowed)
			(pads allowed)
			(copperpour not_allowed)
			(footprints allowed)
		)
		(placement
			(enabled no)
			(sheetname "")
		)
		(fill yes
			(thermal_gap 0.5)
			(thermal_bridge_width 0.5)
			(island_removal_mode 0)
		)
		(polygon
			(pts
				(arc
					(start 293.049198 -204.32141)
					(mid 293.064077 -204.357331)
					(end 293.099998 -204.37221)
				)
				(arc
					(start 294.499538 -204.37221)
					(mid 294.535459 -204.357331)
					(end 294.550338 -204.32141)
				)
				(arc
					(start 294.550338 -203.91247)
					(mid 294.535459 -203.876549)
					(end 294.499538 -203.86167)
				)
				(arc
					(start 293.099998 -203.86167)
					(mid 293.064077 -203.876549)
					(end 293.049198 -203.91247)
				)
			)
		)
	)
	(zone
		(layers "In1.Cu" "In2.Cu")
		(hatch none 0.5)
		(connect_pads
			(clearance 0)
		)
		(min_thickness 0.25)
		(keepout
			(tracks not_allowed)
			(vias allowed)
			(pads allowed)
			(copperpour not_allowed)
			(footprints allowed)
		)
		(placement
			(enabled no)
			(sheetname "")
		)
		(fill yes
			(thermal_gap 0.5)
			(thermal_bridge_width 0.5)
			(island_removal_mode 0)
		)
		(polygon
			(pts
				(arc
					(start 195.78193 -217.071448)
					(mid 195.796809 -217.107369)
					(end 195.83273 -217.122248)
				)
				(arc
					(start 197.23227 -217.122248)
					(mid 197.268191 -217.107369)
					(end 197.28307 -217.071448)
				)
				(arc
					(start 197.28307 -216.662508)
					(mid 197.268191 -216.626587)
					(end 197.23227 -216.611708)
				)
				(arc
					(start 195.83273 -216.611708)
					(mid 195.796809 -216.626587)
					(end 195.78193 -216.662508)
				)
			)
		)
	)
	(zone
		(layers "In1.Cu" "In2.Cu")
		(hatch none 0.5)
		(connect_pads
			(clearance 0)
		)
		(min_thickness 0.25)
		(keepout
			(tracks not_allowed)
			(vias allowed)
			(pads allowed)
			(copperpour not_allowed)
			(footprints allowed)
		)
		(placement
			(enabled no)
			(sheetname "")
		)
		(fill yes
			(thermal_gap 0.5)
			(thermal_bridge_width 0.5)
			(island_removal_mode 0)
		)
		(polygon
			(pts
				(arc
					(start 410.103066 -270.621506)
					(mid 410.117945 -270.657427)
					(end 410.153866 -270.672306)
				)
				(arc
					(start 411.553406 -270.672306)
					(mid 411.589327 -270.657427)
					(end 411.604206 -270.621506)
				)
				(arc
					(start 411.604206 -270.212566)
					(mid 411.589327 -270.176645)
					(end 411.553406 -270.161766)
				)
				(arc
					(start 410.153866 -270.161766)
					(mid 410.117945 -270.176645)
					(end 410.103066 -270.212566)
				)
			)
		)
	)
	(zone
		(layers "In1.Cu" "In2.Cu")
		(hatch none 0.5)
		(connect_pads
			(clearance 0)
		)
		(min_thickness 0.25)
		(keepout
			(tracks not_allowed)
			(vias allowed)
			(pads allowed)
			(copperpour not_allowed)
			(footprints allowed)
		)
		(placement
			(enabled no)
			(sheetname "")
		)
		(fill yes
			(thermal_gap 0.5)
			(thermal_bridge_width 0.5)
			(island_removal_mode 0)
		)
		(polygon
			(pts
				(arc
					(start 26.577798 -285.92145)
					(mid 26.592677 -285.957371)
					(end 26.628598 -285.97225)
				)
				(arc
					(start 28.028138 -285.97225)
					(mid 28.064059 -285.957371)
					(end 28.078938 -285.92145)
				)
				(arc
					(start 28.078938 -285.51251)
					(mid 28.064059 -285.476589)
					(end 28.028138 -285.46171)
				)
				(arc
					(start 26.628598 -285.46171)
					(mid 26.592677 -285.476589)
					(end 26.577798 -285.51251)
				)
			)
		)
	)
	(zone
		(layers "In1.Cu" "In2.Cu")
		(hatch none 0.5)
		(connect_pads
			(clearance 0)
		)
		(min_thickness 0.25)
		(keepout
			(tracks not_allowed)
			(vias allowed)
			(pads allowed)
			(copperpour not_allowed)
			(footprints allowed)
		)
		(placement
			(enabled no)
			(sheetname "")
		)
		(fill yes
			(thermal_gap 0.5)
			(thermal_bridge_width 0.5)
			(island_removal_mode 0)
		)
		(polygon
			(pts
				(arc
					(start 270.417798 -291.8714)
					(mid 270.432677 -291.907321)
					(end 270.468598 -291.9222)
				)
				(arc
					(start 271.868138 -291.9222)
					(mid 271.904059 -291.907321)
					(end 271.918938 -291.8714)
				)
				(arc
					(start 271.918938 -291.46246)
					(mid 271.904059 -291.426539)
					(end 271.868138 -291.41166)
				)
				(arc
					(start 270.468598 -291.41166)
					(mid 270.432677 -291.426539)
					(end 270.417798 -291.46246)
				)
			)
		)
	)
	(zone
		(layers "In1.Cu" "In2.Cu")
		(hatch none 0.5)
		(connect_pads
			(clearance 0)
		)
		(min_thickness 0.25)
		(keepout
			(tracks not_allowed)
			(vias allowed)
			(pads allowed)
			(copperpour not_allowed)
			(footprints allowed)
		)
		(placement
			(enabled no)
			(sheetname "")
		)
		(fill yes
			(thermal_gap 0.5)
			(thermal_bridge_width 0.5)
			(island_removal_mode 0)
		)
		(polygon
			(pts
				(arc
					(start 11.490198 -197.521322)
					(mid 11.505077 -197.557243)
					(end 11.540998 -197.572122)
				)
				(arc
					(start 12.940538 -197.572122)
					(mid 12.976459 -197.557243)
					(end 12.991338 -197.521322)
				)
				(arc
					(start 12.991338 -197.112382)
					(mid 12.976459 -197.076461)
					(end 12.940538 -197.061582)
				)
				(arc
					(start 11.540998 -197.061582)
					(mid 11.505077 -197.076461)
					(end 11.490198 -197.112382)
				)
			)
		)
	)
	(zone
		(layers "In1.Cu" "In2.Cu")
		(hatch none 0.5)
		(connect_pads
			(clearance 0)
		)
		(min_thickness 0.25)
		(keepout
			(tracks not_allowed)
			(vias allowed)
			(pads allowed)
			(copperpour not_allowed)
			(footprints allowed)
		)
		(placement
			(enabled no)
			(sheetname "")
		)
		(fill yes
			(thermal_gap 0.5)
			(thermal_bridge_width 0.5)
			(island_removal_mode 0)
		)
		(polygon
			(pts
				(arc
					(start 285.505398 -235.771436)
					(mid 285.520277 -235.807357)
					(end 285.556198 -235.822236)
				)
				(arc
					(start 286.955738 -235.822236)
					(mid 286.991659 -235.807357)
					(end 287.006538 -235.771436)
				)
				(arc
					(start 287.006538 -235.362496)
					(mid 286.991659 -235.326575)
					(end 286.955738 -235.311696)
				)
				(arc
					(start 285.556198 -235.311696)
					(mid 285.520277 -235.326575)
					(end 285.505398 -235.362496)
				)
			)
		)
	)
	(zone
		(layers "In1.Cu" "In2.Cu")
		(hatch none 0.5)
		(connect_pads
			(clearance 0)
		)
		(min_thickness 0.25)
		(keepout
			(tracks not_allowed)
			(vias allowed)
			(pads allowed)
			(copperpour not_allowed)
			(footprints allowed)
		)
		(placement
			(enabled no)
			(sheetname "")
		)
		(fill yes
			(thermal_gap 0.5)
			(thermal_bridge_width 0.5)
			(island_removal_mode 0)
		)
		(polygon
			(pts
				(arc
					(start 158.06293 -226.421442)
					(mid 158.077809 -226.457363)
					(end 158.11373 -226.472242)
				)
				(arc
					(start 159.51327 -226.472242)
					(mid 159.549191 -226.457363)
					(end 159.56407 -226.421442)
				)
				(arc
					(start 159.56407 -226.012502)
					(mid 159.549191 -225.976581)
					(end 159.51327 -225.961702)
				)
				(arc
					(start 158.11373 -225.961702)
					(mid 158.077809 -225.976581)
					(end 158.06293 -226.012502)
				)
			)
		)
	)
	(zone
		(layers "In1.Cu" "In2.Cu")
		(hatch none 0.5)
		(connect_pads
			(clearance 0)
		)
		(min_thickness 0.25)
		(keepout
			(tracks not_allowed)
			(vias allowed)
			(pads allowed)
			(copperpour not_allowed)
			(footprints allowed)
		)
		(placement
			(enabled no)
			(sheetname "")
		)
		(fill yes
			(thermal_gap 0.5)
			(thermal_bridge_width 0.5)
			(island_removal_mode 0)
		)
		(polygon
			(pts
				(arc
					(start 14.93393 -303.7713)
					(mid 14.948809 -303.807221)
					(end 14.98473 -303.8221)
				)
				(arc
					(start 16.38427 -303.8221)
					(mid 16.420191 -303.807221)
					(end 16.43507 -303.7713)
				)
				(arc
					(start 16.43507 -303.36236)
					(mid 16.420191 -303.326439)
					(end 16.38427 -303.31156)
				)
				(arc
					(start 14.98473 -303.31156)
					(mid 14.948809 -303.326439)
					(end 14.93393 -303.36236)
				)
			)
		)
	)
	(zone
		(layers "In1.Cu" "In2.Cu")
		(hatch none 0.5)
		(connect_pads
			(clearance 0)
		)
		(min_thickness 0.25)
		(keepout
			(tracks not_allowed)
			(vias allowed)
			(pads allowed)
			(copperpour not_allowed)
			(footprints allowed)
		)
		(placement
			(enabled no)
			(sheetname "")
		)
		(fill yes
			(thermal_gap 0.5)
			(thermal_bridge_width 0.5)
			(island_removal_mode 0)
		)
		(polygon
			(pts
				(arc
					(start 259.430266 -250.221496)
					(mid 259.445145 -250.257417)
					(end 259.481066 -250.272296)
				)
				(arc
					(start 260.880606 -250.272296)
					(mid 260.916527 -250.257417)
					(end 260.931406 -250.221496)
				)
				(arc
					(start 260.931406 -249.812556)
					(mid 260.916527 -249.776635)
					(end 260.880606 -249.761756)
				)
				(arc
					(start 259.481066 -249.761756)
					(mid 259.445145 -249.776635)
					(end 259.430266 -249.812556)
				)
			)
		)
	)
	(zone
		(layers "In1.Cu" "In2.Cu")
		(hatch none 0.5)
		(connect_pads
			(clearance 0)
		)
		(min_thickness 0.25)
		(keepout
			(tracks not_allowed)
			(vias allowed)
			(pads allowed)
			(copperpour not_allowed)
			(footprints allowed)
		)
		(placement
			(enabled no)
			(sheetname "")
		)
		(fill yes
			(thermal_gap 0.5)
			(thermal_bridge_width 0.5)
			(island_removal_mode 0)
		)
		(polygon
			(pts
				(arc
					(start 188.23813 -307.171344)
					(mid 188.253009 -307.207265)
					(end 188.28893 -307.222144)
				)
				(arc
					(start 189.68847 -307.222144)
					(mid 189.724391 -307.207265)
					(end 189.73927 -307.171344)
				)
				(arc
					(start 189.73927 -306.762404)
					(mid 189.724391 -306.726483)
					(end 189.68847 -306.711604)
				)
				(arc
					(start 188.28893 -306.711604)
					(mid 188.253009 -306.726483)
					(end 188.23813 -306.762404)
				)
			)
		)
	)
	(zone
		(layers "In1.Cu" "In2.Cu")
		(hatch none 0.5)
		(connect_pads
			(clearance 0)
		)
		(min_thickness 0.25)
		(keepout
			(tracks not_allowed)
			(vias allowed)
			(pads allowed)
			(copperpour not_allowed)
			(footprints allowed)
		)
		(placement
			(enabled no)
			(sheetname "")
		)
		(fill yes
			(thermal_gap 0.5)
			(thermal_bridge_width 0.5)
			(island_removal_mode 0)
		)
		(polygon
			(pts
				(arc
					(start 34.121598 -197.521322)
					(mid 34.136477 -197.557243)
					(end 34.172398 -197.572122)
				)
				(arc
					(start 35.571938 -197.572122)
					(mid 35.607859 -197.557243)
					(end 35.622738 -197.521322)
				)
				(arc
					(start 35.622738 -197.112382)
					(mid 35.607859 -197.076461)
					(end 35.571938 -197.061582)
				)
				(arc
					(start 34.172398 -197.061582)
					(mid 34.136477 -197.076461)
					(end 34.121598 -197.112382)
				)
			)
		)
	)
	(zone
		(layers "In1.Cu" "In2.Cu")
		(hatch none 0.5)
		(connect_pads
			(clearance 0)
		)
		(min_thickness 0.25)
		(keepout
			(tracks not_allowed)
			(vias allowed)
			(pads allowed)
			(copperpour not_allowed)
			(footprints allowed)
		)
		(placement
			(enabled no)
			(sheetname "")
		)
		(fill yes
			(thermal_gap 0.5)
			(thermal_bridge_width 0.5)
			(island_removal_mode 0)
		)
		(polygon
			(pts
				(arc
					(start 188.23813 -279.121362)
					(mid 188.253009 -279.157283)
					(end 188.28893 -279.172162)
				)
				(arc
					(start 189.68847 -279.172162)
					(mid 189.724391 -279.157283)
					(end 189.73927 -279.121362)
				)
				(arc
					(start 189.73927 -278.712422)
					(mid 189.724391 -278.676501)
					(end 189.68847 -278.661622)
				)
				(arc
					(start 188.28893 -278.661622)
					(mid 188.253009 -278.676501)
					(end 188.23813 -278.712422)
				)
			)
		)
	)
	(zone
		(layers "In1.Cu" "In2.Cu")
		(hatch none 0.5)
		(connect_pads
			(clearance 0)
		)
		(min_thickness 0.25)
		(keepout
			(tracks not_allowed)
			(vias allowed)
			(pads allowed)
			(copperpour not_allowed)
			(footprints allowed)
		)
		(placement
			(enabled no)
			(sheetname "")
		)
		(fill yes
			(thermal_gap 0.5)
			(thermal_bridge_width 0.5)
			(island_removal_mode 0)
		)
		(polygon
			(pts
				(arc
					(start 266.974066 -250.221496)
					(mid 266.988945 -250.257417)
					(end 267.024866 -250.272296)
				)
				(arc
					(start 268.424406 -250.272296)
					(mid 268.460327 -250.257417)
					(end 268.475206 -250.221496)
				)
				(arc
					(start 268.475206 -249.812556)
					(mid 268.460327 -249.776635)
					(end 268.424406 -249.761756)
				)
				(arc
					(start 267.024866 -249.761756)
					(mid 266.988945 -249.776635)
					(end 266.974066 -249.812556)
				)
			)
		)
	)
	(zone
		(layers "In1.Cu" "In2.Cu")
		(hatch none 0.5)
		(connect_pads
			(clearance 0)
		)
		(min_thickness 0.25)
		(keepout
			(tracks not_allowed)
			(vias allowed)
			(pads allowed)
			(copperpour not_allowed)
			(footprints allowed)
		)
		(placement
			(enabled no)
			(sheetname "")
		)
		(fill yes
			(thermal_gap 0.5)
			(thermal_bridge_width 0.5)
			(island_removal_mode 0)
		)
		(polygon
			(pts
				(arc
					(start 425.190666 -205.171548)
					(mid 425.205545 -205.207469)
					(end 425.241466 -205.222348)
				)
				(arc
					(start 426.641006 -205.222348)
					(mid 426.676927 -205.207469)
					(end 426.691806 -205.171548)
				)
				(arc
					(start 426.691806 -204.762608)
					(mid 426.676927 -204.726687)
					(end 426.641006 -204.711808)
				)
				(arc
					(start 425.241466 -204.711808)
					(mid 425.205545 -204.726687)
					(end 425.190666 -204.762608)
				)
			)
		)
	)
	(zone
		(layers "In1.Cu" "In2.Cu")
		(hatch none 0.5)
		(connect_pads
			(clearance 0)
		)
		(min_thickness 0.25)
		(keepout
			(tracks not_allowed)
			(vias allowed)
			(pads allowed)
			(copperpour not_allowed)
			(footprints allowed)
		)
		(placement
			(enabled no)
			(sheetname "")
		)
		(fill yes
			(thermal_gap 0.5)
			(thermal_bridge_width 0.5)
			(island_removal_mode 0)
		)
		(polygon
			(pts
				(arc
					(start 259.430266 -300.37151)
					(mid 259.445145 -300.407431)
					(end 259.481066 -300.42231)
				)
				(arc
					(start 260.880606 -300.42231)
					(mid 260.916527 -300.407431)
					(end 260.931406 -300.37151)
				)
				(arc
					(start 260.931406 -299.96257)
					(mid 260.916527 -299.926649)
					(end 260.880606 -299.91177)
				)
				(arc
					(start 259.481066 -299.91177)
					(mid 259.445145 -299.926649)
					(end 259.430266 -299.96257)
				)
			)
		)
	)
	(zone
		(layers "In1.Cu" "In2.Cu")
		(hatch none 0.5)
		(connect_pads
			(clearance 0)
		)
		(min_thickness 0.25)
		(keepout
			(tracks not_allowed)
			(vias allowed)
			(pads allowed)
			(copperpour not_allowed)
			(footprints allowed)
		)
		(placement
			(enabled no)
			(sheetname "")
		)
		(fill yes
			(thermal_gap 0.5)
			(thermal_bridge_width 0.5)
			(island_removal_mode 0)
		)
		(polygon
			(pts
				(arc
					(start 162.162998 -248.521474)
					(mid 162.177877 -248.557395)
					(end 162.213798 -248.572274)
				)
				(arc
					(start 163.613338 -248.572274)
					(mid 163.649259 -248.557395)
					(end 163.664138 -248.521474)
				)
				(arc
					(start 163.664138 -248.112534)
					(mid 163.649259 -248.076613)
					(end 163.613338 -248.061734)
				)
				(arc
					(start 162.213798 -248.061734)
					(mid 162.177877 -248.076613)
					(end 162.162998 -248.112534)
				)
			)
		)
	)
	(zone
		(layers "In1.Cu" "In2.Cu")
		(hatch none 0.5)
		(connect_pads
			(clearance 0)
		)
		(min_thickness 0.25)
		(keepout
			(tracks not_allowed)
			(vias allowed)
			(pads allowed)
			(copperpour not_allowed)
			(footprints allowed)
		)
		(placement
			(enabled no)
			(sheetname "")
		)
		(fill yes
			(thermal_gap 0.5)
			(thermal_bridge_width 0.5)
			(island_removal_mode 0)
		)
		(polygon
			(pts
				(arc
					(start 60.19673 -249.371358)
					(mid 60.211609 -249.407279)
					(end 60.24753 -249.422158)
				)
				(arc
					(start 61.64707 -249.422158)
					(mid 61.682991 -249.407279)
					(end 61.69787 -249.371358)
				)
				(arc
					(start 61.69787 -248.962418)
					(mid 61.682991 -248.926497)
					(end 61.64707 -248.911618)
				)
				(arc
					(start 60.24753 -248.911618)
					(mid 60.211609 -248.926497)
					(end 60.19673 -248.962418)
				)
			)
		)
	)
	(zone
		(layers "In1.Cu" "In2.Cu")
		(hatch none 0.5)
		(connect_pads
			(clearance 0)
		)
		(min_thickness 0.25)
		(keepout
			(tracks not_allowed)
			(vias allowed)
			(pads allowed)
			(copperpour not_allowed)
			(footprints allowed)
		)
		(placement
			(enabled no)
			(sheetname "")
		)
		(fill yes
			(thermal_gap 0.5)
			(thermal_bridge_width 0.5)
			(island_removal_mode 0)
		)
		(polygon
			(pts
				(arc
					(start 165.60673 -241.721386)
					(mid 165.621609 -241.757307)
					(end 165.65753 -241.772186)
				)
				(arc
					(start 167.05707 -241.772186)
					(mid 167.092991 -241.757307)
					(end 167.10787 -241.721386)
				)
				(arc
					(start 167.10787 -241.312446)
					(mid 167.092991 -241.276525)
					(end 167.05707 -241.261646)
				)
				(arc
					(start 165.65753 -241.261646)
					(mid 165.621609 -241.276525)
					(end 165.60673 -241.312446)
				)
			)
		)
	)
	(zone
		(layers "In1.Cu" "In2.Cu")
		(hatch none 0.5)
		(connect_pads
			(clearance 0)
		)
		(min_thickness 0.25)
		(keepout
			(tracks not_allowed)
			(vias allowed)
			(pads allowed)
			(copperpour not_allowed)
			(footprints allowed)
		)
		(placement
			(enabled no)
			(sheetname "")
		)
		(fill yes
			(thermal_gap 0.5)
			(thermal_bridge_width 0.5)
			(island_removal_mode 0)
		)
		(polygon
			(pts
				(arc
					(start 443.721998 -200.071482)
					(mid 443.736877 -200.107403)
					(end 443.772798 -200.122282)
				)
				(arc
					(start 445.172338 -200.122282)
					(mid 445.208259 -200.107403)
					(end 445.223138 -200.071482)
				)
				(arc
					(start 445.223138 -199.662542)
					(mid 445.208259 -199.626621)
					(end 445.172338 -199.611742)
				)
				(arc
					(start 443.772798 -199.611742)
					(mid 443.736877 -199.626621)
					(end 443.721998 -199.662542)
				)
			)
		)
	)
	(zone
		(layers "In1.Cu" "In2.Cu")
		(hatch none 0.5)
		(connect_pads
			(clearance 0)
		)
		(min_thickness 0.25)
		(keepout
			(tracks not_allowed)
			(vias allowed)
			(pads allowed)
			(copperpour not_allowed)
			(footprints allowed)
		)
		(placement
			(enabled no)
			(sheetname "")
		)
		(fill yes
			(thermal_gap 0.5)
			(thermal_bridge_width 0.5)
			(island_removal_mode 0)
		)
		(polygon
			(pts
				(arc
					(start 64.296798 -208.571338)
					(mid 64.311677 -208.607259)
					(end 64.347598 -208.622138)
				)
				(arc
					(start 65.747138 -208.622138)
					(mid 65.783059 -208.607259)
					(end 65.797938 -208.571338)
				)
				(arc
					(start 65.797938 -208.162398)
					(mid 65.783059 -208.126477)
					(end 65.747138 -208.111598)
				)
				(arc
					(start 64.347598 -208.111598)
					(mid 64.311677 -208.126477)
					(end 64.296798 -208.162398)
				)
			)
		)
	)
	(zone
		(layers "In1.Cu" "In2.Cu")
		(hatch none 0.5)
		(connect_pads
			(clearance 0)
		)
		(min_thickness 0.25)
		(keepout
			(tracks not_allowed)
			(vias allowed)
			(pads allowed)
			(copperpour not_allowed)
			(footprints allowed)
		)
		(placement
			(enabled no)
			(sheetname "")
		)
		(fill yes
			(thermal_gap 0.5)
			(thermal_bridge_width 0.5)
			(island_removal_mode 0)
		)
		(polygon
			(pts
				(arc
					(start 19.033998 -225.571304)
					(mid 19.048877 -225.607225)
					(end 19.084798 -225.622104)
				)
				(arc
					(start 20.484338 -225.622104)
					(mid 20.520259 -225.607225)
					(end 20.535138 -225.571304)
				)
				(arc
					(start 20.535138 -225.162364)
					(mid 20.520259 -225.126443)
					(end 20.484338 -225.111564)
				)
				(arc
					(start 19.084798 -225.111564)
					(mid 19.048877 -225.126443)
					(end 19.033998 -225.162364)
				)
			)
		)
	)
	(zone
		(layers "In1.Cu" "In2.Cu")
		(hatch none 0.5)
		(connect_pads
			(clearance 0)
		)
		(min_thickness 0.25)
		(keepout
			(tracks not_allowed)
			(vias allowed)
			(pads allowed)
			(copperpour not_allowed)
			(footprints allowed)
		)
		(placement
			(enabled no)
			(sheetname "")
		)
		(fill yes
			(thermal_gap 0.5)
			(thermal_bridge_width 0.5)
			(island_removal_mode 0)
		)
		(polygon
			(pts
				(arc
					(start 19.033998 -217.921332)
					(mid 19.048877 -217.957253)
					(end 19.084798 -217.972132)
				)
				(arc
					(start 20.484338 -217.972132)
					(mid 20.520259 -217.957253)
					(end 20.535138 -217.921332)
				)
				(arc
					(start 20.535138 -217.512392)
					(mid 20.520259 -217.476471)
					(end 20.484338 -217.461592)
				)
				(arc
					(start 19.084798 -217.461592)
					(mid 19.048877 -217.476471)
					(end 19.033998 -217.512392)
				)
			)
		)
	)
	(zone
		(layers "In1.Cu" "In2.Cu")
		(hatch none 0.5)
		(connect_pads
			(clearance 0)
		)
		(min_thickness 0.25)
		(keepout
			(tracks not_allowed)
			(vias allowed)
			(pads allowed)
			(copperpour not_allowed)
			(footprints allowed)
		)
		(placement
			(enabled no)
			(sheetname "")
		)
		(fill yes
			(thermal_gap 0.5)
			(thermal_bridge_width 0.5)
			(island_removal_mode 0)
		)
		(polygon
			(pts
				(arc
					(start 173.15053 -291.8714)
					(mid 173.165409 -291.907321)
					(end 173.20133 -291.9222)
				)
				(arc
					(start 174.60087 -291.9222)
					(mid 174.636791 -291.907321)
					(end 174.65167 -291.8714)
				)
				(arc
					(start 174.65167 -291.46246)
					(mid 174.636791 -291.426539)
					(end 174.60087 -291.41166)
				)
				(arc
					(start 173.20133 -291.41166)
					(mid 173.165409 -291.426539)
					(end 173.15053 -291.46246)
				)
			)
		)
	)
	(zone
		(layers "In1.Cu" "In2.Cu")
		(hatch none 0.5)
		(connect_pads
			(clearance 0)
		)
		(min_thickness 0.25)
		(keepout
			(tracks not_allowed)
			(vias allowed)
			(pads allowed)
			(copperpour not_allowed)
			(footprints allowed)
		)
		(placement
			(enabled no)
			(sheetname "")
		)
		(fill yes
			(thermal_gap 0.5)
			(thermal_bridge_width 0.5)
			(island_removal_mode 0)
		)
		(polygon
			(pts
				(arc
					(start 451.265798 -230.67137)
					(mid 451.280677 -230.707291)
					(end 451.316598 -230.72217)
				)
				(arc
					(start 452.716138 -230.72217)
					(mid 452.752059 -230.707291)
					(end 452.766938 -230.67137)
				)
				(arc
					(start 452.766938 -230.26243)
					(mid 452.752059 -230.226509)
					(end 452.716138 -230.21163)
				)
				(arc
					(start 451.316598 -230.21163)
					(mid 451.280677 -230.226509)
					(end 451.265798 -230.26243)
				)
			)
		)
	)
	(zone
		(layers "In1.Cu" "In2.Cu")
		(hatch none 0.5)
		(connect_pads
			(clearance 0)
		)
		(min_thickness 0.25)
		(keepout
			(tracks not_allowed)
			(vias allowed)
			(pads allowed)
			(copperpour not_allowed)
			(footprints allowed)
		)
		(placement
			(enabled no)
			(sheetname "")
		)
		(fill yes
			(thermal_gap 0.5)
			(thermal_bridge_width 0.5)
			(island_removal_mode 0)
		)
		(polygon
			(pts
				(arc
					(start 417.646866 -304.621438)
					(mid 417.661745 -304.657359)
					(end 417.697666 -304.672238)
				)
				(arc
					(start 419.097206 -304.672238)
					(mid 419.133127 -304.657359)
					(end 419.148006 -304.621438)
				)
				(arc
					(start 419.148006 -304.212498)
					(mid 419.133127 -304.176577)
					(end 419.097206 -304.161698)
				)
				(arc
					(start 417.697666 -304.161698)
					(mid 417.661745 -304.176577)
					(end 417.646866 -304.212498)
				)
			)
		)
	)
	(zone
		(layers "In1.Cu" "In2.Cu")
		(hatch none 0.5)
		(connect_pads
			(clearance 0)
		)
		(min_thickness 0.25)
		(keepout
			(tracks not_allowed)
			(vias allowed)
			(pads allowed)
			(copperpour not_allowed)
			(footprints allowed)
		)
		(placement
			(enabled no)
			(sheetname "")
		)
		(fill yes
			(thermal_gap 0.5)
			(thermal_bridge_width 0.5)
			(island_removal_mode 0)
		)
		(polygon
			(pts
				(arc
					(start 277.961598 -223.021398)
					(mid 277.976477 -223.057319)
					(end 278.012398 -223.072198)
				)
				(arc
					(start 279.411938 -223.072198)
					(mid 279.447859 -223.057319)
					(end 279.462738 -223.021398)
				)
				(arc
					(start 279.462738 -222.612458)
					(mid 279.447859 -222.576537)
					(end 279.411938 -222.561658)
				)
				(arc
					(start 278.012398 -222.561658)
					(mid 277.976477 -222.576537)
					(end 277.961598 -222.612458)
				)
			)
		)
	)
	(zone
		(layers "In1.Cu" "In2.Cu")
		(hatch none 0.5)
		(connect_pads
			(clearance 0)
		)
		(min_thickness 0.25)
		(keepout
			(tracks not_allowed)
			(vias allowed)
			(pads allowed)
			(copperpour not_allowed)
			(footprints allowed)
		)
		(placement
			(enabled no)
			(sheetname "")
		)
		(fill yes
			(thermal_gap 0.5)
			(thermal_bridge_width 0.5)
			(island_removal_mode 0)
		)
		(polygon
			(pts
				(arc
					(start 285.505398 -284.221428)
					(mid 285.520277 -284.257349)
					(end 285.556198 -284.272228)
				)
				(arc
					(start 286.955738 -284.272228)
					(mid 286.991659 -284.257349)
					(end 287.006538 -284.221428)
				)
				(arc
					(start 287.006538 -283.812488)
					(mid 286.991659 -283.776567)
					(end 286.955738 -283.761688)
				)
				(arc
					(start 285.556198 -283.761688)
					(mid 285.520277 -283.776567)
					(end 285.505398 -283.812488)
				)
			)
		)
	)
	(zone
		(layers "In1.Cu" "In2.Cu")
		(hatch none 0.5)
		(connect_pads
			(clearance 0)
		)
		(min_thickness 0.25)
		(keepout
			(tracks not_allowed)
			(vias allowed)
			(pads allowed)
			(copperpour not_allowed)
			(footprints allowed)
		)
		(placement
			(enabled no)
			(sheetname "")
		)
		(fill yes
			(thermal_gap 0.5)
			(thermal_bridge_width 0.5)
			(island_removal_mode 0)
		)
		(polygon
			(pts
				(arc
					(start 45.10913 -273.171412)
					(mid 45.124009 -273.207333)
					(end 45.15993 -273.222212)
				)
				(arc
					(start 46.55947 -273.222212)
					(mid 46.595391 -273.207333)
					(end 46.61027 -273.171412)
				)
				(arc
					(start 46.61027 -272.762472)
					(mid 46.595391 -272.726551)
					(end 46.55947 -272.711672)
				)
				(arc
					(start 45.15993 -272.711672)
					(mid 45.124009 -272.726551)
					(end 45.10913 -272.762472)
				)
			)
		)
	)
	(zone
		(layers "In1.Cu" "In2.Cu")
		(hatch none 0.5)
		(connect_pads
			(clearance 0)
		)
		(min_thickness 0.25)
		(keepout
			(tracks not_allowed)
			(vias allowed)
			(pads allowed)
			(copperpour not_allowed)
			(footprints allowed)
		)
		(placement
			(enabled no)
			(sheetname "")
		)
		(fill yes
			(thermal_gap 0.5)
			(thermal_bridge_width 0.5)
			(island_removal_mode 0)
		)
		(polygon
			(pts
				(arc
					(start 259.430266 -206.871316)
					(mid 259.445145 -206.907237)
					(end 259.481066 -206.922116)
				)
				(arc
					(start 260.880606 -206.922116)
					(mid 260.916527 -206.907237)
					(end 260.931406 -206.871316)
				)
				(arc
					(start 260.931406 -206.462376)
					(mid 260.916527 -206.426455)
					(end 260.880606 -206.411576)
				)
				(arc
					(start 259.481066 -206.411576)
					(mid 259.445145 -206.426455)
					(end 259.430266 -206.462376)
				)
			)
		)
	)
	(zone
		(layers "In1.Cu" "In2.Cu")
		(hatch none 0.5)
		(connect_pads
			(clearance 0)
		)
		(min_thickness 0.25)
		(keepout
			(tracks not_allowed)
			(vias allowed)
			(pads allowed)
			(copperpour not_allowed)
			(footprints allowed)
		)
		(placement
			(enabled no)
			(sheetname "")
		)
		(fill yes
			(thermal_gap 0.5)
			(thermal_bridge_width 0.5)
			(island_removal_mode 0)
		)
		(polygon
			(pts
				(arc
					(start 37.56533 -252.771402)
					(mid 37.580209 -252.807323)
					(end 37.61613 -252.822202)
				)
				(arc
					(start 39.01567 -252.822202)
					(mid 39.051591 -252.807323)
					(end 39.06647 -252.771402)
				)
				(arc
					(start 39.06647 -252.362462)
					(mid 39.051591 -252.326541)
					(end 39.01567 -252.311662)
				)
				(arc
					(start 37.61613 -252.311662)
					(mid 37.580209 -252.326541)
					(end 37.56533 -252.362462)
				)
			)
		)
	)
	(zone
		(layers "In1.Cu" "In2.Cu")
		(hatch none 0.5)
		(connect_pads
			(clearance 0)
		)
		(min_thickness 0.25)
		(keepout
			(tracks not_allowed)
			(vias allowed)
			(pads allowed)
			(copperpour not_allowed)
			(footprints allowed)
		)
		(placement
			(enabled no)
			(sheetname "")
		)
		(fill yes
			(thermal_gap 0.5)
			(thermal_bridge_width 0.5)
			(island_removal_mode 0)
		)
		(polygon
			(pts
				(arc
					(start 177.250598 -304.621438)
					(mid 177.265477 -304.657359)
					(end 177.301398 -304.672238)
				)
				(arc
					(start 178.700938 -304.672238)
					(mid 178.736859 -304.657359)
					(end 178.751738 -304.621438)
				)
				(arc
					(start 178.751738 -304.212498)
					(mid 178.736859 -304.176577)
					(end 178.700938 -304.161698)
				)
				(arc
					(start 177.301398 -304.161698)
					(mid 177.265477 -304.176577)
					(end 177.250598 -304.212498)
				)
			)
		)
	)
	(zone
		(layers "In1.Cu" "In2.Cu")
		(hatch none 0.5)
		(connect_pads
			(clearance 0)
		)
		(min_thickness 0.25)
		(keepout
			(tracks not_allowed)
			(vias allowed)
			(pads allowed)
			(copperpour not_allowed)
			(footprints allowed)
		)
		(placement
			(enabled no)
			(sheetname "")
		)
		(fill yes
			(thermal_gap 0.5)
			(thermal_bridge_width 0.5)
			(island_removal_mode 0)
		)
		(polygon
			(pts
				(arc
					(start 297.149266 -312.27141)
					(mid 297.164145 -312.307331)
					(end 297.200066 -312.32221)
				)
				(arc
					(start 298.599606 -312.32221)
					(mid 298.635527 -312.307331)
					(end 298.650406 -312.27141)
				)
				(arc
					(start 298.650406 -311.86247)
					(mid 298.635527 -311.826549)
					(end 298.599606 -311.81167)
				)
				(arc
					(start 297.200066 -311.81167)
					(mid 297.164145 -311.826549)
					(end 297.149266 -311.86247)
				)
			)
		)
	)
	(zone
		(layers "In1.Cu" "In2.Cu")
		(hatch none 0.5)
		(connect_pads
			(clearance 0)
		)
		(min_thickness 0.25)
		(keepout
			(tracks not_allowed)
			(vias allowed)
			(pads allowed)
			(copperpour not_allowed)
			(footprints allowed)
		)
		(placement
			(enabled no)
			(sheetname "")
		)
		(fill yes
			(thermal_gap 0.5)
			(thermal_bridge_width 0.5)
			(island_removal_mode 0)
		)
		(polygon
			(pts
				(arc
					(start 180.69433 -282.521406)
					(mid 180.709209 -282.557327)
					(end 180.74513 -282.572206)
				)
				(arc
					(start 182.14467 -282.572206)
					(mid 182.180591 -282.557327)
					(end 182.19547 -282.521406)
				)
				(arc
					(start 182.19547 -282.112466)
					(mid 182.180591 -282.076545)
					(end 182.14467 -282.061666)
				)
				(arc
					(start 180.74513 -282.061666)
					(mid 180.709209 -282.076545)
					(end 180.69433 -282.112466)
				)
			)
		)
	)
	(zone
		(layers "In1.Cu" "In2.Cu")
		(hatch none 0.5)
		(connect_pads
			(clearance 0)
		)
		(min_thickness 0.25)
		(keepout
			(tracks not_allowed)
			(vias allowed)
			(pads allowed)
			(copperpour not_allowed)
			(footprints allowed)
		)
		(placement
			(enabled no)
			(sheetname "")
		)
		(fill yes
			(thermal_gap 0.5)
			(thermal_bridge_width 0.5)
			(island_removal_mode 0)
		)
		(polygon
			(pts
				(arc
					(start 30.02153 -234.071414)
					(mid 30.036409 -234.107335)
					(end 30.07233 -234.122214)
				)
				(arc
					(start 31.47187 -234.122214)
					(mid 31.507791 -234.107335)
					(end 31.52267 -234.071414)
				)
				(arc
					(start 31.52267 -233.662474)
					(mid 31.507791 -233.626553)
					(end 31.47187 -233.611674)
				)
				(arc
					(start 30.07233 -233.611674)
					(mid 30.036409 -233.626553)
					(end 30.02153 -233.662474)
				)
			)
		)
	)
	(zone
		(layers "In1.Cu" "In2.Cu")
		(hatch none 0.5)
		(connect_pads
			(clearance 0)
		)
		(min_thickness 0.25)
		(keepout
			(tracks not_allowed)
			(vias allowed)
			(pads allowed)
			(copperpour not_allowed)
			(footprints allowed)
		)
		(placement
			(enabled no)
			(sheetname "")
		)
		(fill yes
			(thermal_gap 0.5)
			(thermal_bridge_width 0.5)
			(island_removal_mode 0)
		)
		(polygon
			(pts
				(arc
					(start 192.338198 -203.471526)
					(mid 192.353077 -203.507447)
					(end 192.388998 -203.522326)
				)
				(arc
					(start 193.788538 -203.522326)
					(mid 193.824459 -203.507447)
					(end 193.839338 -203.471526)
				)
				(arc
					(start 193.839338 -203.062586)
					(mid 193.824459 -203.026665)
					(end 193.788538 -203.011786)
				)
				(arc
					(start 192.388998 -203.011786)
					(mid 192.353077 -203.026665)
					(end 192.338198 -203.062586)
				)
			)
		)
	)
	(zone
		(layers "In1.Cu" "In2.Cu")
		(hatch none 0.5)
		(connect_pads
			(clearance 0)
		)
		(min_thickness 0.25)
		(keepout
			(tracks not_allowed)
			(vias allowed)
			(pads allowed)
			(copperpour not_allowed)
			(footprints allowed)
		)
		(placement
			(enabled no)
			(sheetname "")
		)
		(fill yes
			(thermal_gap 0.5)
			(thermal_bridge_width 0.5)
			(island_removal_mode 0)
		)
		(polygon
			(pts
				(arc
					(start 259.430266 -245.12143)
					(mid 259.445145 -245.157351)
					(end 259.481066 -245.17223)
				)
				(arc
					(start 260.880606 -245.17223)
					(mid 260.916527 -245.157351)
					(end 260.931406 -245.12143)
				)
				(arc
					(start 260.931406 -244.71249)
					(mid 260.916527 -244.676569)
					(end 260.880606 -244.66169)
				)
				(arc
					(start 259.481066 -244.66169)
					(mid 259.445145 -244.676569)
					(end 259.430266 -244.71249)
				)
			)
		)
	)
	(zone
		(layers "In1.Cu" "In2.Cu")
		(hatch none 0.5)
		(connect_pads
			(clearance 0)
		)
		(min_thickness 0.25)
		(keepout
			(tracks not_allowed)
			(vias allowed)
			(pads allowed)
			(copperpour not_allowed)
			(footprints allowed)
		)
		(placement
			(enabled no)
			(sheetname "")
		)
		(fill yes
			(thermal_gap 0.5)
			(thermal_bridge_width 0.5)
			(island_removal_mode 0)
		)
		(polygon
			(pts
				(arc
					(start 180.69433 -223.021398)
					(mid 180.709209 -223.057319)
					(end 180.74513 -223.072198)
				)
				(arc
					(start 182.14467 -223.072198)
					(mid 182.180591 -223.057319)
					(end 182.19547 -223.021398)
				)
				(arc
					(start 182.19547 -222.612458)
					(mid 182.180591 -222.576537)
					(end 182.14467 -222.561658)
				)
				(arc
					(start 180.74513 -222.561658)
					(mid 180.709209 -222.576537)
					(end 180.69433 -222.612458)
				)
			)
		)
	)
	(zone
		(layers "In1.Cu" "In2.Cu")
		(hatch none 0.5)
		(connect_pads
			(clearance 0)
		)
		(min_thickness 0.25)
		(keepout
			(tracks not_allowed)
			(vias allowed)
			(pads allowed)
			(copperpour not_allowed)
			(footprints allowed)
		)
		(placement
			(enabled no)
			(sheetname "")
		)
		(fill yes
			(thermal_gap 0.5)
			(thermal_bridge_width 0.5)
			(island_removal_mode 0)
		)
		(polygon
			(pts
				(arc
					(start 289.605466 -291.021516)
					(mid 289.620345 -291.057437)
					(end 289.656266 -291.072316)
				)
				(arc
					(start 291.055806 -291.072316)
					(mid 291.091727 -291.057437)
					(end 291.106606 -291.021516)
				)
				(arc
					(start 291.106606 -290.612576)
					(mid 291.091727 -290.576655)
					(end 291.055806 -290.561776)
				)
				(arc
					(start 289.656266 -290.561776)
					(mid 289.620345 -290.576655)
					(end 289.605466 -290.612576)
				)
			)
		)
	)
	(zone
		(layers "In1.Cu" "In2.Cu")
		(hatch none 0.5)
		(connect_pads
			(clearance 0)
		)
		(min_thickness 0.25)
		(keepout
			(tracks not_allowed)
			(vias allowed)
			(pads allowed)
			(copperpour not_allowed)
			(footprints allowed)
		)
		(placement
			(enabled no)
			(sheetname "")
		)
		(fill yes
			(thermal_gap 0.5)
			(thermal_bridge_width 0.5)
			(island_removal_mode 0)
		)
		(polygon
			(pts
				(arc
					(start 308.136798 -238.321342)
					(mid 308.151677 -238.357263)
					(end 308.187598 -238.372142)
				)
				(arc
					(start 309.587138 -238.372142)
					(mid 309.623059 -238.357263)
					(end 309.637938 -238.321342)
				)
				(arc
					(start 309.637938 -237.912402)
					(mid 309.623059 -237.876481)
					(end 309.587138 -237.861602)
				)
				(arc
					(start 308.187598 -237.861602)
					(mid 308.151677 -237.876481)
					(end 308.136798 -237.912402)
				)
			)
		)
	)
	(zone
		(layers "In1.Cu" "In2.Cu")
		(hatch none 0.5)
		(connect_pads
			(clearance 0)
		)
		(min_thickness 0.25)
		(keepout
			(tracks not_allowed)
			(vias allowed)
			(pads allowed)
			(copperpour not_allowed)
			(footprints allowed)
		)
		(placement
			(enabled no)
			(sheetname "")
		)
		(fill yes
			(thermal_gap 0.5)
			(thermal_bridge_width 0.5)
			(island_removal_mode 0)
		)
		(polygon
			(pts
				(arc
					(start 255.330198 -228.971348)
					(mid 255.345077 -229.007269)
					(end 255.380998 -229.022148)
				)
				(arc
					(start 256.780538 -229.022148)
					(mid 256.816459 -229.007269)
					(end 256.831338 -228.971348)
				)
				(arc
					(start 256.831338 -228.562408)
					(mid 256.816459 -228.526487)
					(end 256.780538 -228.511608)
				)
				(arc
					(start 255.380998 -228.511608)
					(mid 255.345077 -228.526487)
					(end 255.330198 -228.562408)
				)
			)
		)
	)
	(zone
		(layers "In1.Cu" "In2.Cu")
		(hatch none 0.5)
		(connect_pads
			(clearance 0)
		)
		(min_thickness 0.25)
		(keepout
			(tracks not_allowed)
			(vias allowed)
			(pads allowed)
			(copperpour not_allowed)
			(footprints allowed)
		)
		(placement
			(enabled no)
			(sheetname "")
		)
		(fill yes
			(thermal_gap 0.5)
			(thermal_bridge_width 0.5)
			(island_removal_mode 0)
		)
		(polygon
			(pts
				(arc
					(start 207.425798 -268.921484)
					(mid 207.440677 -268.957405)
					(end 207.476598 -268.972284)
				)
				(arc
					(start 208.876138 -268.972284)
					(mid 208.912059 -268.957405)
					(end 208.926938 -268.921484)
				)
				(arc
					(start 208.926938 -268.512544)
					(mid 208.912059 -268.476623)
					(end 208.876138 -268.461744)
				)
				(arc
					(start 207.476598 -268.461744)
					(mid 207.440677 -268.476623)
					(end 207.425798 -268.512544)
				)
			)
		)
	)
	(zone
		(layers "In1.Cu" "In2.Cu")
		(hatch none 0.5)
		(connect_pads
			(clearance 0)
		)
		(min_thickness 0.25)
		(keepout
			(tracks not_allowed)
			(vias allowed)
			(pads allowed)
			(copperpour not_allowed)
			(footprints allowed)
		)
		(placement
			(enabled no)
			(sheetname "")
		)
		(fill yes
			(thermal_gap 0.5)
			(thermal_bridge_width 0.5)
			(island_removal_mode 0)
		)
		(polygon
			(pts
				(arc
					(start 64.296798 -218.77147)
					(mid 64.311677 -218.807391)
					(end 64.347598 -218.82227)
				)
				(arc
					(start 65.747138 -218.82227)
					(mid 65.783059 -218.807391)
					(end 65.797938 -218.77147)
				)
				(arc
					(start 65.797938 -218.36253)
					(mid 65.783059 -218.326609)
					(end 65.747138 -218.31173)
				)
				(arc
					(start 64.347598 -218.31173)
					(mid 64.311677 -218.326609)
					(end 64.296798 -218.36253)
				)
			)
		)
	)
	(zone
		(layers "In1.Cu" "In2.Cu")
		(hatch none 0.5)
		(connect_pads
			(clearance 0)
		)
		(min_thickness 0.25)
		(keepout
			(tracks not_allowed)
			(vias allowed)
			(pads allowed)
			(copperpour not_allowed)
			(footprints allowed)
		)
		(placement
			(enabled no)
			(sheetname "")
		)
		(fill yes
			(thermal_gap 0.5)
			(thermal_bridge_width 0.5)
			(island_removal_mode 0)
		)
		(polygon
			(pts
				(arc
					(start 64.296798 -272.321528)
					(mid 64.311677 -272.357449)
					(end 64.347598 -272.372328)
				)
				(arc
					(start 65.747138 -272.372328)
					(mid 65.783059 -272.357449)
					(end 65.797938 -272.321528)
				)
				(arc
					(start 65.797938 -271.912588)
					(mid 65.783059 -271.876667)
					(end 65.747138 -271.861788)
				)
				(arc
					(start 64.347598 -271.861788)
					(mid 64.311677 -271.876667)
					(end 64.296798 -271.912588)
				)
			)
		)
	)
	(zone
		(layers "In1.Cu" "In2.Cu")
		(hatch none 0.5)
		(connect_pads
			(clearance 0)
		)
		(min_thickness 0.25)
		(keepout
			(tracks not_allowed)
			(vias allowed)
			(pads allowed)
			(copperpour not_allowed)
			(footprints allowed)
		)
		(placement
			(enabled no)
			(sheetname "")
		)
		(fill yes
			(thermal_gap 0.5)
			(thermal_bridge_width 0.5)
			(island_removal_mode 0)
		)
		(polygon
			(pts
				(arc
					(start 312.236866 -278.271478)
					(mid 312.251745 -278.307399)
					(end 312.287666 -278.322278)
				)
				(arc
					(start 313.687206 -278.322278)
					(mid 313.723127 -278.307399)
					(end 313.738006 -278.271478)
				)
				(arc
					(start 313.738006 -277.862538)
					(mid 313.723127 -277.826617)
					(end 313.687206 -277.811738)
				)
				(arc
					(start 312.287666 -277.811738)
					(mid 312.251745 -277.826617)
					(end 312.236866 -277.862538)
				)
			)
		)
	)
	(zone
		(layers "In1.Cu" "In2.Cu")
		(hatch none 0.5)
		(connect_pads
			(clearance 0)
		)
		(min_thickness 0.25)
		(keepout
			(tracks not_allowed)
			(vias allowed)
			(pads allowed)
			(copperpour not_allowed)
			(footprints allowed)
		)
		(placement
			(enabled no)
			(sheetname "")
		)
		(fill yes
			(thermal_gap 0.5)
			(thermal_bridge_width 0.5)
			(island_removal_mode 0)
		)
		(polygon
			(pts
				(arc
					(start 30.02153 -217.071448)
					(mid 30.036409 -217.107369)
					(end 30.07233 -217.122248)
				)
				(arc
					(start 31.47187 -217.122248)
					(mid 31.507791 -217.107369)
					(end 31.52267 -217.071448)
				)
				(arc
					(start 31.52267 -216.662508)
					(mid 31.507791 -216.626587)
					(end 31.47187 -216.611708)
				)
				(arc
					(start 30.07233 -216.611708)
					(mid 30.036409 -216.626587)
					(end 30.02153 -216.662508)
				)
			)
		)
	)
	(zone
		(layers "In1.Cu" "In2.Cu")
		(hatch none 0.5)
		(connect_pads
			(clearance 0)
		)
		(min_thickness 0.25)
		(keepout
			(tracks not_allowed)
			(vias allowed)
			(pads allowed)
			(copperpour not_allowed)
			(footprints allowed)
		)
		(placement
			(enabled no)
			(sheetname "")
		)
		(fill yes
			(thermal_gap 0.5)
			(thermal_bridge_width 0.5)
			(island_removal_mode 0)
		)
		(polygon
			(pts
				(arc
					(start 447.822066 -292.721538)
					(mid 447.836945 -292.757459)
					(end 447.872866 -292.772338)
				)
				(arc
					(start 449.272406 -292.772338)
					(mid 449.308327 -292.757459)
					(end 449.323206 -292.721538)
				)
				(arc
					(start 449.323206 -292.312598)
					(mid 449.308327 -292.276677)
					(end 449.272406 -292.261798)
				)
				(arc
					(start 447.872866 -292.261798)
					(mid 447.836945 -292.276677)
					(end 447.822066 -292.312598)
				)
			)
		)
	)
	(zone
		(layers "In1.Cu" "In2.Cu")
		(hatch none 0.5)
		(connect_pads
			(clearance 0)
		)
		(min_thickness 0.25)
		(keepout
			(tracks not_allowed)
			(vias allowed)
			(pads allowed)
			(copperpour not_allowed)
			(footprints allowed)
		)
		(placement
			(enabled no)
			(sheetname "")
		)
		(fill yes
			(thermal_gap 0.5)
			(thermal_bridge_width 0.5)
			(island_removal_mode 0)
		)
		(polygon
			(pts
				(arc
					(start 184.794398 -206.871316)
					(mid 184.809277 -206.907237)
					(end 184.845198 -206.922116)
				)
				(arc
					(start 186.244738 -206.922116)
					(mid 186.280659 -206.907237)
					(end 186.295538 -206.871316)
				)
				(arc
					(start 186.295538 -206.462376)
					(mid 186.280659 -206.426455)
					(end 186.244738 -206.411576)
				)
				(arc
					(start 184.845198 -206.411576)
					(mid 184.809277 -206.426455)
					(end 184.794398 -206.462376)
				)
			)
		)
	)
	(zone
		(layers "In1.Cu" "In2.Cu")
		(hatch none 0.5)
		(connect_pads
			(clearance 0)
		)
		(min_thickness 0.25)
		(keepout
			(tracks not_allowed)
			(vias allowed)
			(pads allowed)
			(copperpour not_allowed)
			(footprints allowed)
		)
		(placement
			(enabled no)
			(sheetname "")
		)
		(fill yes
			(thermal_gap 0.5)
			(thermal_bridge_width 0.5)
			(island_removal_mode 0)
		)
		(polygon
			(pts
				(arc
					(start 162.162998 -295.271444)
					(mid 162.177877 -295.307365)
					(end 162.213798 -295.322244)
				)
				(arc
					(start 163.613338 -295.322244)
					(mid 163.649259 -295.307365)
					(end 163.664138 -295.271444)
				)
				(arc
					(start 163.664138 -294.862504)
					(mid 163.649259 -294.826583)
					(end 163.613338 -294.811704)
				)
				(arc
					(start 162.213798 -294.811704)
					(mid 162.177877 -294.826583)
					(end 162.162998 -294.862504)
				)
			)
		)
	)
	(zone
		(layers "In1.Cu" "In2.Cu")
		(hatch none 0.5)
		(connect_pads
			(clearance 0)
		)
		(min_thickness 0.25)
		(keepout
			(tracks not_allowed)
			(vias allowed)
			(pads allowed)
			(copperpour not_allowed)
			(footprints allowed)
		)
		(placement
			(enabled no)
			(sheetname "")
		)
		(fill yes
			(thermal_gap 0.5)
			(thermal_bridge_width 0.5)
			(island_removal_mode 0)
		)
		(polygon
			(pts
				(arc
					(start 195.78193 -206.021432)
					(mid 195.796809 -206.057353)
					(end 195.83273 -206.072232)
				)
				(arc
					(start 197.23227 -206.072232)
					(mid 197.268191 -206.057353)
					(end 197.28307 -206.021432)
				)
				(arc
					(start 197.28307 -205.612492)
					(mid 197.268191 -205.576571)
					(end 197.23227 -205.561692)
				)
				(arc
					(start 195.83273 -205.561692)
					(mid 195.796809 -205.576571)
					(end 195.78193 -205.612492)
				)
			)
		)
	)
	(zone
		(layers "In1.Cu" "In2.Cu")
		(hatch none 0.5)
		(connect_pads
			(clearance 0)
		)
		(min_thickness 0.25)
		(keepout
			(tracks not_allowed)
			(vias allowed)
			(pads allowed)
			(copperpour not_allowed)
			(footprints allowed)
		)
		(placement
			(enabled no)
			(sheetname "")
		)
		(fill yes
			(thermal_gap 0.5)
			(thermal_bridge_width 0.5)
			(island_removal_mode 0)
		)
		(polygon
			(pts
				(arc
					(start 45.10913 -209.421476)
					(mid 45.124009 -209.457397)
					(end 45.15993 -209.472276)
				)
				(arc
					(start 46.55947 -209.472276)
					(mid 46.595391 -209.457397)
					(end 46.61027 -209.421476)
				)
				(arc
					(start 46.61027 -209.012536)
					(mid 46.595391 -208.976615)
					(end 46.55947 -208.961736)
				)
				(arc
					(start 45.15993 -208.961736)
					(mid 45.124009 -208.976615)
					(end 45.10913 -209.012536)
				)
			)
		)
	)
	(zone
		(layers "In1.Cu" "In2.Cu")
		(hatch none 0.5)
		(connect_pads
			(clearance 0)
		)
		(min_thickness 0.25)
		(keepout
			(tracks not_allowed)
			(vias allowed)
			(pads allowed)
			(copperpour not_allowed)
			(footprints allowed)
		)
		(placement
			(enabled no)
			(sheetname "")
		)
		(fill yes
			(thermal_gap 0.5)
			(thermal_bridge_width 0.5)
			(island_removal_mode 0)
		)
		(polygon
			(pts
				(arc
					(start 406.002998 -202.621388)
					(mid 406.017877 -202.657309)
					(end 406.053798 -202.672188)
				)
				(arc
					(start 407.453338 -202.672188)
					(mid 407.489259 -202.657309)
					(end 407.504138 -202.621388)
				)
				(arc
					(start 407.504138 -202.212448)
					(mid 407.489259 -202.176527)
					(end 407.453338 -202.161648)
				)
				(arc
					(start 406.053798 -202.161648)
					(mid 406.017877 -202.176527)
					(end 406.002998 -202.212448)
				)
			)
		)
	)
	(zone
		(layers "In1.Cu" "In2.Cu")
		(hatch none 0.5)
		(connect_pads
			(clearance 0)
		)
		(min_thickness 0.25)
		(keepout
			(tracks not_allowed)
			(vias allowed)
			(pads allowed)
			(copperpour not_allowed)
			(footprints allowed)
		)
		(placement
			(enabled no)
			(sheetname "")
		)
		(fill yes
			(thermal_gap 0.5)
			(thermal_bridge_width 0.5)
			(island_removal_mode 0)
		)
		(polygon
			(pts
				(arc
					(start 207.425798 -208.571338)
					(mid 207.440677 -208.607259)
					(end 207.476598 -208.622138)
				)
				(arc
					(start 208.876138 -208.622138)
					(mid 208.912059 -208.607259)
					(end 208.926938 -208.571338)
				)
				(arc
					(start 208.926938 -208.162398)
					(mid 208.912059 -208.126477)
					(end 208.876138 -208.111598)
				)
				(arc
					(start 207.476598 -208.111598)
					(mid 207.440677 -208.126477)
					(end 207.425798 -208.162398)
				)
			)
		)
	)
	(zone
		(layers "In1.Cu" "In2.Cu")
		(hatch none 0.5)
		(connect_pads
			(clearance 0)
		)
		(min_thickness 0.25)
		(keepout
			(tracks not_allowed)
			(vias allowed)
			(pads allowed)
			(copperpour not_allowed)
			(footprints allowed)
		)
		(placement
			(enabled no)
			(sheetname "")
		)
		(fill yes
			(thermal_gap 0.5)
			(thermal_bridge_width 0.5)
			(island_removal_mode 0)
		)
		(polygon
			(pts
				(arc
					(start 22.47773 -243.421408)
					(mid 22.492609 -243.457329)
					(end 22.52853 -243.472208)
				)
				(arc
					(start 23.92807 -243.472208)
					(mid 23.963991 -243.457329)
					(end 23.97887 -243.421408)
				)
				(arc
					(start 23.97887 -243.012468)
					(mid 23.963991 -242.976547)
					(end 23.92807 -242.961668)
				)
				(arc
					(start 22.52853 -242.961668)
					(mid 22.492609 -242.976547)
					(end 22.47773 -243.012468)
				)
			)
		)
	)
	(zone
		(layers "In1.Cu" "In2.Cu")
		(hatch none 0.5)
		(connect_pads
			(clearance 0)
		)
		(min_thickness 0.25)
		(keepout
			(tracks not_allowed)
			(vias allowed)
			(pads allowed)
			(copperpour not_allowed)
			(footprints allowed)
		)
		(placement
			(enabled no)
			(sheetname "")
		)
		(fill yes
			(thermal_gap 0.5)
			(thermal_bridge_width 0.5)
			(island_removal_mode 0)
		)
		(polygon
			(pts
				(arc
					(start 180.69433 -307.171344)
					(mid 180.709209 -307.207265)
					(end 180.74513 -307.222144)
				)
				(arc
					(start 182.14467 -307.222144)
					(mid 182.180591 -307.207265)
					(end 182.19547 -307.171344)
				)
				(arc
					(start 182.19547 -306.762404)
					(mid 182.180591 -306.726483)
					(end 182.14467 -306.711604)
				)
				(arc
					(start 180.74513 -306.711604)
					(mid 180.709209 -306.726483)
					(end 180.69433 -306.762404)
				)
			)
		)
	)
	(zone
		(layers "In1.Cu" "In2.Cu")
		(hatch none 0.5)
		(connect_pads
			(clearance 0)
		)
		(min_thickness 0.25)
		(keepout
			(tracks not_allowed)
			(vias allowed)
			(pads allowed)
			(copperpour not_allowed)
			(footprints allowed)
		)
		(placement
			(enabled no)
			(sheetname "")
		)
		(fill yes
			(thermal_gap 0.5)
			(thermal_bridge_width 0.5)
			(island_removal_mode 0)
		)
		(polygon
			(pts
				(arc
					(start 262.873998 -230.67137)
					(mid 262.888877 -230.707291)
					(end 262.924798 -230.72217)
				)
				(arc
					(start 264.324338 -230.72217)
					(mid 264.360259 -230.707291)
					(end 264.375138 -230.67137)
				)
				(arc
					(start 264.375138 -230.26243)
					(mid 264.360259 -230.226509)
					(end 264.324338 -230.21163)
				)
				(arc
					(start 262.924798 -230.21163)
					(mid 262.888877 -230.226509)
					(end 262.873998 -230.26243)
				)
			)
		)
	)
	(zone
		(layers "In1.Cu" "In2.Cu")
		(hatch none 0.5)
		(connect_pads
			(clearance 0)
		)
		(min_thickness 0.25)
		(keepout
			(tracks not_allowed)
			(vias allowed)
			(pads allowed)
			(copperpour not_allowed)
			(footprints allowed)
		)
		(placement
			(enabled no)
			(sheetname "")
		)
		(fill yes
			(thermal_gap 0.5)
			(thermal_bridge_width 0.5)
			(island_removal_mode 0)
		)
		(polygon
			(pts
				(arc
					(start 7.39013 -313.121294)
					(mid 7.405009 -313.157215)
					(end 7.44093 -313.172094)
				)
				(arc
					(start 8.84047 -313.172094)
					(mid 8.876391 -313.157215)
					(end 8.89127 -313.121294)
				)
				(arc
					(start 8.89127 -312.712354)
					(mid 8.876391 -312.676433)
					(end 8.84047 -312.661554)
				)
				(arc
					(start 7.44093 -312.661554)
					(mid 7.405009 -312.676433)
					(end 7.39013 -312.712354)
				)
			)
		)
	)
	(zone
		(layers "In1.Cu" "In2.Cu")
		(hatch none 0.5)
		(connect_pads
			(clearance 0)
		)
		(min_thickness 0.25)
		(keepout
			(tracks not_allowed)
			(vias allowed)
			(pads allowed)
			(copperpour not_allowed)
			(footprints allowed)
		)
		(placement
			(enabled no)
			(sheetname "")
		)
		(fill yes
			(thermal_gap 0.5)
			(thermal_bridge_width 0.5)
			(island_removal_mode 0)
		)
		(polygon
			(pts
				(arc
					(start 37.56533 -280.821384)
					(mid 37.580209 -280.857305)
					(end 37.61613 -280.872184)
				)
				(arc
					(start 39.01567 -280.872184)
					(mid 39.051591 -280.857305)
					(end 39.06647 -280.821384)
				)
				(arc
					(start 39.06647 -280.412444)
					(mid 39.051591 -280.376523)
					(end 39.01567 -280.361644)
				)
				(arc
					(start 37.61613 -280.361644)
					(mid 37.580209 -280.376523)
					(end 37.56533 -280.412444)
				)
			)
		)
	)
	(zone
		(layers "In1.Cu" "In2.Cu")
		(hatch none 0.5)
		(connect_pads
			(clearance 0)
		)
		(min_thickness 0.25)
		(keepout
			(tracks not_allowed)
			(vias allowed)
			(pads allowed)
			(copperpour not_allowed)
			(footprints allowed)
		)
		(placement
			(enabled no)
			(sheetname "")
		)
		(fill yes
			(thermal_gap 0.5)
			(thermal_bridge_width 0.5)
			(island_removal_mode 0)
		)
		(polygon
			(pts
				(arc
					(start 266.974066 -223.871536)
					(mid 266.988945 -223.907457)
					(end 267.024866 -223.922336)
				)
				(arc
					(start 268.424406 -223.922336)
					(mid 268.460327 -223.907457)
					(end 268.475206 -223.871536)
				)
				(arc
					(start 268.475206 -223.462596)
					(mid 268.460327 -223.426675)
					(end 268.424406 -223.411796)
				)
				(arc
					(start 267.024866 -223.411796)
					(mid 266.988945 -223.426675)
					(end 266.974066 -223.462596)
				)
			)
		)
	)
	(zone
		(layers "In1.Cu" "In2.Cu")
		(hatch none 0.5)
		(connect_pads
			(clearance 0)
		)
		(min_thickness 0.25)
		(keepout
			(tracks not_allowed)
			(vias allowed)
			(pads allowed)
			(copperpour not_allowed)
			(footprints allowed)
		)
		(placement
			(enabled no)
			(sheetname "")
		)
		(fill yes
			(thermal_gap 0.5)
			(thermal_bridge_width 0.5)
			(island_removal_mode 0)
		)
		(polygon
			(pts
				(arc
					(start 37.56533 -288.471356)
					(mid 37.580209 -288.507277)
					(end 37.61613 -288.522156)
				)
				(arc
					(start 39.01567 -288.522156)
					(mid 39.051591 -288.507277)
					(end 39.06647 -288.471356)
				)
				(arc
					(start 39.06647 -288.062416)
					(mid 39.051591 -288.026495)
					(end 39.01567 -288.011616)
				)
				(arc
					(start 37.61613 -288.011616)
					(mid 37.580209 -288.026495)
					(end 37.56533 -288.062416)
				)
			)
		)
	)
	(zone
		(layers "In1.Cu" "In2.Cu")
		(hatch none 0.5)
		(connect_pads
			(clearance 0)
		)
		(min_thickness 0.25)
		(keepout
			(tracks not_allowed)
			(vias allowed)
			(pads allowed)
			(copperpour not_allowed)
			(footprints allowed)
		)
		(placement
			(enabled no)
			(sheetname "")
		)
		(fill yes
			(thermal_gap 0.5)
			(thermal_bridge_width 0.5)
			(island_removal_mode 0)
		)
		(polygon
			(pts
				(arc
					(start 22.47773 -259.57149)
					(mid 22.492609 -259.607411)
					(end 22.52853 -259.62229)
				)
				(arc
					(start 23.92807 -259.62229)
					(mid 23.963991 -259.607411)
					(end 23.97887 -259.57149)
				)
				(arc
					(start 23.97887 -259.16255)
					(mid 23.963991 -259.126629)
					(end 23.92807 -259.11175)
				)
				(arc
					(start 22.52853 -259.11175)
					(mid 22.492609 -259.126629)
					(end 22.47773 -259.16255)
				)
			)
		)
	)
	(zone
		(layers "In1.Cu" "In2.Cu")
		(hatch none 0.5)
		(connect_pads
			(clearance 0)
		)
		(min_thickness 0.25)
		(keepout
			(tracks not_allowed)
			(vias allowed)
			(pads allowed)
			(copperpour not_allowed)
			(footprints allowed)
		)
		(placement
			(enabled no)
			(sheetname "")
		)
		(fill yes
			(thermal_gap 0.5)
			(thermal_bridge_width 0.5)
			(island_removal_mode 0)
		)
		(polygon
			(pts
				(arc
					(start 421.090598 -245.971314)
					(mid 421.105477 -246.007235)
					(end 421.141398 -246.022114)
				)
				(arc
					(start 422.540938 -246.022114)
					(mid 422.576859 -246.007235)
					(end 422.591738 -245.971314)
				)
				(arc
					(start 422.591738 -245.562374)
					(mid 422.576859 -245.526453)
					(end 422.540938 -245.511574)
				)
				(arc
					(start 421.141398 -245.511574)
					(mid 421.105477 -245.526453)
					(end 421.090598 -245.562374)
				)
			)
		)
	)
	(zone
		(layers "In1.Cu" "In2.Cu")
		(hatch none 0.5)
		(connect_pads
			(clearance 0)
		)
		(min_thickness 0.25)
		(keepout
			(tracks not_allowed)
			(vias allowed)
			(pads allowed)
			(copperpour not_allowed)
			(footprints allowed)
		)
		(placement
			(enabled no)
			(sheetname "")
		)
		(fill yes
			(thermal_gap 0.5)
			(thermal_bridge_width 0.5)
			(island_removal_mode 0)
		)
		(polygon
			(pts
				(arc
					(start 210.86953 -224.72142)
					(mid 210.884409 -224.757341)
					(end 210.92033 -224.77222)
				)
				(arc
					(start 212.31987 -224.77222)
					(mid 212.355791 -224.757341)
					(end 212.37067 -224.72142)
				)
				(arc
					(start 212.37067 -224.31248)
					(mid 212.355791 -224.276559)
					(end 212.31987 -224.26168)
				)
				(arc
					(start 210.92033 -224.26168)
					(mid 210.884409 -224.276559)
					(end 210.86953 -224.31248)
				)
			)
		)
	)
	(zone
		(layers "In1.Cu" "In2.Cu")
		(hatch none 0.5)
		(connect_pads
			(clearance 0)
		)
		(min_thickness 0.25)
		(keepout
			(tracks not_allowed)
			(vias allowed)
			(pads allowed)
			(copperpour not_allowed)
			(footprints allowed)
		)
		(placement
			(enabled no)
			(sheetname "")
		)
		(fill yes
			(thermal_gap 0.5)
			(thermal_bridge_width 0.5)
			(island_removal_mode 0)
		)
		(polygon
			(pts
				(arc
					(start 462.909666 -245.12143)
					(mid 462.924545 -245.157351)
					(end 462.960466 -245.17223)
				)
				(arc
					(start 464.360006 -245.17223)
					(mid 464.395927 -245.157351)
					(end 464.410806 -245.12143)
				)
				(arc
					(start 464.410806 -244.71249)
					(mid 464.395927 -244.676569)
					(end 464.360006 -244.66169)
				)
				(arc
					(start 462.960466 -244.66169)
					(mid 462.924545 -244.676569)
					(end 462.909666 -244.71249)
				)
			)
		)
	)
	(zone
		(layers "In1.Cu" "In2.Cu")
		(hatch none 0.5)
		(connect_pads
			(clearance 0)
		)
		(min_thickness 0.25)
		(keepout
			(tracks not_allowed)
			(vias allowed)
			(pads allowed)
			(copperpour not_allowed)
			(footprints allowed)
		)
		(placement
			(enabled no)
			(sheetname "")
		)
		(fill yes
			(thermal_gap 0.5)
			(thermal_bridge_width 0.5)
			(island_removal_mode 0)
		)
		(polygon
			(pts
				(arc
					(start 37.56533 -218.77147)
					(mid 37.580209 -218.807391)
					(end 37.61613 -218.82227)
				)
				(arc
					(start 39.01567 -218.82227)
					(mid 39.051591 -218.807391)
					(end 39.06647 -218.77147)
				)
				(arc
					(start 39.06647 -218.36253)
					(mid 39.051591 -218.326609)
					(end 39.01567 -218.31173)
				)
				(arc
					(start 37.61613 -218.31173)
					(mid 37.580209 -218.326609)
					(end 37.56533 -218.36253)
				)
			)
		)
	)
	(zone
		(layers "In1.Cu" "In2.Cu")
		(hatch none 0.5)
		(connect_pads
			(clearance 0)
		)
		(min_thickness 0.25)
		(keepout
			(tracks not_allowed)
			(vias allowed)
			(pads allowed)
			(copperpour not_allowed)
			(footprints allowed)
		)
		(placement
			(enabled no)
			(sheetname "")
		)
		(fill yes
			(thermal_gap 0.5)
			(thermal_bridge_width 0.5)
			(island_removal_mode 0)
		)
		(polygon
			(pts
				(arc
					(start 162.162998 -222.171514)
					(mid 162.177877 -222.207435)
					(end 162.213798 -222.222314)
				)
				(arc
					(start 163.613338 -222.222314)
					(mid 163.649259 -222.207435)
					(end 163.664138 -222.171514)
				)
				(arc
					(start 163.664138 -221.762574)
					(mid 163.649259 -221.726653)
					(end 163.613338 -221.711774)
				)
				(arc
					(start 162.213798 -221.711774)
					(mid 162.177877 -221.726653)
					(end 162.162998 -221.762574)
				)
			)
		)
	)
	(zone
		(layers "In1.Cu" "In2.Cu")
		(hatch none 0.5)
		(connect_pads
			(clearance 0)
		)
		(min_thickness 0.25)
		(keepout
			(tracks not_allowed)
			(vias allowed)
			(pads allowed)
			(copperpour not_allowed)
			(footprints allowed)
		)
		(placement
			(enabled no)
			(sheetname "")
		)
		(fill yes
			(thermal_gap 0.5)
			(thermal_bridge_width 0.5)
			(island_removal_mode 0)
		)
		(polygon
			(pts
				(arc
					(start 443.721998 -297.82135)
					(mid 443.736877 -297.857271)
					(end 443.772798 -297.87215)
				)
				(arc
					(start 445.172338 -297.87215)
					(mid 445.208259 -297.857271)
					(end 445.223138 -297.82135)
				)
				(arc
					(start 445.223138 -297.41241)
					(mid 445.208259 -297.376489)
					(end 445.172338 -297.36161)
				)
				(arc
					(start 443.772798 -297.36161)
					(mid 443.736877 -297.376489)
					(end 443.721998 -297.41241)
				)
			)
		)
	)
	(zone
		(layers "In1.Cu" "In2.Cu")
		(hatch none 0.5)
		(connect_pads
			(clearance 0)
		)
		(min_thickness 0.25)
		(keepout
			(tracks not_allowed)
			(vias allowed)
			(pads allowed)
			(copperpour not_allowed)
			(footprints allowed)
		)
		(placement
			(enabled no)
			(sheetname "")
		)
		(fill yes
			(thermal_gap 0.5)
			(thermal_bridge_width 0.5)
			(island_removal_mode 0)
		)
		(polygon
			(pts
				(arc
					(start 195.78193 -245.971314)
					(mid 195.796809 -246.007235)
					(end 195.83273 -246.022114)
				)
				(arc
					(start 197.23227 -246.022114)
					(mid 197.268191 -246.007235)
					(end 197.28307 -245.971314)
				)
				(arc
					(start 197.28307 -245.562374)
					(mid 197.268191 -245.526453)
					(end 197.23227 -245.511574)
				)
				(arc
					(start 195.83273 -245.511574)
					(mid 195.796809 -245.526453)
					(end 195.78193 -245.562374)
				)
			)
		)
	)
	(zone
		(layers "In1.Cu" "In2.Cu")
		(hatch none 0.5)
		(connect_pads
			(clearance 0)
		)
		(min_thickness 0.25)
		(keepout
			(tracks not_allowed)
			(vias allowed)
			(pads allowed)
			(copperpour not_allowed)
			(footprints allowed)
		)
		(placement
			(enabled no)
			(sheetname "")
		)
		(fill yes
			(thermal_gap 0.5)
			(thermal_bridge_width 0.5)
			(island_removal_mode 0)
		)
		(polygon
			(pts
				(arc
					(start 312.236866 -223.871536)
					(mid 312.251745 -223.907457)
					(end 312.287666 -223.922336)
				)
				(arc
					(start 313.687206 -223.922336)
					(mid 313.723127 -223.907457)
					(end 313.738006 -223.871536)
				)
				(arc
					(start 313.738006 -223.462596)
					(mid 313.723127 -223.426675)
					(end 313.687206 -223.411796)
				)
				(arc
					(start 312.287666 -223.411796)
					(mid 312.251745 -223.426675)
					(end 312.236866 -223.462596)
				)
			)
		)
	)
	(zone
		(layers "In1.Cu" "In2.Cu")
		(hatch none 0.5)
		(connect_pads
			(clearance 0)
		)
		(min_thickness 0.25)
		(keepout
			(tracks not_allowed)
			(vias allowed)
			(pads allowed)
			(copperpour not_allowed)
			(footprints allowed)
		)
		(placement
			(enabled no)
			(sheetname "")
		)
		(fill yes
			(thermal_gap 0.5)
			(thermal_bridge_width 0.5)
			(island_removal_mode 0)
		)
		(polygon
			(pts
				(arc
					(start 52.65293 -305.471322)
					(mid 52.667809 -305.507243)
					(end 52.70373 -305.522122)
				)
				(arc
					(start 54.10327 -305.522122)
					(mid 54.139191 -305.507243)
					(end 54.15407 -305.471322)
				)
				(arc
					(start 54.15407 -305.062382)
					(mid 54.139191 -305.026461)
					(end 54.10327 -305.011582)
				)
				(arc
					(start 52.70373 -305.011582)
					(mid 52.667809 -305.026461)
					(end 52.65293 -305.062382)
				)
			)
		)
	)
	(zone
		(layers "In1.Cu" "In2.Cu")
		(hatch none 0.5)
		(connect_pads
			(clearance 0)
		)
		(min_thickness 0.25)
		(keepout
			(tracks not_allowed)
			(vias allowed)
			(pads allowed)
			(copperpour not_allowed)
			(footprints allowed)
		)
		(placement
			(enabled no)
			(sheetname "")
		)
		(fill yes
			(thermal_gap 0.5)
			(thermal_bridge_width 0.5)
			(island_removal_mode 0)
		)
		(polygon
			(pts
				(arc
					(start 293.049198 -284.221428)
					(mid 293.064077 -284.257349)
					(end 293.099998 -284.272228)
				)
				(arc
					(start 294.499538 -284.272228)
					(mid 294.535459 -284.257349)
					(end 294.550338 -284.221428)
				)
				(arc
					(start 294.550338 -283.812488)
					(mid 294.535459 -283.776567)
					(end 294.499538 -283.761688)
				)
				(arc
					(start 293.099998 -283.761688)
					(mid 293.064077 -283.776567)
					(end 293.049198 -283.812488)
				)
			)
		)
	)
	(zone
		(layers "In1.Cu" "In2.Cu")
		(hatch none 0.5)
		(connect_pads
			(clearance 0)
		)
		(min_thickness 0.25)
		(keepout
			(tracks not_allowed)
			(vias allowed)
			(pads allowed)
			(copperpour not_allowed)
			(footprints allowed)
		)
		(placement
			(enabled no)
			(sheetname "")
		)
		(fill yes
			(thermal_gap 0.5)
			(thermal_bridge_width 0.5)
			(island_removal_mode 0)
		)
		(polygon
			(pts
				(arc
					(start 207.425798 -240.871502)
					(mid 207.440677 -240.907423)
					(end 207.476598 -240.922302)
				)
				(arc
					(start 208.876138 -240.922302)
					(mid 208.912059 -240.907423)
					(end 208.926938 -240.871502)
				)
				(arc
					(start 208.926938 -240.462562)
					(mid 208.912059 -240.426641)
					(end 208.876138 -240.411762)
				)
				(arc
					(start 207.476598 -240.411762)
					(mid 207.440677 -240.426641)
					(end 207.425798 -240.462562)
				)
			)
		)
	)
	(zone
		(layers "In1.Cu" "In2.Cu")
		(hatch none 0.5)
		(connect_pads
			(clearance 0)
		)
		(min_thickness 0.25)
		(keepout
			(tracks not_allowed)
			(vias allowed)
			(pads allowed)
			(copperpour not_allowed)
			(footprints allowed)
		)
		(placement
			(enabled no)
			(sheetname "")
		)
		(fill yes
			(thermal_gap 0.5)
			(thermal_bridge_width 0.5)
			(island_removal_mode 0)
		)
		(polygon
			(pts
				(arc
					(start 26.577798 -296.971466)
					(mid 26.592677 -297.007387)
					(end 26.628598 -297.022266)
				)
				(arc
					(start 28.028138 -297.022266)
					(mid 28.064059 -297.007387)
					(end 28.078938 -296.971466)
				)
				(arc
					(start 28.078938 -296.562526)
					(mid 28.064059 -296.526605)
					(end 28.028138 -296.511726)
				)
				(arc
					(start 26.628598 -296.511726)
					(mid 26.592677 -296.526605)
					(end 26.577798 -296.562526)
				)
			)
		)
	)
	(zone
		(layers "In1.Cu" "In2.Cu")
		(hatch none 0.5)
		(connect_pads
			(clearance 0)
		)
		(min_thickness 0.25)
		(keepout
			(tracks not_allowed)
			(vias allowed)
			(pads allowed)
			(copperpour not_allowed)
			(footprints allowed)
		)
		(placement
			(enabled no)
			(sheetname "")
		)
		(fill yes
			(thermal_gap 0.5)
			(thermal_bridge_width 0.5)
			(island_removal_mode 0)
		)
		(polygon
			(pts
				(arc
					(start 64.296798 -240.871502)
					(mid 64.311677 -240.907423)
					(end 64.347598 -240.922302)
				)
				(arc
					(start 65.747138 -240.922302)
					(mid 65.783059 -240.907423)
					(end 65.797938 -240.871502)
				)
				(arc
					(start 65.797938 -240.462562)
					(mid 65.783059 -240.426641)
					(end 65.747138 -240.411762)
				)
				(arc
					(start 64.347598 -240.411762)
					(mid 64.311677 -240.426641)
					(end 64.296798 -240.462562)
				)
			)
		)
	)
	(zone
		(layers "In1.Cu" "In2.Cu")
		(hatch none 0.5)
		(connect_pads
			(clearance 0)
		)
		(min_thickness 0.25)
		(keepout
			(tracks not_allowed)
			(vias allowed)
			(pads allowed)
			(copperpour not_allowed)
			(footprints allowed)
		)
		(placement
			(enabled no)
			(sheetname "")
		)
		(fill yes
			(thermal_gap 0.5)
			(thermal_bridge_width 0.5)
			(island_removal_mode 0)
		)
		(polygon
			(pts
				(arc
					(start 60.19673 -200.921366)
					(mid 60.211609 -200.957287)
					(end 60.24753 -200.972166)
				)
				(arc
					(start 61.64707 -200.972166)
					(mid 61.682991 -200.957287)
					(end 61.69787 -200.921366)
				)
				(arc
					(start 61.69787 -200.512426)
					(mid 61.682991 -200.476505)
					(end 61.64707 -200.461626)
				)
				(arc
					(start 60.24753 -200.461626)
					(mid 60.211609 -200.476505)
					(end 60.19673 -200.512426)
				)
			)
		)
	)
	(zone
		(layers "In1.Cu" "In2.Cu")
		(hatch none 0.5)
		(connect_pads
			(clearance 0)
		)
		(min_thickness 0.25)
		(keepout
			(tracks not_allowed)
			(vias allowed)
			(pads allowed)
			(copperpour not_allowed)
			(footprints allowed)
		)
		(placement
			(enabled no)
			(sheetname "")
		)
		(fill yes
			(thermal_gap 0.5)
			(thermal_bridge_width 0.5)
			(island_removal_mode 0)
		)
		(polygon
			(pts
				(arc
					(start 177.250598 -287.621472)
					(mid 177.265477 -287.657393)
					(end 177.301398 -287.672272)
				)
				(arc
					(start 178.700938 -287.672272)
					(mid 178.736859 -287.657393)
					(end 178.751738 -287.621472)
				)
				(arc
					(start 178.751738 -287.212532)
					(mid 178.736859 -287.176611)
					(end 178.700938 -287.161732)
				)
				(arc
					(start 177.301398 -287.161732)
					(mid 177.265477 -287.176611)
					(end 177.250598 -287.212532)
				)
			)
		)
	)
	(zone
		(layers "In1.Cu" "In2.Cu")
		(hatch none 0.5)
		(connect_pads
			(clearance 0)
		)
		(min_thickness 0.25)
		(keepout
			(tracks not_allowed)
			(vias allowed)
			(pads allowed)
			(copperpour not_allowed)
			(footprints allowed)
		)
		(placement
			(enabled no)
			(sheetname "")
		)
		(fill yes
			(thermal_gap 0.5)
			(thermal_bridge_width 0.5)
			(island_removal_mode 0)
		)
		(polygon
			(pts
				(arc
					(start 300.592998 -288.471356)
					(mid 300.607877 -288.507277)
					(end 300.643798 -288.522156)
				)
				(arc
					(start 302.043338 -288.522156)
					(mid 302.079259 -288.507277)
					(end 302.094138 -288.471356)
				)
				(arc
					(start 302.094138 -288.062416)
					(mid 302.079259 -288.026495)
					(end 302.043338 -288.011616)
				)
				(arc
					(start 300.643798 -288.011616)
					(mid 300.607877 -288.026495)
					(end 300.592998 -288.062416)
				)
			)
		)
	)
	(zone
		(layers "In1.Cu" "In2.Cu")
		(hatch none 0.5)
		(connect_pads
			(clearance 0)
		)
		(min_thickness 0.25)
		(keepout
			(tracks not_allowed)
			(vias allowed)
			(pads allowed)
			(copperpour not_allowed)
			(footprints allowed)
		)
		(placement
			(enabled no)
			(sheetname "")
		)
		(fill yes
			(thermal_gap 0.5)
			(thermal_bridge_width 0.5)
			(island_removal_mode 0)
		)
		(polygon
			(pts
				(arc
					(start 52.65293 -238.321342)
					(mid 52.667809 -238.357263)
					(end 52.70373 -238.372142)
				)
				(arc
					(start 54.10327 -238.372142)
					(mid 54.139191 -238.357263)
					(end 54.15407 -238.321342)
				)
				(arc
					(start 54.15407 -237.912402)
					(mid 54.139191 -237.876481)
					(end 54.10327 -237.861602)
				)
				(arc
					(start 52.70373 -237.861602)
					(mid 52.667809 -237.876481)
					(end 52.65293 -237.912402)
				)
			)
		)
	)
	(zone
		(layers "In1.Cu" "In2.Cu")
		(hatch none 0.5)
		(connect_pads
			(clearance 0)
		)
		(min_thickness 0.25)
		(keepout
			(tracks not_allowed)
			(vias allowed)
			(pads allowed)
			(copperpour not_allowed)
			(footprints allowed)
		)
		(placement
			(enabled no)
			(sheetname "")
		)
		(fill yes
			(thermal_gap 0.5)
			(thermal_bridge_width 0.5)
			(island_removal_mode 0)
		)
		(polygon
			(pts
				(arc
					(start 417.646866 -231.521508)
					(mid 417.661745 -231.557429)
					(end 417.697666 -231.572308)
				)
				(arc
					(start 419.097206 -231.572308)
					(mid 419.133127 -231.557429)
					(end 419.148006 -231.521508)
				)
				(arc
					(start 419.148006 -231.112568)
					(mid 419.133127 -231.076647)
					(end 419.097206 -231.061768)
				)
				(arc
					(start 417.697666 -231.061768)
					(mid 417.661745 -231.076647)
					(end 417.646866 -231.112568)
				)
			)
		)
	)
	(zone
		(layers "In1.Cu" "In2.Cu")
		(hatch none 0.5)
		(connect_pads
			(clearance 0)
		)
		(min_thickness 0.25)
		(keepout
			(tracks not_allowed)
			(vias allowed)
			(pads allowed)
			(copperpour not_allowed)
			(footprints allowed)
		)
		(placement
			(enabled no)
			(sheetname "")
		)
		(fill yes
			(thermal_gap 0.5)
			(thermal_bridge_width 0.5)
			(island_removal_mode 0)
		)
		(polygon
			(pts
				(arc
					(start 300.592998 -200.071482)
					(mid 300.607877 -200.107403)
					(end 300.643798 -200.122282)
				)
				(arc
					(start 302.043338 -200.122282)
					(mid 302.079259 -200.107403)
					(end 302.094138 -200.071482)
				)
				(arc
					(start 302.094138 -199.662542)
					(mid 302.079259 -199.626621)
					(end 302.043338 -199.611742)
				)
				(arc
					(start 300.643798 -199.611742)
					(mid 300.607877 -199.626621)
					(end 300.592998 -199.662542)
				)
			)
		)
	)
	(zone
		(layers "In1.Cu" "In2.Cu")
		(hatch none 0.5)
		(connect_pads
			(clearance 0)
		)
		(min_thickness 0.25)
		(keepout
			(tracks not_allowed)
			(vias allowed)
			(pads allowed)
			(copperpour not_allowed)
			(footprints allowed)
		)
		(placement
			(enabled no)
			(sheetname "")
		)
		(fill yes
			(thermal_gap 0.5)
			(thermal_bridge_width 0.5)
			(island_removal_mode 0)
		)
		(polygon
			(pts
				(arc
					(start 188.23813 -262.971534)
					(mid 188.253009 -263.007455)
					(end 188.28893 -263.022334)
				)
				(arc
					(start 189.68847 -263.022334)
					(mid 189.724391 -263.007455)
					(end 189.73927 -262.971534)
				)
				(arc
					(start 189.73927 -262.562594)
					(mid 189.724391 -262.526673)
					(end 189.68847 -262.511794)
				)
				(arc
					(start 188.28893 -262.511794)
					(mid 188.253009 -262.526673)
					(end 188.23813 -262.562594)
				)
			)
		)
	)
	(zone
		(layers "In1.Cu" "In2.Cu")
		(hatch none 0.5)
		(connect_pads
			(clearance 0)
		)
		(min_thickness 0.25)
		(keepout
			(tracks not_allowed)
			(vias allowed)
			(pads allowed)
			(copperpour not_allowed)
			(footprints allowed)
		)
		(placement
			(enabled no)
			(sheetname "")
		)
		(fill yes
			(thermal_gap 0.5)
			(thermal_bridge_width 0.5)
			(island_removal_mode 0)
		)
		(polygon
			(pts
				(arc
					(start 7.39013 -218.77147)
					(mid 7.405009 -218.807391)
					(end 7.44093 -218.82227)
				)
				(arc
					(start 8.84047 -218.82227)
					(mid 8.876391 -218.807391)
					(end 8.89127 -218.77147)
				)
				(arc
					(start 8.89127 -218.36253)
					(mid 8.876391 -218.326609)
					(end 8.84047 -218.31173)
				)
				(arc
					(start 7.44093 -218.31173)
					(mid 7.405009 -218.326609)
					(end 7.39013 -218.36253)
				)
			)
		)
	)
	(zone
		(layers "In1.Cu" "In2.Cu")
		(hatch none 0.5)
		(connect_pads
			(clearance 0)
		)
		(min_thickness 0.25)
		(keepout
			(tracks not_allowed)
			(vias allowed)
			(pads allowed)
			(copperpour not_allowed)
			(footprints allowed)
		)
		(placement
			(enabled no)
			(sheetname "")
		)
		(fill yes
			(thermal_gap 0.5)
			(thermal_bridge_width 0.5)
			(island_removal_mode 0)
		)
		(polygon
			(pts
				(arc
					(start 180.69433 -308.871366)
					(mid 180.709209 -308.907287)
					(end 180.74513 -308.922166)
				)
				(arc
					(start 182.14467 -308.922166)
					(mid 182.180591 -308.907287)
					(end 182.19547 -308.871366)
				)
				(arc
					(start 182.19547 -308.462426)
					(mid 182.180591 -308.426505)
					(end 182.14467 -308.411626)
				)
				(arc
					(start 180.74513 -308.411626)
					(mid 180.709209 -308.426505)
					(end 180.69433 -308.462426)
				)
			)
		)
	)
	(zone
		(layers "In1.Cu" "In2.Cu")
		(hatch none 0.5)
		(connect_pads
			(clearance 0)
		)
		(min_thickness 0.25)
		(keepout
			(tracks not_allowed)
			(vias allowed)
			(pads allowed)
			(copperpour not_allowed)
			(footprints allowed)
		)
		(placement
			(enabled no)
			(sheetname "")
		)
		(fill yes
			(thermal_gap 0.5)
			(thermal_bridge_width 0.5)
			(island_removal_mode 0)
		)
		(polygon
			(pts
				(arc
					(start 259.430266 -228.121464)
					(mid 259.445145 -228.157385)
					(end 259.481066 -228.172264)
				)
				(arc
					(start 260.880606 -228.172264)
					(mid 260.916527 -228.157385)
					(end 260.931406 -228.121464)
				)
				(arc
					(start 260.931406 -227.712524)
					(mid 260.916527 -227.676603)
					(end 260.880606 -227.661724)
				)
				(arc
					(start 259.481066 -227.661724)
					(mid 259.445145 -227.676603)
					(end 259.430266 -227.712524)
				)
			)
		)
	)
	(zone
		(layers "In1.Cu" "In2.Cu")
		(hatch none 0.5)
		(connect_pads
			(clearance 0)
		)
		(min_thickness 0.25)
		(keepout
			(tracks not_allowed)
			(vias allowed)
			(pads allowed)
			(copperpour not_allowed)
			(footprints allowed)
		)
		(placement
			(enabled no)
			(sheetname "")
		)
		(fill yes
			(thermal_gap 0.5)
			(thermal_bridge_width 0.5)
			(island_removal_mode 0)
		)
		(polygon
			(pts
				(arc
					(start 26.577798 -274.871434)
					(mid 26.592677 -274.907355)
					(end 26.628598 -274.922234)
				)
				(arc
					(start 28.028138 -274.922234)
					(mid 28.064059 -274.907355)
					(end 28.078938 -274.871434)
				)
				(arc
					(start 28.078938 -274.462494)
					(mid 28.064059 -274.426573)
					(end 28.028138 -274.411694)
				)
				(arc
					(start 26.628598 -274.411694)
					(mid 26.592677 -274.426573)
					(end 26.577798 -274.462494)
				)
			)
		)
	)
	(zone
		(layers "In1.Cu" "In2.Cu")
		(hatch none 0.5)
		(connect_pads
			(clearance 0)
		)
		(min_thickness 0.25)
		(keepout
			(tracks not_allowed)
			(vias allowed)
			(pads allowed)
			(copperpour not_allowed)
			(footprints allowed)
		)
		(placement
			(enabled no)
			(sheetname "")
		)
		(fill yes
			(thermal_gap 0.5)
			(thermal_bridge_width 0.5)
			(island_removal_mode 0)
		)
		(polygon
			(pts
				(arc
					(start 428.634398 -237.471458)
					(mid 428.649277 -237.507379)
					(end 428.685198 -237.522258)
				)
				(arc
					(start 430.084738 -237.522258)
					(mid 430.120659 -237.507379)
					(end 430.135538 -237.471458)
				)
				(arc
					(start 430.135538 -237.062518)
					(mid 430.120659 -237.026597)
					(end 430.084738 -237.011718)
				)
				(arc
					(start 428.685198 -237.011718)
					(mid 428.649277 -237.026597)
					(end 428.634398 -237.062518)
				)
			)
		)
	)
	(zone
		(layers "In1.Cu" "In2.Cu")
		(hatch none 0.5)
		(connect_pads
			(clearance 0)
		)
		(min_thickness 0.25)
		(keepout
			(tracks not_allowed)
			(vias allowed)
			(pads allowed)
			(copperpour not_allowed)
			(footprints allowed)
		)
		(placement
			(enabled no)
			(sheetname "")
		)
		(fill yes
			(thermal_gap 0.5)
			(thermal_bridge_width 0.5)
			(island_removal_mode 0)
		)
		(polygon
			(pts
				(arc
					(start 451.265798 -301.221394)
					(mid 451.280677 -301.257315)
					(end 451.316598 -301.272194)
				)
				(arc
					(start 452.716138 -301.272194)
					(mid 452.752059 -301.257315)
					(end 452.766938 -301.221394)
				)
				(arc
					(start 452.766938 -300.812454)
					(mid 452.752059 -300.776533)
					(end 452.716138 -300.761654)
				)
				(arc
					(start 451.316598 -300.761654)
					(mid 451.280677 -300.776533)
					(end 451.265798 -300.812454)
				)
			)
		)
	)
	(zone
		(layers "In1.Cu" "In2.Cu")
		(hatch none 0.5)
		(connect_pads
			(clearance 0)
		)
		(min_thickness 0.25)
		(keepout
			(tracks not_allowed)
			(vias allowed)
			(pads allowed)
			(copperpour not_allowed)
			(footprints allowed)
		)
		(placement
			(enabled no)
			(sheetname "")
		)
		(fill yes
			(thermal_gap 0.5)
			(thermal_bridge_width 0.5)
			(island_removal_mode 0)
		)
		(polygon
			(pts
				(arc
					(start 30.02153 -273.171412)
					(mid 30.036409 -273.207333)
					(end 30.07233 -273.222212)
				)
				(arc
					(start 31.47187 -273.222212)
					(mid 31.507791 -273.207333)
					(end 31.52267 -273.171412)
				)
				(arc
					(start 31.52267 -272.762472)
					(mid 31.507791 -272.726551)
					(end 31.47187 -272.711672)
				)
				(arc
					(start 30.07233 -272.711672)
					(mid 30.036409 -272.726551)
					(end 30.02153 -272.762472)
				)
			)
		)
	)
	(zone
		(layers "In1.Cu" "In2.Cu")
		(hatch none 0.5)
		(connect_pads
			(clearance 0)
		)
		(min_thickness 0.25)
		(keepout
			(tracks not_allowed)
			(vias allowed)
			(pads allowed)
			(copperpour not_allowed)
			(footprints allowed)
		)
		(placement
			(enabled no)
			(sheetname "")
		)
		(fill yes
			(thermal_gap 0.5)
			(thermal_bridge_width 0.5)
			(island_removal_mode 0)
		)
		(polygon
			(pts
				(arc
					(start 289.605466 -296.971466)
					(mid 289.620345 -297.007387)
					(end 289.656266 -297.022266)
				)
				(arc
					(start 291.055806 -297.022266)
					(mid 291.091727 -297.007387)
					(end 291.106606 -296.971466)
				)
				(arc
					(start 291.106606 -296.562526)
					(mid 291.091727 -296.526605)
					(end 291.055806 -296.511726)
				)
				(arc
					(start 289.656266 -296.511726)
					(mid 289.620345 -296.526605)
					(end 289.605466 -296.562526)
				)
			)
		)
	)
	(zone
		(layers "In1.Cu" "In2.Cu")
		(hatch none 0.5)
		(connect_pads
			(clearance 0)
		)
		(min_thickness 0.25)
		(keepout
			(tracks not_allowed)
			(vias allowed)
			(pads allowed)
			(copperpour not_allowed)
			(footprints allowed)
		)
		(placement
			(enabled no)
			(sheetname "")
		)
		(fill yes
			(thermal_gap 0.5)
			(thermal_bridge_width 0.5)
			(island_removal_mode 0)
		)
		(polygon
			(pts
				(arc
					(start 203.32573 -240.021364)
					(mid 203.340609 -240.057285)
					(end 203.37653 -240.072164)
				)
				(arc
					(start 204.77607 -240.072164)
					(mid 204.811991 -240.057285)
					(end 204.82687 -240.021364)
				)
				(arc
					(start 204.82687 -239.612424)
					(mid 204.811991 -239.576503)
					(end 204.77607 -239.561624)
				)
				(arc
					(start 203.37653 -239.561624)
					(mid 203.340609 -239.576503)
					(end 203.32573 -239.612424)
				)
			)
		)
	)
	(zone
		(layers "In1.Cu" "In2.Cu")
		(hatch none 0.5)
		(connect_pads
			(clearance 0)
		)
		(min_thickness 0.25)
		(keepout
			(tracks not_allowed)
			(vias allowed)
			(pads allowed)
			(copperpour not_allowed)
			(footprints allowed)
		)
		(placement
			(enabled no)
			(sheetname "")
		)
		(fill yes
			(thermal_gap 0.5)
			(thermal_bridge_width 0.5)
			(island_removal_mode 0)
		)
		(polygon
			(pts
				(arc
					(start 34.121598 -274.871434)
					(mid 34.136477 -274.907355)
					(end 34.172398 -274.922234)
				)
				(arc
					(start 35.571938 -274.922234)
					(mid 35.607859 -274.907355)
					(end 35.622738 -274.871434)
				)
				(arc
					(start 35.622738 -274.462494)
					(mid 35.607859 -274.426573)
					(end 35.571938 -274.411694)
				)
				(arc
					(start 34.172398 -274.411694)
					(mid 34.136477 -274.426573)
					(end 34.121598 -274.462494)
				)
			)
		)
	)
	(zone
		(layers "In1.Cu" "In2.Cu")
		(hatch none 0.5)
		(connect_pads
			(clearance 0)
		)
		(min_thickness 0.25)
		(keepout
			(tracks not_allowed)
			(vias allowed)
			(pads allowed)
			(copperpour not_allowed)
			(footprints allowed)
		)
		(placement
			(enabled no)
			(sheetname "")
		)
		(fill yes
			(thermal_gap 0.5)
			(thermal_bridge_width 0.5)
			(island_removal_mode 0)
		)
		(polygon
			(pts
				(arc
					(start 49.209198 -214.521542)
					(mid 49.224077 -214.557463)
					(end 49.259998 -214.572342)
				)
				(arc
					(start 50.659538 -214.572342)
					(mid 50.695459 -214.557463)
					(end 50.710338 -214.521542)
				)
				(arc
					(start 50.710338 -214.112602)
					(mid 50.695459 -214.076681)
					(end 50.659538 -214.061802)
				)
				(arc
					(start 49.259998 -214.061802)
					(mid 49.224077 -214.076681)
					(end 49.209198 -214.112602)
				)
			)
		)
	)
	(zone
		(layers "In1.Cu" "In2.Cu")
		(hatch none 0.5)
		(connect_pads
			(clearance 0)
		)
		(min_thickness 0.25)
		(keepout
			(tracks not_allowed)
			(vias allowed)
			(pads allowed)
			(copperpour not_allowed)
			(footprints allowed)
		)
		(placement
			(enabled no)
			(sheetname "")
		)
		(fill yes
			(thermal_gap 0.5)
			(thermal_bridge_width 0.5)
			(island_removal_mode 0)
		)
		(polygon
			(pts
				(arc
					(start 180.69433 -288.471356)
					(mid 180.709209 -288.507277)
					(end 180.74513 -288.522156)
				)
				(arc
					(start 182.14467 -288.522156)
					(mid 182.180591 -288.507277)
					(end 182.19547 -288.471356)
				)
				(arc
					(start 182.19547 -288.062416)
					(mid 182.180591 -288.026495)
					(end 182.14467 -288.011616)
				)
				(arc
					(start 180.74513 -288.011616)
					(mid 180.709209 -288.026495)
					(end 180.69433 -288.062416)
				)
			)
		)
	)
	(zone
		(layers "In1.Cu" "In2.Cu")
		(hatch none 0.5)
		(connect_pads
			(clearance 0)
		)
		(min_thickness 0.25)
		(keepout
			(tracks not_allowed)
			(vias allowed)
			(pads allowed)
			(copperpour not_allowed)
			(footprints allowed)
		)
		(placement
			(enabled no)
			(sheetname "")
		)
		(fill yes
			(thermal_gap 0.5)
			(thermal_bridge_width 0.5)
			(island_removal_mode 0)
		)
		(polygon
			(pts
				(arc
					(start 458.809598 -221.321376)
					(mid 458.824477 -221.357297)
					(end 458.860398 -221.372176)
				)
				(arc
					(start 460.259938 -221.372176)
					(mid 460.295859 -221.357297)
					(end 460.310738 -221.321376)
				)
				(arc
					(start 460.310738 -220.912436)
					(mid 460.295859 -220.876515)
					(end 460.259938 -220.861636)
				)
				(arc
					(start 458.860398 -220.861636)
					(mid 458.824477 -220.876515)
					(end 458.809598 -220.912436)
				)
			)
		)
	)
	(zone
		(layers "In1.Cu" "In2.Cu")
		(hatch none 0.5)
		(connect_pads
			(clearance 0)
		)
		(min_thickness 0.25)
		(keepout
			(tracks not_allowed)
			(vias allowed)
			(pads allowed)
			(copperpour not_allowed)
			(footprints allowed)
		)
		(placement
			(enabled no)
			(sheetname "")
		)
		(fill yes
			(thermal_gap 0.5)
			(thermal_bridge_width 0.5)
			(island_removal_mode 0)
		)
		(polygon
			(pts
				(arc
					(start 421.090598 -282.521406)
					(mid 421.105477 -282.557327)
					(end 421.141398 -282.572206)
				)
				(arc
					(start 422.540938 -282.572206)
					(mid 422.576859 -282.557327)
					(end 422.591738 -282.521406)
				)
				(arc
					(start 422.591738 -282.112466)
					(mid 422.576859 -282.076545)
					(end 422.540938 -282.061666)
				)
				(arc
					(start 421.141398 -282.061666)
					(mid 421.105477 -282.076545)
					(end 421.090598 -282.112466)
				)
			)
		)
	)
	(zone
		(layers "In1.Cu" "In2.Cu")
		(hatch none 0.5)
		(connect_pads
			(clearance 0)
		)
		(min_thickness 0.25)
		(keepout
			(tracks not_allowed)
			(vias allowed)
			(pads allowed)
			(copperpour not_allowed)
			(footprints allowed)
		)
		(placement
			(enabled no)
			(sheetname "")
		)
		(fill yes
			(thermal_gap 0.5)
			(thermal_bridge_width 0.5)
			(island_removal_mode 0)
		)
		(polygon
			(pts
				(arc
					(start 417.646866 -212.82152)
					(mid 417.661745 -212.857441)
					(end 417.697666 -212.87232)
				)
				(arc
					(start 419.097206 -212.87232)
					(mid 419.133127 -212.857441)
					(end 419.148006 -212.82152)
				)
				(arc
					(start 419.148006 -212.41258)
					(mid 419.133127 -212.376659)
					(end 419.097206 -212.36178)
				)
				(arc
					(start 417.697666 -212.36178)
					(mid 417.661745 -212.376659)
					(end 417.646866 -212.41258)
				)
			)
		)
	)
	(zone
		(layers "In1.Cu" "In2.Cu")
		(hatch none 0.5)
		(connect_pads
			(clearance 0)
		)
		(min_thickness 0.25)
		(keepout
			(tracks not_allowed)
			(vias allowed)
			(pads allowed)
			(copperpour not_allowed)
			(footprints allowed)
		)
		(placement
			(enabled no)
			(sheetname "")
		)
		(fill yes
			(thermal_gap 0.5)
			(thermal_bridge_width 0.5)
			(island_removal_mode 0)
		)
		(polygon
			(pts
				(arc
					(start 447.822066 -231.521508)
					(mid 447.836945 -231.557429)
					(end 447.872866 -231.572308)
				)
				(arc
					(start 449.272406 -231.572308)
					(mid 449.308327 -231.557429)
					(end 449.323206 -231.521508)
				)
				(arc
					(start 449.323206 -231.112568)
					(mid 449.308327 -231.076647)
					(end 449.272406 -231.061768)
				)
				(arc
					(start 447.872866 -231.061768)
					(mid 447.836945 -231.076647)
					(end 447.822066 -231.112568)
				)
			)
		)
	)
	(zone
		(layers "In1.Cu" "In2.Cu")
		(hatch none 0.5)
		(connect_pads
			(clearance 0)
		)
		(min_thickness 0.25)
		(keepout
			(tracks not_allowed)
			(vias allowed)
			(pads allowed)
			(copperpour not_allowed)
			(footprints allowed)
		)
		(placement
			(enabled no)
			(sheetname "")
		)
		(fill yes
			(thermal_gap 0.5)
			(thermal_bridge_width 0.5)
			(island_removal_mode 0)
		)
		(polygon
			(pts
				(arc
					(start 199.881998 -312.27141)
					(mid 199.896877 -312.307331)
					(end 199.932798 -312.32221)
				)
				(arc
					(start 201.332338 -312.32221)
					(mid 201.368259 -312.307331)
					(end 201.383138 -312.27141)
				)
				(arc
					(start 201.383138 -311.86247)
					(mid 201.368259 -311.826549)
					(end 201.332338 -311.81167)
				)
				(arc
					(start 199.932798 -311.81167)
					(mid 199.896877 -311.826549)
					(end 199.881998 -311.86247)
				)
			)
		)
	)
	(zone
		(layers "In1.Cu" "In2.Cu")
		(hatch none 0.5)
		(connect_pads
			(clearance 0)
		)
		(min_thickness 0.25)
		(keepout
			(tracks not_allowed)
			(vias allowed)
			(pads allowed)
			(copperpour not_allowed)
			(footprints allowed)
		)
		(placement
			(enabled no)
			(sheetname "")
		)
		(fill yes
			(thermal_gap 0.5)
			(thermal_bridge_width 0.5)
			(island_removal_mode 0)
		)
		(polygon
			(pts
				(arc
					(start 184.794398 -240.871502)
					(mid 184.809277 -240.907423)
					(end 184.845198 -240.922302)
				)
				(arc
					(start 186.244738 -240.922302)
					(mid 186.280659 -240.907423)
					(end 186.295538 -240.871502)
				)
				(arc
					(start 186.295538 -240.462562)
					(mid 186.280659 -240.426641)
					(end 186.244738 -240.411762)
				)
				(arc
					(start 184.845198 -240.411762)
					(mid 184.809277 -240.426641)
					(end 184.794398 -240.462562)
				)
			)
		)
	)
	(zone
		(layers "In1.Cu" "In2.Cu")
		(hatch none 0.5)
		(connect_pads
			(clearance 0)
		)
		(min_thickness 0.25)
		(keepout
			(tracks not_allowed)
			(vias allowed)
			(pads allowed)
			(copperpour not_allowed)
			(footprints allowed)
		)
		(placement
			(enabled no)
			(sheetname "")
		)
		(fill yes
			(thermal_gap 0.5)
			(thermal_bridge_width 0.5)
			(island_removal_mode 0)
		)
		(polygon
			(pts
				(arc
					(start 45.10913 -303.7713)
					(mid 45.124009 -303.807221)
					(end 45.15993 -303.8221)
				)
				(arc
					(start 46.55947 -303.8221)
					(mid 46.595391 -303.807221)
					(end 46.61027 -303.7713)
				)
				(arc
					(start 46.61027 -303.36236)
					(mid 46.595391 -303.326439)
					(end 46.55947 -303.31156)
				)
				(arc
					(start 45.15993 -303.31156)
					(mid 45.124009 -303.326439)
					(end 45.10913 -303.36236)
				)
			)
		)
	)
	(zone
		(layers "In1.Cu" "In2.Cu")
		(hatch none 0.5)
		(connect_pads
			(clearance 0)
		)
		(min_thickness 0.25)
		(keepout
			(tracks not_allowed)
			(vias allowed)
			(pads allowed)
			(copperpour not_allowed)
			(footprints allowed)
		)
		(placement
			(enabled no)
			(sheetname "")
		)
		(fill yes
			(thermal_gap 0.5)
			(thermal_bridge_width 0.5)
			(island_removal_mode 0)
		)
		(polygon
			(pts
				(arc
					(start 282.061666 -293.571422)
					(mid 282.076545 -293.607343)
					(end 282.112466 -293.622222)
				)
				(arc
					(start 283.512006 -293.622222)
					(mid 283.547927 -293.607343)
					(end 283.562806 -293.571422)
				)
				(arc
					(start 283.562806 -293.162482)
					(mid 283.547927 -293.126561)
					(end 283.512006 -293.111682)
				)
				(arc
					(start 282.112466 -293.111682)
					(mid 282.076545 -293.126561)
					(end 282.061666 -293.162482)
				)
			)
		)
	)
	(zone
		(layers "In1.Cu" "In2.Cu")
		(hatch none 0.5)
		(connect_pads
			(clearance 0)
		)
		(min_thickness 0.25)
		(keepout
			(tracks not_allowed)
			(vias allowed)
			(pads allowed)
			(copperpour not_allowed)
			(footprints allowed)
		)
		(placement
			(enabled no)
			(sheetname "")
		)
		(fill yes
			(thermal_gap 0.5)
			(thermal_bridge_width 0.5)
			(island_removal_mode 0)
		)
		(polygon
			(pts
				(arc
					(start 11.490198 -211.121498)
					(mid 11.505077 -211.157419)
					(end 11.540998 -211.172298)
				)
				(arc
					(start 12.940538 -211.172298)
					(mid 12.976459 -211.157419)
					(end 12.991338 -211.121498)
				)
				(arc
					(start 12.991338 -210.712558)
					(mid 12.976459 -210.676637)
					(end 12.940538 -210.661758)
				)
				(arc
					(start 11.540998 -210.661758)
					(mid 11.505077 -210.676637)
					(end 11.490198 -210.712558)
				)
			)
		)
	)
	(zone
		(layers "In1.Cu" "In2.Cu")
		(hatch none 0.5)
		(connect_pads
			(clearance 0)
		)
		(min_thickness 0.25)
		(keepout
			(tracks not_allowed)
			(vias allowed)
			(pads allowed)
			(copperpour not_allowed)
			(footprints allowed)
		)
		(placement
			(enabled no)
			(sheetname "")
		)
		(fill yes
			(thermal_gap 0.5)
			(thermal_bridge_width 0.5)
			(island_removal_mode 0)
		)
		(polygon
			(pts
				(arc
					(start 207.425798 -216.22131)
					(mid 207.440677 -216.257231)
					(end 207.476598 -216.27211)
				)
				(arc
					(start 208.876138 -216.27211)
					(mid 208.912059 -216.257231)
					(end 208.926938 -216.22131)
				)
				(arc
					(start 208.926938 -215.81237)
					(mid 208.912059 -215.776449)
					(end 208.876138 -215.76157)
				)
				(arc
					(start 207.476598 -215.76157)
					(mid 207.440677 -215.776449)
					(end 207.425798 -215.81237)
				)
			)
		)
	)
	(zone
		(layers "In1.Cu" "In2.Cu")
		(hatch none 0.5)
		(connect_pads
			(clearance 0)
		)
		(min_thickness 0.25)
		(keepout
			(tracks not_allowed)
			(vias allowed)
			(pads allowed)
			(copperpour not_allowed)
			(footprints allowed)
		)
		(placement
			(enabled no)
			(sheetname "")
		)
		(fill yes
			(thermal_gap 0.5)
			(thermal_bridge_width 0.5)
			(island_removal_mode 0)
		)
		(polygon
			(pts
				(arc
					(start 458.809598 -294.421306)
					(mid 458.824477 -294.457227)
					(end 458.860398 -294.472106)
				)
				(arc
					(start 460.259938 -294.472106)
					(mid 460.295859 -294.457227)
					(end 460.310738 -294.421306)
				)
				(arc
					(start 460.310738 -294.012366)
					(mid 460.295859 -293.976445)
					(end 460.259938 -293.961566)
				)
				(arc
					(start 458.860398 -293.961566)
					(mid 458.824477 -293.976445)
					(end 458.809598 -294.012366)
				)
			)
		)
	)
	(zone
		(layers "In1.Cu" "In2.Cu")
		(hatch none 0.5)
		(connect_pads
			(clearance 0)
		)
		(min_thickness 0.25)
		(keepout
			(tracks not_allowed)
			(vias allowed)
			(pads allowed)
			(copperpour not_allowed)
			(footprints allowed)
		)
		(placement
			(enabled no)
			(sheetname "")
		)
		(fill yes
			(thermal_gap 0.5)
			(thermal_bridge_width 0.5)
			(island_removal_mode 0)
		)
		(polygon
			(pts
				(arc
					(start 199.881998 -228.121464)
					(mid 199.896877 -228.157385)
					(end 199.932798 -228.172264)
				)
				(arc
					(start 201.332338 -228.172264)
					(mid 201.368259 -228.157385)
					(end 201.383138 -228.121464)
				)
				(arc
					(start 201.383138 -227.712524)
					(mid 201.368259 -227.676603)
					(end 201.332338 -227.661724)
				)
				(arc
					(start 199.932798 -227.661724)
					(mid 199.896877 -227.676603)
					(end 199.881998 -227.712524)
				)
			)
		)
	)
	(zone
		(layers "In1.Cu" "In2.Cu")
		(hatch none 0.5)
		(connect_pads
			(clearance 0)
		)
		(min_thickness 0.25)
		(keepout
			(tracks not_allowed)
			(vias allowed)
			(pads allowed)
			(copperpour not_allowed)
			(footprints allowed)
		)
		(placement
			(enabled no)
			(sheetname "")
		)
		(fill yes
			(thermal_gap 0.5)
			(thermal_bridge_width 0.5)
			(island_removal_mode 0)
		)
		(polygon
			(pts
				(arc
					(start 158.06293 -224.72142)
					(mid 158.077809 -224.757341)
					(end 158.11373 -224.77222)
				)
				(arc
					(start 159.51327 -224.77222)
					(mid 159.549191 -224.757341)
					(end 159.56407 -224.72142)
				)
				(arc
					(start 159.56407 -224.31248)
					(mid 159.549191 -224.276559)
					(end 159.51327 -224.26168)
				)
				(arc
					(start 158.11373 -224.26168)
					(mid 158.077809 -224.276559)
					(end 158.06293 -224.31248)
				)
			)
		)
	)
	(zone
		(layers "In1.Cu" "In2.Cu")
		(hatch none 0.5)
		(connect_pads
			(clearance 0)
		)
		(min_thickness 0.25)
		(keepout
			(tracks not_allowed)
			(vias allowed)
			(pads allowed)
			(copperpour not_allowed)
			(footprints allowed)
		)
		(placement
			(enabled no)
			(sheetname "")
		)
		(fill yes
			(thermal_gap 0.5)
			(thermal_bridge_width 0.5)
			(island_removal_mode 0)
		)
		(polygon
			(pts
				(arc
					(start 410.103066 -250.221496)
					(mid 410.117945 -250.257417)
					(end 410.153866 -250.272296)
				)
				(arc
					(start 411.553406 -250.272296)
					(mid 411.589327 -250.257417)
					(end 411.604206 -250.221496)
				)
				(arc
					(start 411.604206 -249.812556)
					(mid 411.589327 -249.776635)
					(end 411.553406 -249.761756)
				)
				(arc
					(start 410.153866 -249.761756)
					(mid 410.117945 -249.776635)
					(end 410.103066 -249.812556)
				)
			)
		)
	)
	(zone
		(layers "In1.Cu" "In2.Cu")
		(hatch none 0.5)
		(connect_pads
			(clearance 0)
		)
		(min_thickness 0.25)
		(keepout
			(tracks not_allowed)
			(vias allowed)
			(pads allowed)
			(copperpour not_allowed)
			(footprints allowed)
		)
		(placement
			(enabled no)
			(sheetname "")
		)
		(fill yes
			(thermal_gap 0.5)
			(thermal_bridge_width 0.5)
			(island_removal_mode 0)
		)
		(polygon
			(pts
				(arc
					(start 266.974066 -276.571456)
					(mid 266.988945 -276.607377)
					(end 267.024866 -276.622256)
				)
				(arc
					(start 268.424406 -276.622256)
					(mid 268.460327 -276.607377)
					(end 268.475206 -276.571456)
				)
				(arc
					(start 268.475206 -276.162516)
					(mid 268.460327 -276.126595)
					(end 268.424406 -276.111716)
				)
				(arc
					(start 267.024866 -276.111716)
					(mid 266.988945 -276.126595)
					(end 266.974066 -276.162516)
				)
			)
		)
	)
	(zone
		(layers "In1.Cu" "In2.Cu")
		(hatch none 0.5)
		(connect_pads
			(clearance 0)
		)
		(min_thickness 0.25)
		(keepout
			(tracks not_allowed)
			(vias allowed)
			(pads allowed)
			(copperpour not_allowed)
			(footprints allowed)
		)
		(placement
			(enabled no)
			(sheetname "")
		)
		(fill yes
			(thermal_gap 0.5)
			(thermal_bridge_width 0.5)
			(island_removal_mode 0)
		)
		(polygon
			(pts
				(arc
					(start 458.809598 -285.071312)
					(mid 458.824477 -285.107233)
					(end 458.860398 -285.122112)
				)
				(arc
					(start 460.259938 -285.122112)
					(mid 460.295859 -285.107233)
					(end 460.310738 -285.071312)
				)
				(arc
					(start 460.310738 -284.662372)
					(mid 460.295859 -284.626451)
					(end 460.259938 -284.611572)
				)
				(arc
					(start 458.860398 -284.611572)
					(mid 458.824477 -284.626451)
					(end 458.809598 -284.662372)
				)
			)
		)
	)
	(zone
		(layers "In1.Cu" "In2.Cu")
		(hatch none 0.5)
		(connect_pads
			(clearance 0)
		)
		(min_thickness 0.25)
		(keepout
			(tracks not_allowed)
			(vias allowed)
			(pads allowed)
			(copperpour not_allowed)
			(footprints allowed)
		)
		(placement
			(enabled no)
			(sheetname "")
		)
		(fill yes
			(thermal_gap 0.5)
			(thermal_bridge_width 0.5)
			(island_removal_mode 0)
		)
		(polygon
			(pts
				(arc
					(start 297.149266 -262.121396)
					(mid 297.164145 -262.157317)
					(end 297.200066 -262.172196)
				)
				(arc
					(start 298.599606 -262.172196)
					(mid 298.635527 -262.157317)
					(end 298.650406 -262.121396)
				)
				(arc
					(start 298.650406 -261.712456)
					(mid 298.635527 -261.676535)
					(end 298.599606 -261.661656)
				)
				(arc
					(start 297.200066 -261.661656)
					(mid 297.164145 -261.676535)
					(end 297.149266 -261.712456)
				)
			)
		)
	)
	(zone
		(layers "In1.Cu" "In2.Cu")
		(hatch none 0.5)
		(connect_pads
			(clearance 0)
		)
		(min_thickness 0.25)
		(keepout
			(tracks not_allowed)
			(vias allowed)
			(pads allowed)
			(copperpour not_allowed)
			(footprints allowed)
		)
		(placement
			(enabled no)
			(sheetname "")
		)
		(fill yes
			(thermal_gap 0.5)
			(thermal_bridge_width 0.5)
			(island_removal_mode 0)
		)
		(polygon
			(pts
				(arc
					(start 462.909666 -289.321494)
					(mid 462.924545 -289.357415)
					(end 462.960466 -289.372294)
				)
				(arc
					(start 464.360006 -289.372294)
					(mid 464.395927 -289.357415)
					(end 464.410806 -289.321494)
				)
				(arc
					(start 464.410806 -288.912554)
					(mid 464.395927 -288.876633)
					(end 464.360006 -288.861754)
				)
				(arc
					(start 462.960466 -288.861754)
					(mid 462.924545 -288.876633)
					(end 462.909666 -288.912554)
				)
			)
		)
	)
	(zone
		(layers "In1.Cu" "In2.Cu")
		(hatch none 0.5)
		(connect_pads
			(clearance 0)
		)
		(min_thickness 0.25)
		(keepout
			(tracks not_allowed)
			(vias allowed)
			(pads allowed)
			(copperpour not_allowed)
			(footprints allowed)
		)
		(placement
			(enabled no)
			(sheetname "")
		)
		(fill yes
			(thermal_gap 0.5)
			(thermal_bridge_width 0.5)
			(island_removal_mode 0)
		)
		(polygon
			(pts
				(arc
					(start 210.86953 -314.821316)
					(mid 210.884409 -314.857237)
					(end 210.92033 -314.872116)
				)
				(arc
					(start 212.31987 -314.872116)
					(mid 212.355791 -314.857237)
					(end 212.37067 -314.821316)
				)
				(arc
					(start 212.37067 -314.412376)
					(mid 212.355791 -314.376455)
					(end 212.31987 -314.361576)
				)
				(arc
					(start 210.92033 -314.361576)
					(mid 210.884409 -314.376455)
					(end 210.86953 -314.412376)
				)
			)
		)
	)
	(zone
		(layers "In1.Cu" "In2.Cu")
		(hatch none 0.5)
		(connect_pads
			(clearance 0)
		)
		(min_thickness 0.25)
		(keepout
			(tracks not_allowed)
			(vias allowed)
			(pads allowed)
			(copperpour not_allowed)
			(footprints allowed)
		)
		(placement
			(enabled no)
			(sheetname "")
		)
		(fill yes
			(thermal_gap 0.5)
			(thermal_bridge_width 0.5)
			(island_removal_mode 0)
		)
		(polygon
			(pts
				(arc
					(start 34.121598 -225.571304)
					(mid 34.136477 -225.607225)
					(end 34.172398 -225.622104)
				)
				(arc
					(start 35.571938 -225.622104)
					(mid 35.607859 -225.607225)
					(end 35.622738 -225.571304)
				)
				(arc
					(start 35.622738 -225.162364)
					(mid 35.607859 -225.126443)
					(end 35.571938 -225.111564)
				)
				(arc
					(start 34.172398 -225.111564)
					(mid 34.136477 -225.126443)
					(end 34.121598 -225.162364)
				)
			)
		)
	)
	(zone
		(layers "In1.Cu" "In2.Cu")
		(hatch none 0.5)
		(connect_pads
			(clearance 0)
		)
		(min_thickness 0.25)
		(keepout
			(tracks not_allowed)
			(vias allowed)
			(pads allowed)
			(copperpour not_allowed)
			(footprints allowed)
		)
		(placement
			(enabled no)
			(sheetname "")
		)
		(fill yes
			(thermal_gap 0.5)
			(thermal_bridge_width 0.5)
			(island_removal_mode 0)
		)
		(polygon
			(pts
				(arc
					(start 304.693066 -212.82152)
					(mid 304.707945 -212.857441)
					(end 304.743866 -212.87232)
				)
				(arc
					(start 306.143406 -212.87232)
					(mid 306.179327 -212.857441)
					(end 306.194206 -212.82152)
				)
				(arc
					(start 306.194206 -212.41258)
					(mid 306.179327 -212.376659)
					(end 306.143406 -212.36178)
				)
				(arc
					(start 304.743866 -212.36178)
					(mid 304.707945 -212.376659)
					(end 304.693066 -212.41258)
				)
			)
		)
	)
	(zone
		(layers "In1.Cu" "In2.Cu")
		(hatch none 0.5)
		(connect_pads
			(clearance 0)
		)
		(min_thickness 0.25)
		(keepout
			(tracks not_allowed)
			(vias allowed)
			(pads allowed)
			(copperpour not_allowed)
			(footprints allowed)
		)
		(placement
			(enabled no)
			(sheetname "")
		)
		(fill yes
			(thermal_gap 0.5)
			(thermal_bridge_width 0.5)
			(island_removal_mode 0)
		)
		(polygon
			(pts
				(arc
					(start 421.090598 -316.521338)
					(mid 421.105477 -316.557259)
					(end 421.141398 -316.572138)
				)
				(arc
					(start 422.540938 -316.572138)
					(mid 422.576859 -316.557259)
					(end 422.591738 -316.521338)
				)
				(arc
					(start 422.591738 -316.112398)
					(mid 422.576859 -316.076477)
					(end 422.540938 -316.061598)
				)
				(arc
					(start 421.141398 -316.061598)
					(mid 421.105477 -316.076477)
					(end 421.090598 -316.112398)
				)
			)
		)
	)
	(zone
		(layers "In1.Cu" "In2.Cu")
		(hatch none 0.5)
		(connect_pads
			(clearance 0)
		)
		(min_thickness 0.25)
		(keepout
			(tracks not_allowed)
			(vias allowed)
			(pads allowed)
			(copperpour not_allowed)
			(footprints allowed)
		)
		(placement
			(enabled no)
			(sheetname "")
		)
		(fill yes
			(thermal_gap 0.5)
			(thermal_bridge_width 0.5)
			(island_removal_mode 0)
		)
		(polygon
			(pts
				(arc
					(start 425.190666 -240.871502)
					(mid 425.205545 -240.907423)
					(end 425.241466 -240.922302)
				)
				(arc
					(start 426.641006 -240.922302)
					(mid 426.676927 -240.907423)
					(end 426.691806 -240.871502)
				)
				(arc
					(start 426.691806 -240.462562)
					(mid 426.676927 -240.426641)
					(end 426.641006 -240.411762)
				)
				(arc
					(start 425.241466 -240.411762)
					(mid 425.205545 -240.426641)
					(end 425.190666 -240.462562)
				)
			)
		)
	)
	(zone
		(layers "In1.Cu" "In2.Cu")
		(hatch none 0.5)
		(connect_pads
			(clearance 0)
		)
		(min_thickness 0.25)
		(keepout
			(tracks not_allowed)
			(vias allowed)
			(pads allowed)
			(copperpour not_allowed)
			(footprints allowed)
		)
		(placement
			(enabled no)
			(sheetname "")
		)
		(fill yes
			(thermal_gap 0.5)
			(thermal_bridge_width 0.5)
			(island_removal_mode 0)
		)
		(polygon
			(pts
				(arc
					(start 52.65293 -252.771402)
					(mid 52.667809 -252.807323)
					(end 52.70373 -252.822202)
				)
				(arc
					(start 54.10327 -252.822202)
					(mid 54.139191 -252.807323)
					(end 54.15407 -252.771402)
				)
				(arc
					(start 54.15407 -252.362462)
					(mid 54.139191 -252.326541)
					(end 54.10327 -252.311662)
				)
				(arc
					(start 52.70373 -252.311662)
					(mid 52.667809 -252.326541)
					(end 52.65293 -252.362462)
				)
			)
		)
	)
	(zone
		(layers "In1.Cu" "In2.Cu")
		(hatch none 0.5)
		(connect_pads
			(clearance 0)
		)
		(min_thickness 0.25)
		(keepout
			(tracks not_allowed)
			(vias allowed)
			(pads allowed)
			(copperpour not_allowed)
			(footprints allowed)
		)
		(placement
			(enabled no)
			(sheetname "")
		)
		(fill yes
			(thermal_gap 0.5)
			(thermal_bridge_width 0.5)
			(island_removal_mode 0)
		)
		(polygon
			(pts
				(arc
					(start 462.909666 -300.37151)
					(mid 462.924545 -300.407431)
					(end 462.960466 -300.42231)
				)
				(arc
					(start 464.360006 -300.42231)
					(mid 464.395927 -300.407431)
					(end 464.410806 -300.37151)
				)
				(arc
					(start 464.410806 -299.96257)
					(mid 464.395927 -299.926649)
					(end 464.360006 -299.91177)
				)
				(arc
					(start 462.960466 -299.91177)
					(mid 462.924545 -299.926649)
					(end 462.909666 -299.96257)
				)
			)
		)
	)
	(zone
		(layers "In1.Cu" "In2.Cu")
		(hatch none 0.5)
		(connect_pads
			(clearance 0)
		)
		(min_thickness 0.25)
		(keepout
			(tracks not_allowed)
			(vias allowed)
			(pads allowed)
			(copperpour not_allowed)
			(footprints allowed)
		)
		(placement
			(enabled no)
			(sheetname "")
		)
		(fill yes
			(thermal_gap 0.5)
			(thermal_bridge_width 0.5)
			(island_removal_mode 0)
		)
		(polygon
			(pts
				(arc
					(start 37.56533 -230.67137)
					(mid 37.580209 -230.707291)
					(end 37.61613 -230.72217)
				)
				(arc
					(start 39.01567 -230.72217)
					(mid 39.051591 -230.707291)
					(end 39.06647 -230.67137)
				)
				(arc
					(start 39.06647 -230.26243)
					(mid 39.051591 -230.226509)
					(end 39.01567 -230.21163)
				)
				(arc
					(start 37.61613 -230.21163)
					(mid 37.580209 -230.226509)
					(end 37.56533 -230.26243)
				)
			)
		)
	)
	(zone
		(layers "In1.Cu" "In2.Cu")
		(hatch none 0.5)
		(connect_pads
			(clearance 0)
		)
		(min_thickness 0.25)
		(keepout
			(tracks not_allowed)
			(vias allowed)
			(pads allowed)
			(copperpour not_allowed)
			(footprints allowed)
		)
		(placement
			(enabled no)
			(sheetname "")
		)
		(fill yes
			(thermal_gap 0.5)
			(thermal_bridge_width 0.5)
			(island_removal_mode 0)
		)
		(polygon
			(pts
				(arc
					(start 255.330198 -261.271512)
					(mid 255.345077 -261.307433)
					(end 255.380998 -261.322312)
				)
				(arc
					(start 256.780538 -261.322312)
					(mid 256.816459 -261.307433)
					(end 256.831338 -261.271512)
				)
				(arc
					(start 256.831338 -260.862572)
					(mid 256.816459 -260.826651)
					(end 256.780538 -260.811772)
				)
				(arc
					(start 255.380998 -260.811772)
					(mid 255.345077 -260.826651)
					(end 255.330198 -260.862572)
				)
			)
		)
	)
	(zone
		(layers "In1.Cu" "In2.Cu")
		(hatch none 0.5)
		(connect_pads
			(clearance 0)
		)
		(min_thickness 0.25)
		(keepout
			(tracks not_allowed)
			(vias allowed)
			(pads allowed)
			(copperpour not_allowed)
			(footprints allowed)
		)
		(placement
			(enabled no)
			(sheetname "")
		)
		(fill yes
			(thermal_gap 0.5)
			(thermal_bridge_width 0.5)
			(island_removal_mode 0)
		)
		(polygon
			(pts
				(arc
					(start 210.86953 -290.171378)
					(mid 210.884409 -290.207299)
					(end 210.92033 -290.222178)
				)
				(arc
					(start 212.31987 -290.222178)
					(mid 212.355791 -290.207299)
					(end 212.37067 -290.171378)
				)
				(arc
					(start 212.37067 -289.762438)
					(mid 212.355791 -289.726517)
					(end 212.31987 -289.711638)
				)
				(arc
					(start 210.92033 -289.711638)
					(mid 210.884409 -289.726517)
					(end 210.86953 -289.762438)
				)
			)
		)
	)
	(zone
		(layers "In1.Cu" "In2.Cu")
		(hatch none 0.5)
		(connect_pads
			(clearance 0)
		)
		(min_thickness 0.25)
		(keepout
			(tracks not_allowed)
			(vias allowed)
			(pads allowed)
			(copperpour not_allowed)
			(footprints allowed)
		)
		(placement
			(enabled no)
			(sheetname "")
		)
		(fill yes
			(thermal_gap 0.5)
			(thermal_bridge_width 0.5)
			(island_removal_mode 0)
		)
		(polygon
			(pts
				(arc
					(start 312.236866 -251.921518)
					(mid 312.251745 -251.957439)
					(end 312.287666 -251.972318)
				)
				(arc
					(start 313.687206 -251.972318)
					(mid 313.723127 -251.957439)
					(end 313.738006 -251.921518)
				)
				(arc
					(start 313.738006 -251.512578)
					(mid 313.723127 -251.476657)
					(end 313.687206 -251.461778)
				)
				(arc
					(start 312.287666 -251.461778)
					(mid 312.251745 -251.476657)
					(end 312.236866 -251.512578)
				)
			)
		)
	)
	(zone
		(layers "In1.Cu" "In2.Cu")
		(hatch none 0.5)
		(connect_pads
			(clearance 0)
		)
		(min_thickness 0.25)
		(keepout
			(tracks not_allowed)
			(vias allowed)
			(pads allowed)
			(copperpour not_allowed)
			(footprints allowed)
		)
		(placement
			(enabled no)
			(sheetname "")
		)
		(fill yes
			(thermal_gap 0.5)
			(thermal_bridge_width 0.5)
			(island_removal_mode 0)
		)
		(polygon
			(pts
				(arc
					(start 458.809598 -228.121464)
					(mid 458.824477 -228.157385)
					(end 458.860398 -228.172264)
				)
				(arc
					(start 460.259938 -228.172264)
					(mid 460.295859 -228.157385)
					(end 460.310738 -228.121464)
				)
				(arc
					(start 460.310738 -227.712524)
					(mid 460.295859 -227.676603)
					(end 460.259938 -227.661724)
				)
				(arc
					(start 458.860398 -227.661724)
					(mid 458.824477 -227.676603)
					(end 458.809598 -227.712524)
				)
			)
		)
	)
	(zone
		(layers "In1.Cu" "In2.Cu")
		(hatch none 0.5)
		(connect_pads
			(clearance 0)
		)
		(min_thickness 0.25)
		(keepout
			(tracks not_allowed)
			(vias allowed)
			(pads allowed)
			(copperpour not_allowed)
			(footprints allowed)
		)
		(placement
			(enabled no)
			(sheetname "")
		)
		(fill yes
			(thermal_gap 0.5)
			(thermal_bridge_width 0.5)
			(island_removal_mode 0)
		)
		(polygon
			(pts
				(arc
					(start 266.974066 -274.02155)
					(mid 266.988945 -274.057471)
					(end 267.024866 -274.07235)
				)
				(arc
					(start 268.424406 -274.07235)
					(mid 268.460327 -274.057471)
					(end 268.475206 -274.02155)
				)
				(arc
					(start 268.475206 -273.61261)
					(mid 268.460327 -273.576689)
					(end 268.424406 -273.56181)
				)
				(arc
					(start 267.024866 -273.56181)
					(mid 266.988945 -273.576689)
					(end 266.974066 -273.61261)
				)
			)
		)
	)
	(zone
		(layers "In1.Cu" "In2.Cu")
		(hatch none 0.5)
		(connect_pads
			(clearance 0)
		)
		(min_thickness 0.25)
		(keepout
			(tracks not_allowed)
			(vias allowed)
			(pads allowed)
			(copperpour not_allowed)
			(footprints allowed)
		)
		(placement
			(enabled no)
			(sheetname "")
		)
		(fill yes
			(thermal_gap 0.5)
			(thermal_bridge_width 0.5)
			(island_removal_mode 0)
		)
		(polygon
			(pts
				(arc
					(start 304.693066 -292.721538)
					(mid 304.707945 -292.757459)
					(end 304.743866 -292.772338)
				)
				(arc
					(start 306.143406 -292.772338)
					(mid 306.179327 -292.757459)
					(end 306.194206 -292.721538)
				)
				(arc
					(start 306.194206 -292.312598)
					(mid 306.179327 -292.276677)
					(end 306.143406 -292.261798)
				)
				(arc
					(start 304.743866 -292.261798)
					(mid 304.707945 -292.276677)
					(end 304.693066 -292.312598)
				)
			)
		)
	)
	(zone
		(layers "In1.Cu" "In2.Cu")
		(hatch none 0.5)
		(connect_pads
			(clearance 0)
		)
		(min_thickness 0.25)
		(keepout
			(tracks not_allowed)
			(vias allowed)
			(pads allowed)
			(copperpour not_allowed)
			(footprints allowed)
		)
		(placement
			(enabled no)
			(sheetname "")
		)
		(fill yes
			(thermal_gap 0.5)
			(thermal_bridge_width 0.5)
			(island_removal_mode 0)
		)
		(polygon
			(pts
				(arc
					(start 289.605466 -246.821452)
					(mid 289.620345 -246.857373)
					(end 289.656266 -246.872252)
				)
				(arc
					(start 291.055806 -246.872252)
					(mid 291.091727 -246.857373)
					(end 291.106606 -246.821452)
				)
				(arc
					(start 291.106606 -246.412512)
					(mid 291.091727 -246.376591)
					(end 291.055806 -246.361712)
				)
				(arc
					(start 289.656266 -246.361712)
					(mid 289.620345 -246.376591)
					(end 289.605466 -246.412512)
				)
			)
		)
	)
	(zone
		(layers "In1.Cu" "In2.Cu")
		(hatch none 0.5)
		(connect_pads
			(clearance 0)
		)
		(min_thickness 0.25)
		(keepout
			(tracks not_allowed)
			(vias allowed)
			(pads allowed)
			(copperpour not_allowed)
			(footprints allowed)
		)
		(placement
			(enabled no)
			(sheetname "")
		)
		(fill yes
			(thermal_gap 0.5)
			(thermal_bridge_width 0.5)
			(island_removal_mode 0)
		)
		(polygon
			(pts
				(arc
					(start 406.002998 -268.071346)
					(mid 406.017877 -268.107267)
					(end 406.053798 -268.122146)
				)
				(arc
					(start 407.453338 -268.122146)
					(mid 407.489259 -268.107267)
					(end 407.504138 -268.071346)
				)
				(arc
					(start 407.504138 -267.662406)
					(mid 407.489259 -267.626485)
					(end 407.453338 -267.611606)
				)
				(arc
					(start 406.053798 -267.611606)
					(mid 406.017877 -267.626485)
					(end 406.002998 -267.662406)
				)
			)
		)
	)
	(zone
		(layers "In1.Cu" "In2.Cu")
		(hatch none 0.5)
		(connect_pads
			(clearance 0)
		)
		(min_thickness 0.25)
		(keepout
			(tracks not_allowed)
			(vias allowed)
			(pads allowed)
			(copperpour not_allowed)
			(footprints allowed)
		)
		(placement
			(enabled no)
			(sheetname "")
		)
		(fill yes
			(thermal_gap 0.5)
			(thermal_bridge_width 0.5)
			(island_removal_mode 0)
		)
		(polygon
			(pts
				(arc
					(start 192.338198 -197.521322)
					(mid 192.353077 -197.557243)
					(end 192.388998 -197.572122)
				)
				(arc
					(start 193.788538 -197.572122)
					(mid 193.824459 -197.557243)
					(end 193.839338 -197.521322)
				)
				(arc
					(start 193.839338 -197.112382)
					(mid 193.824459 -197.076461)
					(end 193.788538 -197.061582)
				)
				(arc
					(start 192.388998 -197.061582)
					(mid 192.353077 -197.076461)
					(end 192.338198 -197.112382)
				)
			)
		)
	)
	(zone
		(layers "In1.Cu" "In2.Cu")
		(hatch none 0.5)
		(connect_pads
			(clearance 0)
		)
		(min_thickness 0.25)
		(keepout
			(tracks not_allowed)
			(vias allowed)
			(pads allowed)
			(copperpour not_allowed)
			(footprints allowed)
		)
		(placement
			(enabled no)
			(sheetname "")
		)
		(fill yes
			(thermal_gap 0.5)
			(thermal_bridge_width 0.5)
			(island_removal_mode 0)
		)
		(polygon
			(pts
				(arc
					(start 34.121598 -260.421374)
					(mid 34.136477 -260.457295)
					(end 34.172398 -260.472174)
				)
				(arc
					(start 35.571938 -260.472174)
					(mid 35.607859 -260.457295)
					(end 35.622738 -260.421374)
				)
				(arc
					(start 35.622738 -260.012434)
					(mid 35.607859 -259.976513)
					(end 35.571938 -259.961634)
				)
				(arc
					(start 34.172398 -259.961634)
					(mid 34.136477 -259.976513)
					(end 34.121598 -260.012434)
				)
			)
		)
	)
	(zone
		(layers "In1.Cu" "In2.Cu")
		(hatch none 0.5)
		(connect_pads
			(clearance 0)
		)
		(min_thickness 0.25)
		(keepout
			(tracks not_allowed)
			(vias allowed)
			(pads allowed)
			(copperpour not_allowed)
			(footprints allowed)
		)
		(placement
			(enabled no)
			(sheetname "")
		)
		(fill yes
			(thermal_gap 0.5)
			(thermal_bridge_width 0.5)
			(island_removal_mode 0)
		)
		(polygon
			(pts
				(arc
					(start 45.10913 -245.971314)
					(mid 45.124009 -246.007235)
					(end 45.15993 -246.022114)
				)
				(arc
					(start 46.55947 -246.022114)
					(mid 46.595391 -246.007235)
					(end 46.61027 -245.971314)
				)
				(arc
					(start 46.61027 -245.562374)
					(mid 46.595391 -245.526453)
					(end 46.55947 -245.511574)
				)
				(arc
					(start 45.15993 -245.511574)
					(mid 45.124009 -245.526453)
					(end 45.10913 -245.562374)
				)
			)
		)
	)
	(zone
		(layers "In1.Cu" "In2.Cu")
		(hatch none 0.5)
		(connect_pads
			(clearance 0)
		)
		(min_thickness 0.25)
		(keepout
			(tracks not_allowed)
			(vias allowed)
			(pads allowed)
			(copperpour not_allowed)
			(footprints allowed)
		)
		(placement
			(enabled no)
			(sheetname "")
		)
		(fill yes
			(thermal_gap 0.5)
			(thermal_bridge_width 0.5)
			(island_removal_mode 0)
		)
		(polygon
			(pts
				(arc
					(start 413.546798 -282.521406)
					(mid 413.561677 -282.557327)
					(end 413.597598 -282.572206)
				)
				(arc
					(start 414.997138 -282.572206)
					(mid 415.033059 -282.557327)
					(end 415.047938 -282.521406)
				)
				(arc
					(start 415.047938 -282.112466)
					(mid 415.033059 -282.076545)
					(end 414.997138 -282.061666)
				)
				(arc
					(start 413.597598 -282.061666)
					(mid 413.561677 -282.076545)
					(end 413.546798 -282.112466)
				)
			)
		)
	)
	(zone
		(layers "In1.Cu" "In2.Cu")
		(hatch none 0.5)
		(connect_pads
			(clearance 0)
		)
		(min_thickness 0.25)
		(keepout
			(tracks not_allowed)
			(vias allowed)
			(pads allowed)
			(copperpour not_allowed)
			(footprints allowed)
		)
		(placement
			(enabled no)
			(sheetname "")
		)
		(fill yes
			(thermal_gap 0.5)
			(thermal_bridge_width 0.5)
			(island_removal_mode 0)
		)
		(polygon
			(pts
				(arc
					(start 45.10913 -297.82135)
					(mid 45.124009 -297.857271)
					(end 45.15993 -297.87215)
				)
				(arc
					(start 46.55947 -297.87215)
					(mid 46.595391 -297.857271)
					(end 46.61027 -297.82135)
				)
				(arc
					(start 46.61027 -297.41241)
					(mid 46.595391 -297.376489)
					(end 46.55947 -297.36161)
				)
				(arc
					(start 45.15993 -297.36161)
					(mid 45.124009 -297.376489)
					(end 45.10913 -297.41241)
				)
			)
		)
	)
	(zone
		(layers "In1.Cu" "In2.Cu")
		(hatch none 0.5)
		(connect_pads
			(clearance 0)
		)
		(min_thickness 0.25)
		(keepout
			(tracks not_allowed)
			(vias allowed)
			(pads allowed)
			(copperpour not_allowed)
			(footprints allowed)
		)
		(placement
			(enabled no)
			(sheetname "")
		)
		(fill yes
			(thermal_gap 0.5)
			(thermal_bridge_width 0.5)
			(island_removal_mode 0)
		)
		(polygon
			(pts
				(arc
					(start 289.605466 -200.071482)
					(mid 289.620345 -200.107403)
					(end 289.656266 -200.122282)
				)
				(arc
					(start 291.055806 -200.122282)
					(mid 291.091727 -200.107403)
					(end 291.106606 -200.071482)
				)
				(arc
					(start 291.106606 -199.662542)
					(mid 291.091727 -199.626621)
					(end 291.055806 -199.611742)
				)
				(arc
					(start 289.656266 -199.611742)
					(mid 289.620345 -199.626621)
					(end 289.605466 -199.662542)
				)
			)
		)
	)
	(zone
		(layers "In1.Cu" "In2.Cu")
		(hatch none 0.5)
		(connect_pads
			(clearance 0)
		)
		(min_thickness 0.25)
		(keepout
			(tracks not_allowed)
			(vias allowed)
			(pads allowed)
			(copperpour not_allowed)
			(footprints allowed)
		)
		(placement
			(enabled no)
			(sheetname "")
		)
		(fill yes
			(thermal_gap 0.5)
			(thermal_bridge_width 0.5)
			(island_removal_mode 0)
		)
		(polygon
			(pts
				(arc
					(start 7.39013 -261.271512)
					(mid 7.405009 -261.307433)
					(end 7.44093 -261.322312)
				)
				(arc
					(start 8.84047 -261.322312)
					(mid 8.876391 -261.307433)
					(end 8.89127 -261.271512)
				)
				(arc
					(start 8.89127 -260.862572)
					(mid 8.876391 -260.826651)
					(end 8.84047 -260.811772)
				)
				(arc
					(start 7.44093 -260.811772)
					(mid 7.405009 -260.826651)
					(end 7.39013 -260.862572)
				)
			)
		)
	)
	(zone
		(layers "In1.Cu" "In2.Cu")
		(hatch none 0.5)
		(connect_pads
			(clearance 0)
		)
		(min_thickness 0.25)
		(keepout
			(tracks not_allowed)
			(vias allowed)
			(pads allowed)
			(copperpour not_allowed)
			(footprints allowed)
		)
		(placement
			(enabled no)
			(sheetname "")
		)
		(fill yes
			(thermal_gap 0.5)
			(thermal_bridge_width 0.5)
			(island_removal_mode 0)
		)
		(polygon
			(pts
				(arc
					(start 199.881998 -216.22131)
					(mid 199.896877 -216.257231)
					(end 199.932798 -216.27211)
				)
				(arc
					(start 201.332338 -216.27211)
					(mid 201.368259 -216.257231)
					(end 201.383138 -216.22131)
				)
				(arc
					(start 201.383138 -215.81237)
					(mid 201.368259 -215.776449)
					(end 201.332338 -215.76157)
				)
				(arc
					(start 199.932798 -215.76157)
					(mid 199.896877 -215.776449)
					(end 199.881998 -215.81237)
				)
			)
		)
	)
	(zone
		(layers "In1.Cu" "In2.Cu")
		(hatch none 0.5)
		(connect_pads
			(clearance 0)
		)
		(min_thickness 0.25)
		(keepout
			(tracks not_allowed)
			(vias allowed)
			(pads allowed)
			(copperpour not_allowed)
			(footprints allowed)
		)
		(placement
			(enabled no)
			(sheetname "")
		)
		(fill yes
			(thermal_gap 0.5)
			(thermal_bridge_width 0.5)
			(island_removal_mode 0)
		)
		(polygon
			(pts
				(arc
					(start 60.19673 -240.021364)
					(mid 60.211609 -240.057285)
					(end 60.24753 -240.072164)
				)
				(arc
					(start 61.64707 -240.072164)
					(mid 61.682991 -240.057285)
					(end 61.69787 -240.021364)
				)
				(arc
					(start 61.69787 -239.612424)
					(mid 61.682991 -239.576503)
					(end 61.64707 -239.561624)
				)
				(arc
					(start 60.24753 -239.561624)
					(mid 60.211609 -239.576503)
					(end 60.19673 -239.612424)
				)
			)
		)
	)
	(zone
		(layers "In1.Cu" "In2.Cu")
		(hatch none 0.5)
		(connect_pads
			(clearance 0)
		)
		(min_thickness 0.25)
		(keepout
			(tracks not_allowed)
			(vias allowed)
			(pads allowed)
			(copperpour not_allowed)
			(footprints allowed)
		)
		(placement
			(enabled no)
			(sheetname "")
		)
		(fill yes
			(thermal_gap 0.5)
			(thermal_bridge_width 0.5)
			(island_removal_mode 0)
		)
		(polygon
			(pts
				(arc
					(start 428.634398 -247.671336)
					(mid 428.649277 -247.707257)
					(end 428.685198 -247.722136)
				)
				(arc
					(start 430.084738 -247.722136)
					(mid 430.120659 -247.707257)
					(end 430.135538 -247.671336)
				)
				(arc
					(start 430.135538 -247.262396)
					(mid 430.120659 -247.226475)
					(end 430.084738 -247.211596)
				)
				(arc
					(start 428.685198 -247.211596)
					(mid 428.649277 -247.226475)
					(end 428.634398 -247.262396)
				)
			)
		)
	)
	(zone
		(layers "In1.Cu" "In2.Cu")
		(hatch none 0.5)
		(connect_pads
			(clearance 0)
		)
		(min_thickness 0.25)
		(keepout
			(tracks not_allowed)
			(vias allowed)
			(pads allowed)
			(copperpour not_allowed)
			(footprints allowed)
		)
		(placement
			(enabled no)
			(sheetname "")
		)
		(fill yes
			(thermal_gap 0.5)
			(thermal_bridge_width 0.5)
			(island_removal_mode 0)
		)
		(polygon
			(pts
				(arc
					(start 207.425798 -300.37151)
					(mid 207.440677 -300.407431)
					(end 207.476598 -300.42231)
				)
				(arc
					(start 208.876138 -300.42231)
					(mid 208.912059 -300.407431)
					(end 208.926938 -300.37151)
				)
				(arc
					(start 208.926938 -299.96257)
					(mid 208.912059 -299.926649)
					(end 208.876138 -299.91177)
				)
				(arc
					(start 207.476598 -299.91177)
					(mid 207.440677 -299.926649)
					(end 207.425798 -299.96257)
				)
			)
		)
	)
	(zone
		(layers "In1.Cu" "In2.Cu")
		(hatch none 0.5)
		(connect_pads
			(clearance 0)
		)
		(min_thickness 0.25)
		(keepout
			(tracks not_allowed)
			(vias allowed)
			(pads allowed)
			(copperpour not_allowed)
			(footprints allowed)
		)
		(placement
			(enabled no)
			(sheetname "")
		)
		(fill yes
			(thermal_gap 0.5)
			(thermal_bridge_width 0.5)
			(island_removal_mode 0)
		)
		(polygon
			(pts
				(arc
					(start 60.19673 -314.821316)
					(mid 60.211609 -314.857237)
					(end 60.24753 -314.872116)
				)
				(arc
					(start 61.64707 -314.872116)
					(mid 61.682991 -314.857237)
					(end 61.69787 -314.821316)
				)
				(arc
					(start 61.69787 -314.412376)
					(mid 61.682991 -314.376455)
					(end 61.64707 -314.361576)
				)
				(arc
					(start 60.24753 -314.361576)
					(mid 60.211609 -314.376455)
					(end 60.19673 -314.412376)
				)
			)
		)
	)
	(zone
		(layers "In1.Cu" "In2.Cu")
		(hatch none 0.5)
		(connect_pads
			(clearance 0)
		)
		(min_thickness 0.25)
		(keepout
			(tracks not_allowed)
			(vias allowed)
			(pads allowed)
			(copperpour not_allowed)
			(footprints allowed)
		)
		(placement
			(enabled no)
			(sheetname "")
		)
		(fill yes
			(thermal_gap 0.5)
			(thermal_bridge_width 0.5)
			(island_removal_mode 0)
		)
		(polygon
			(pts
				(arc
					(start 289.605466 -313.971432)
					(mid 289.620345 -314.007353)
					(end 289.656266 -314.022232)
				)
				(arc
					(start 291.055806 -314.022232)
					(mid 291.091727 -314.007353)
					(end 291.106606 -313.971432)
				)
				(arc
					(start 291.106606 -313.562492)
					(mid 291.091727 -313.526571)
					(end 291.055806 -313.511692)
				)
				(arc
					(start 289.656266 -313.511692)
					(mid 289.620345 -313.526571)
					(end 289.605466 -313.562492)
				)
			)
		)
	)
	(zone
		(layers "In1.Cu" "In2.Cu")
		(hatch none 0.5)
		(connect_pads
			(clearance 0)
		)
		(min_thickness 0.25)
		(keepout
			(tracks not_allowed)
			(vias allowed)
			(pads allowed)
			(copperpour not_allowed)
			(footprints allowed)
		)
		(placement
			(enabled no)
			(sheetname "")
		)
		(fill yes
			(thermal_gap 0.5)
			(thermal_bridge_width 0.5)
			(island_removal_mode 0)
		)
		(polygon
			(pts
				(arc
					(start 14.93393 -312.27141)
					(mid 14.948809 -312.307331)
					(end 14.98473 -312.32221)
				)
				(arc
					(start 16.38427 -312.32221)
					(mid 16.420191 -312.307331)
					(end 16.43507 -312.27141)
				)
				(arc
					(start 16.43507 -311.86247)
					(mid 16.420191 -311.826549)
					(end 16.38427 -311.81167)
				)
				(arc
					(start 14.98473 -311.81167)
					(mid 14.948809 -311.826549)
					(end 14.93393 -311.86247)
				)
			)
		)
	)
	(zone
		(layers "In1.Cu" "In2.Cu")
		(hatch none 0.5)
		(connect_pads
			(clearance 0)
		)
		(min_thickness 0.25)
		(keepout
			(tracks not_allowed)
			(vias allowed)
			(pads allowed)
			(copperpour not_allowed)
			(footprints allowed)
		)
		(placement
			(enabled no)
			(sheetname "")
		)
		(fill yes
			(thermal_gap 0.5)
			(thermal_bridge_width 0.5)
			(island_removal_mode 0)
		)
		(polygon
			(pts
				(arc
					(start 26.577798 -306.32146)
					(mid 26.592677 -306.357381)
					(end 26.628598 -306.37226)
				)
				(arc
					(start 28.028138 -306.37226)
					(mid 28.064059 -306.357381)
					(end 28.078938 -306.32146)
				)
				(arc
					(start 28.078938 -305.91252)
					(mid 28.064059 -305.876599)
					(end 28.028138 -305.86172)
				)
				(arc
					(start 26.628598 -305.86172)
					(mid 26.592677 -305.876599)
					(end 26.577798 -305.91252)
				)
			)
		)
	)
	(zone
		(layers "In1.Cu" "In2.Cu")
		(hatch none 0.5)
		(connect_pads
			(clearance 0)
		)
		(min_thickness 0.25)
		(keepout
			(tracks not_allowed)
			(vias allowed)
			(pads allowed)
			(copperpour not_allowed)
			(footprints allowed)
		)
		(placement
			(enabled no)
			(sheetname "")
		)
		(fill yes
			(thermal_gap 0.5)
			(thermal_bridge_width 0.5)
			(island_removal_mode 0)
		)
		(polygon
			(pts
				(arc
					(start 293.049198 -285.071312)
					(mid 293.064077 -285.107233)
					(end 293.099998 -285.122112)
				)
				(arc
					(start 294.499538 -285.122112)
					(mid 294.535459 -285.107233)
					(end 294.550338 -285.071312)
				)
				(arc
					(start 294.550338 -284.662372)
					(mid 294.535459 -284.626451)
					(end 294.499538 -284.611572)
				)
				(arc
					(start 293.099998 -284.611572)
					(mid 293.064077 -284.626451)
					(end 293.049198 -284.662372)
				)
			)
		)
	)
	(zone
		(layers "In1.Cu" "In2.Cu")
		(hatch none 0.5)
		(connect_pads
			(clearance 0)
		)
		(min_thickness 0.25)
		(keepout
			(tracks not_allowed)
			(vias allowed)
			(pads allowed)
			(copperpour not_allowed)
			(footprints allowed)
		)
		(placement
			(enabled no)
			(sheetname "")
		)
		(fill yes
			(thermal_gap 0.5)
			(thermal_bridge_width 0.5)
			(island_removal_mode 0)
		)
		(polygon
			(pts
				(arc
					(start 195.78193 -286.771334)
					(mid 195.796809 -286.807255)
					(end 195.83273 -286.822134)
				)
				(arc
					(start 197.23227 -286.822134)
					(mid 197.268191 -286.807255)
					(end 197.28307 -286.771334)
				)
				(arc
					(start 197.28307 -286.362394)
					(mid 197.268191 -286.326473)
					(end 197.23227 -286.311594)
				)
				(arc
					(start 195.83273 -286.311594)
					(mid 195.796809 -286.326473)
					(end 195.78193 -286.362394)
				)
			)
		)
	)
	(zone
		(layers "In1.Cu" "In2.Cu")
		(hatch none 0.5)
		(connect_pads
			(clearance 0)
		)
		(min_thickness 0.25)
		(keepout
			(tracks not_allowed)
			(vias allowed)
			(pads allowed)
			(copperpour not_allowed)
			(footprints allowed)
		)
		(placement
			(enabled no)
			(sheetname "")
		)
		(fill yes
			(thermal_gap 0.5)
			(thermal_bridge_width 0.5)
			(island_removal_mode 0)
		)
		(polygon
			(pts
				(arc
					(start 60.19673 -303.7713)
					(mid 60.211609 -303.807221)
					(end 60.24753 -303.8221)
				)
				(arc
					(start 61.64707 -303.8221)
					(mid 61.682991 -303.807221)
					(end 61.69787 -303.7713)
				)
				(arc
					(start 61.69787 -303.36236)
					(mid 61.682991 -303.326439)
					(end 61.64707 -303.31156)
				)
				(arc
					(start 60.24753 -303.31156)
					(mid 60.211609 -303.326439)
					(end 60.19673 -303.36236)
				)
			)
		)
	)
	(zone
		(layers "In1.Cu" "In2.Cu")
		(hatch none 0.5)
		(connect_pads
			(clearance 0)
		)
		(min_thickness 0.25)
		(keepout
			(tracks not_allowed)
			(vias allowed)
			(pads allowed)
			(copperpour not_allowed)
			(footprints allowed)
		)
		(placement
			(enabled no)
			(sheetname "")
		)
		(fill yes
			(thermal_gap 0.5)
			(thermal_bridge_width 0.5)
			(island_removal_mode 0)
		)
		(polygon
			(pts
				(arc
					(start 440.278266 -234.921298)
					(mid 440.293145 -234.957219)
					(end 440.329066 -234.972098)
				)
				(arc
					(start 441.728606 -234.972098)
					(mid 441.764527 -234.957219)
					(end 441.779406 -234.921298)
				)
				(arc
					(start 441.779406 -234.512358)
					(mid 441.764527 -234.476437)
					(end 441.728606 -234.461558)
				)
				(arc
					(start 440.329066 -234.461558)
					(mid 440.293145 -234.476437)
					(end 440.278266 -234.512358)
				)
			)
		)
	)
	(zone
		(layers "In1.Cu" "In2.Cu")
		(hatch none 0.5)
		(connect_pads
			(clearance 0)
		)
		(min_thickness 0.25)
		(keepout
			(tracks not_allowed)
			(vias allowed)
			(pads allowed)
			(copperpour not_allowed)
			(footprints allowed)
		)
		(placement
			(enabled no)
			(sheetname "")
		)
		(fill yes
			(thermal_gap 0.5)
			(thermal_bridge_width 0.5)
			(island_removal_mode 0)
		)
		(polygon
			(pts
				(arc
					(start 432.734466 -274.02155)
					(mid 432.749345 -274.057471)
					(end 432.785266 -274.07235)
				)
				(arc
					(start 434.184806 -274.07235)
					(mid 434.220727 -274.057471)
					(end 434.235606 -274.02155)
				)
				(arc
					(start 434.235606 -273.61261)
					(mid 434.220727 -273.576689)
					(end 434.184806 -273.56181)
				)
				(arc
					(start 432.785266 -273.56181)
					(mid 432.749345 -273.576689)
					(end 432.734466 -273.61261)
				)
			)
		)
	)
	(zone
		(layers "In1.Cu" "In2.Cu")
		(hatch none 0.5)
		(connect_pads
			(clearance 0)
		)
		(min_thickness 0.25)
		(keepout
			(tracks not_allowed)
			(vias allowed)
			(pads allowed)
			(copperpour not_allowed)
			(footprints allowed)
		)
		(placement
			(enabled no)
			(sheetname "")
		)
		(fill yes
			(thermal_gap 0.5)
			(thermal_bridge_width 0.5)
			(island_removal_mode 0)
		)
		(polygon
			(pts
				(arc
					(start 462.909666 -274.871434)
					(mid 462.924545 -274.907355)
					(end 462.960466 -274.922234)
				)
				(arc
					(start 464.360006 -274.922234)
					(mid 464.395927 -274.907355)
					(end 464.410806 -274.871434)
				)
				(arc
					(start 464.410806 -274.462494)
					(mid 464.395927 -274.426573)
					(end 464.360006 -274.411694)
				)
				(arc
					(start 462.960466 -274.411694)
					(mid 462.924545 -274.426573)
					(end 462.909666 -274.462494)
				)
			)
		)
	)
	(zone
		(layers "In1.Cu" "In2.Cu")
		(hatch none 0.5)
		(connect_pads
			(clearance 0)
		)
		(min_thickness 0.25)
		(keepout
			(tracks not_allowed)
			(vias allowed)
			(pads allowed)
			(copperpour not_allowed)
			(footprints allowed)
		)
		(placement
			(enabled no)
			(sheetname "")
		)
		(fill yes
			(thermal_gap 0.5)
			(thermal_bridge_width 0.5)
			(island_removal_mode 0)
		)
		(polygon
			(pts
				(arc
					(start 285.505398 -237.471458)
					(mid 285.520277 -237.507379)
					(end 285.556198 -237.522258)
				)
				(arc
					(start 286.955738 -237.522258)
					(mid 286.991659 -237.507379)
					(end 287.006538 -237.471458)
				)
				(arc
					(start 287.006538 -237.062518)
					(mid 286.991659 -237.026597)
					(end 286.955738 -237.011718)
				)
				(arc
					(start 285.556198 -237.011718)
					(mid 285.520277 -237.026597)
					(end 285.505398 -237.062518)
				)
			)
		)
	)
	(zone
		(layers "In1.Cu" "In2.Cu")
		(hatch none 0.5)
		(connect_pads
			(clearance 0)
		)
		(min_thickness 0.25)
		(keepout
			(tracks not_allowed)
			(vias allowed)
			(pads allowed)
			(copperpour not_allowed)
			(footprints allowed)
		)
		(placement
			(enabled no)
			(sheetname "")
		)
		(fill yes
			(thermal_gap 0.5)
			(thermal_bridge_width 0.5)
			(island_removal_mode 0)
		)
		(polygon
			(pts
				(arc
					(start 188.23813 -303.7713)
					(mid 188.253009 -303.807221)
					(end 188.28893 -303.8221)
				)
				(arc
					(start 189.68847 -303.8221)
					(mid 189.724391 -303.807221)
					(end 189.73927 -303.7713)
				)
				(arc
					(start 189.73927 -303.36236)
					(mid 189.724391 -303.326439)
					(end 189.68847 -303.31156)
				)
				(arc
					(start 188.28893 -303.31156)
					(mid 188.253009 -303.326439)
					(end 188.23813 -303.36236)
				)
			)
		)
	)
	(zone
		(layers "In1.Cu" "In2.Cu")
		(hatch none 0.5)
		(connect_pads
			(clearance 0)
		)
		(min_thickness 0.25)
		(keepout
			(tracks not_allowed)
			(vias allowed)
			(pads allowed)
			(copperpour not_allowed)
			(footprints allowed)
		)
		(placement
			(enabled no)
			(sheetname "")
		)
		(fill yes
			(thermal_gap 0.5)
			(thermal_bridge_width 0.5)
			(island_removal_mode 0)
		)
		(polygon
			(pts
				(arc
					(start 11.490198 -272.321528)
					(mid 11.505077 -272.357449)
					(end 11.540998 -272.372328)
				)
				(arc
					(start 12.940538 -272.372328)
					(mid 12.976459 -272.357449)
					(end 12.991338 -272.321528)
				)
				(arc
					(start 12.991338 -271.912588)
					(mid 12.976459 -271.876667)
					(end 12.940538 -271.861788)
				)
				(arc
					(start 11.540998 -271.861788)
					(mid 11.505077 -271.876667)
					(end 11.490198 -271.912588)
				)
			)
		)
	)
	(zone
		(layers "In1.Cu" "In2.Cu")
		(hatch none 0.5)
		(connect_pads
			(clearance 0)
		)
		(min_thickness 0.25)
		(keepout
			(tracks not_allowed)
			(vias allowed)
			(pads allowed)
			(copperpour not_allowed)
			(footprints allowed)
		)
		(placement
			(enabled no)
			(sheetname "")
		)
		(fill yes
			(thermal_gap 0.5)
			(thermal_bridge_width 0.5)
			(island_removal_mode 0)
		)
		(polygon
			(pts
				(arc
					(start 64.296798 -195.821554)
					(mid 64.311677 -195.857475)
					(end 64.347598 -195.872354)
				)
				(arc
					(start 65.747138 -195.872354)
					(mid 65.783059 -195.857475)
					(end 65.797938 -195.821554)
				)
				(arc
					(start 65.797938 -195.412614)
					(mid 65.783059 -195.376693)
					(end 65.747138 -195.361814)
				)
				(arc
					(start 64.347598 -195.361814)
					(mid 64.311677 -195.376693)
					(end 64.296798 -195.412614)
				)
			)
		)
	)
	(zone
		(layers "In1.Cu" "In2.Cu")
		(hatch none 0.5)
		(connect_pads
			(clearance 0)
		)
		(min_thickness 0.25)
		(keepout
			(tracks not_allowed)
			(vias allowed)
			(pads allowed)
			(copperpour not_allowed)
			(footprints allowed)
		)
		(placement
			(enabled no)
			(sheetname "")
		)
		(fill yes
			(thermal_gap 0.5)
			(thermal_bridge_width 0.5)
			(island_removal_mode 0)
		)
		(polygon
			(pts
				(arc
					(start 52.65293 -296.121328)
					(mid 52.667809 -296.157249)
					(end 52.70373 -296.172128)
				)
				(arc
					(start 54.10327 -296.172128)
					(mid 54.139191 -296.157249)
					(end 54.15407 -296.121328)
				)
				(arc
					(start 54.15407 -295.712388)
					(mid 54.139191 -295.676467)
					(end 54.10327 -295.661588)
				)
				(arc
					(start 52.70373 -295.661588)
					(mid 52.667809 -295.676467)
					(end 52.65293 -295.712388)
				)
			)
		)
	)
	(zone
		(layers "In1.Cu" "In2.Cu")
		(hatch none 0.5)
		(connect_pads
			(clearance 0)
		)
		(min_thickness 0.25)
		(keepout
			(tracks not_allowed)
			(vias allowed)
			(pads allowed)
			(copperpour not_allowed)
			(footprints allowed)
		)
		(placement
			(enabled no)
			(sheetname "")
		)
		(fill yes
			(thermal_gap 0.5)
			(thermal_bridge_width 0.5)
			(island_removal_mode 0)
		)
		(polygon
			(pts
				(arc
					(start 26.577798 -302.921416)
					(mid 26.592677 -302.957337)
					(end 26.628598 -302.972216)
				)
				(arc
					(start 28.028138 -302.972216)
					(mid 28.064059 -302.957337)
					(end 28.078938 -302.921416)
				)
				(arc
					(start 28.078938 -302.512476)
					(mid 28.064059 -302.476555)
					(end 28.028138 -302.461676)
				)
				(arc
					(start 26.628598 -302.461676)
					(mid 26.592677 -302.476555)
					(end 26.577798 -302.512476)
				)
			)
		)
	)
	(zone
		(layers "In1.Cu" "In2.Cu")
		(hatch none 0.5)
		(connect_pads
			(clearance 0)
		)
		(min_thickness 0.25)
		(keepout
			(tracks not_allowed)
			(vias allowed)
			(pads allowed)
			(copperpour not_allowed)
			(footprints allowed)
		)
		(placement
			(enabled no)
			(sheetname "")
		)
		(fill yes
			(thermal_gap 0.5)
			(thermal_bridge_width 0.5)
			(island_removal_mode 0)
		)
		(polygon
			(pts
				(arc
					(start 199.881998 -227.271326)
					(mid 199.896877 -227.307247)
					(end 199.932798 -227.322126)
				)
				(arc
					(start 201.332338 -227.322126)
					(mid 201.368259 -227.307247)
					(end 201.383138 -227.271326)
				)
				(arc
					(start 201.383138 -226.862386)
					(mid 201.368259 -226.826465)
					(end 201.332338 -226.811586)
				)
				(arc
					(start 199.932798 -226.811586)
					(mid 199.896877 -226.826465)
					(end 199.881998 -226.862386)
				)
			)
		)
	)
	(zone
		(layers "In1.Cu" "In2.Cu")
		(hatch none 0.5)
		(connect_pads
			(clearance 0)
		)
		(min_thickness 0.25)
		(keepout
			(tracks not_allowed)
			(vias allowed)
			(pads allowed)
			(copperpour not_allowed)
			(footprints allowed)
		)
		(placement
			(enabled no)
			(sheetname "")
		)
		(fill yes
			(thermal_gap 0.5)
			(thermal_bridge_width 0.5)
			(island_removal_mode 0)
		)
		(polygon
			(pts
				(arc
					(start 308.136798 -232.371392)
					(mid 308.151677 -232.407313)
					(end 308.187598 -232.422192)
				)
				(arc
					(start 309.587138 -232.422192)
					(mid 309.623059 -232.407313)
					(end 309.637938 -232.371392)
				)
				(arc
					(start 309.637938 -231.962452)
					(mid 309.623059 -231.926531)
					(end 309.587138 -231.911652)
				)
				(arc
					(start 308.187598 -231.911652)
					(mid 308.151677 -231.926531)
					(end 308.136798 -231.962452)
				)
			)
		)
	)
	(zone
		(layers "In1.Cu" "In2.Cu")
		(hatch none 0.5)
		(connect_pads
			(clearance 0)
		)
		(min_thickness 0.25)
		(keepout
			(tracks not_allowed)
			(vias allowed)
			(pads allowed)
			(copperpour not_allowed)
			(footprints allowed)
		)
		(placement
			(enabled no)
			(sheetname "")
		)
		(fill yes
			(thermal_gap 0.5)
			(thermal_bridge_width 0.5)
			(island_removal_mode 0)
		)
		(polygon
			(pts
				(arc
					(start 410.103066 -279.9715)
					(mid 410.117945 -280.007421)
					(end 410.153866 -280.0223)
				)
				(arc
					(start 411.553406 -280.0223)
					(mid 411.589327 -280.007421)
					(end 411.604206 -279.9715)
				)
				(arc
					(start 411.604206 -279.56256)
					(mid 411.589327 -279.526639)
					(end 411.553406 -279.51176)
				)
				(arc
					(start 410.153866 -279.51176)
					(mid 410.117945 -279.526639)
					(end 410.103066 -279.56256)
				)
			)
		)
	)
	(zone
		(layers "In1.Cu" "In2.Cu")
		(hatch none 0.5)
		(connect_pads
			(clearance 0)
		)
		(min_thickness 0.25)
		(keepout
			(tracks not_allowed)
			(vias allowed)
			(pads allowed)
			(copperpour not_allowed)
			(footprints allowed)
		)
		(placement
			(enabled no)
			(sheetname "")
		)
		(fill yes
			(thermal_gap 0.5)
			(thermal_bridge_width 0.5)
			(island_removal_mode 0)
		)
		(polygon
			(pts
				(arc
					(start 173.15053 -206.021432)
					(mid 173.165409 -206.057353)
					(end 173.20133 -206.072232)
				)
				(arc
					(start 174.60087 -206.072232)
					(mid 174.636791 -206.057353)
					(end 174.65167 -206.021432)
				)
				(arc
					(start 174.65167 -205.612492)
					(mid 174.636791 -205.576571)
					(end 174.60087 -205.561692)
				)
				(arc
					(start 173.20133 -205.561692)
					(mid 173.165409 -205.576571)
					(end 173.15053 -205.612492)
				)
			)
		)
	)
	(zone
		(layers "In1.Cu" "In2.Cu")
		(hatch none 0.5)
		(connect_pads
			(clearance 0)
		)
		(min_thickness 0.25)
		(keepout
			(tracks not_allowed)
			(vias allowed)
			(pads allowed)
			(copperpour not_allowed)
			(footprints allowed)
		)
		(placement
			(enabled no)
			(sheetname "")
		)
		(fill yes
			(thermal_gap 0.5)
			(thermal_bridge_width 0.5)
			(island_removal_mode 0)
		)
		(polygon
			(pts
				(arc
					(start 162.162998 -246.821452)
					(mid 162.177877 -246.857373)
					(end 162.213798 -246.872252)
				)
				(arc
					(start 163.613338 -246.872252)
					(mid 163.649259 -246.857373)
					(end 163.664138 -246.821452)
				)
				(arc
					(start 163.664138 -246.412512)
					(mid 163.649259 -246.376591)
					(end 163.613338 -246.361712)
				)
				(arc
					(start 162.213798 -246.361712)
					(mid 162.177877 -246.376591)
					(end 162.162998 -246.412512)
				)
			)
		)
	)
	(zone
		(layers "In1.Cu" "In2.Cu")
		(hatch none 0.5)
		(connect_pads
			(clearance 0)
		)
		(min_thickness 0.25)
		(keepout
			(tracks not_allowed)
			(vias allowed)
			(pads allowed)
			(copperpour not_allowed)
			(footprints allowed)
		)
		(placement
			(enabled no)
			(sheetname "")
		)
		(fill yes
			(thermal_gap 0.5)
			(thermal_bridge_width 0.5)
			(island_removal_mode 0)
		)
		(polygon
			(pts
				(arc
					(start 52.65293 -275.721318)
					(mid 52.667809 -275.757239)
					(end 52.70373 -275.772118)
				)
				(arc
					(start 54.10327 -275.772118)
					(mid 54.139191 -275.757239)
					(end 54.15407 -275.721318)
				)
				(arc
					(start 54.15407 -275.312378)
					(mid 54.139191 -275.276457)
					(end 54.10327 -275.261578)
				)
				(arc
					(start 52.70373 -275.261578)
					(mid 52.667809 -275.276457)
					(end 52.65293 -275.312378)
				)
			)
		)
	)
	(zone
		(layers "In1.Cu" "In2.Cu")
		(hatch none 0.5)
		(connect_pads
			(clearance 0)
		)
		(min_thickness 0.25)
		(keepout
			(tracks not_allowed)
			(vias allowed)
			(pads allowed)
			(copperpour not_allowed)
			(footprints allowed)
		)
		(placement
			(enabled no)
			(sheetname "")
		)
		(fill yes
			(thermal_gap 0.5)
			(thermal_bridge_width 0.5)
			(island_removal_mode 0)
		)
		(polygon
			(pts
				(arc
					(start 19.033998 -274.871434)
					(mid 19.048877 -274.907355)
					(end 19.084798 -274.922234)
				)
				(arc
					(start 20.484338 -274.922234)
					(mid 20.520259 -274.907355)
					(end 20.535138 -274.871434)
				)
				(arc
					(start 20.535138 -274.462494)
					(mid 20.520259 -274.426573)
					(end 20.484338 -274.411694)
				)
				(arc
					(start 19.084798 -274.411694)
					(mid 19.048877 -274.426573)
					(end 19.033998 -274.462494)
				)
			)
		)
	)
	(zone
		(layers "In1.Cu" "In2.Cu")
		(hatch none 0.5)
		(connect_pads
			(clearance 0)
		)
		(min_thickness 0.25)
		(keepout
			(tracks not_allowed)
			(vias allowed)
			(pads allowed)
			(copperpour not_allowed)
			(footprints allowed)
		)
		(placement
			(enabled no)
			(sheetname "")
		)
		(fill yes
			(thermal_gap 0.5)
			(thermal_bridge_width 0.5)
			(island_removal_mode 0)
		)
		(polygon
			(pts
				(arc
					(start 432.734466 -208.571338)
					(mid 432.749345 -208.607259)
					(end 432.785266 -208.622138)
				)
				(arc
					(start 434.184806 -208.622138)
					(mid 434.220727 -208.607259)
					(end 434.235606 -208.571338)
				)
				(arc
					(start 434.235606 -208.162398)
					(mid 434.220727 -208.126477)
					(end 434.184806 -208.111598)
				)
				(arc
					(start 432.785266 -208.111598)
					(mid 432.749345 -208.126477)
					(end 432.734466 -208.162398)
				)
			)
		)
	)
	(zone
		(layers "In1.Cu" "In2.Cu")
		(hatch none 0.5)
		(connect_pads
			(clearance 0)
		)
		(min_thickness 0.25)
		(keepout
			(tracks not_allowed)
			(vias allowed)
			(pads allowed)
			(copperpour not_allowed)
			(footprints allowed)
		)
		(placement
			(enabled no)
			(sheetname "")
		)
		(fill yes
			(thermal_gap 0.5)
			(thermal_bridge_width 0.5)
			(island_removal_mode 0)
		)
		(polygon
			(pts
				(arc
					(start 158.06293 -247.671336)
					(mid 158.077809 -247.707257)
					(end 158.11373 -247.722136)
				)
				(arc
					(start 159.51327 -247.722136)
					(mid 159.549191 -247.707257)
					(end 159.56407 -247.671336)
				)
				(arc
					(start 159.56407 -247.262396)
					(mid 159.549191 -247.226475)
					(end 159.51327 -247.211596)
				)
				(arc
					(start 158.11373 -247.211596)
					(mid 158.077809 -247.226475)
					(end 158.06293 -247.262396)
				)
			)
		)
	)
	(zone
		(layers "In1.Cu" "In2.Cu")
		(hatch none 0.5)
		(connect_pads
			(clearance 0)
		)
		(min_thickness 0.25)
		(keepout
			(tracks not_allowed)
			(vias allowed)
			(pads allowed)
			(copperpour not_allowed)
			(footprints allowed)
		)
		(placement
			(enabled no)
			(sheetname "")
		)
		(fill yes
			(thermal_gap 0.5)
			(thermal_bridge_width 0.5)
			(island_removal_mode 0)
		)
		(polygon
			(pts
				(arc
					(start 210.86953 -244.271292)
					(mid 210.884409 -244.307213)
					(end 210.92033 -244.322092)
				)
				(arc
					(start 212.31987 -244.322092)
					(mid 212.355791 -244.307213)
					(end 212.37067 -244.271292)
				)
				(arc
					(start 212.37067 -243.862352)
					(mid 212.355791 -243.826431)
					(end 212.31987 -243.811552)
				)
				(arc
					(start 210.92033 -243.811552)
					(mid 210.884409 -243.826431)
					(end 210.86953 -243.862352)
				)
			)
		)
	)
	(zone
		(layers "In1.Cu" "In2.Cu")
		(hatch none 0.5)
		(connect_pads
			(clearance 0)
		)
		(min_thickness 0.25)
		(keepout
			(tracks not_allowed)
			(vias allowed)
			(pads allowed)
			(copperpour not_allowed)
			(footprints allowed)
		)
		(placement
			(enabled no)
			(sheetname "")
		)
		(fill yes
			(thermal_gap 0.5)
			(thermal_bridge_width 0.5)
			(island_removal_mode 0)
		)
		(polygon
			(pts
				(arc
					(start 11.490198 -274.02155)
					(mid 11.505077 -274.057471)
					(end 11.540998 -274.07235)
				)
				(arc
					(start 12.940538 -274.07235)
					(mid 12.976459 -274.057471)
					(end 12.991338 -274.02155)
				)
				(arc
					(start 12.991338 -273.61261)
					(mid 12.976459 -273.576689)
					(end 12.940538 -273.56181)
				)
				(arc
					(start 11.540998 -273.56181)
					(mid 11.505077 -273.576689)
					(end 11.490198 -273.61261)
				)
			)
		)
	)
	(zone
		(layers "In1.Cu" "In2.Cu")
		(hatch none 0.5)
		(connect_pads
			(clearance 0)
		)
		(min_thickness 0.25)
		(keepout
			(tracks not_allowed)
			(vias allowed)
			(pads allowed)
			(copperpour not_allowed)
			(footprints allowed)
		)
		(placement
			(enabled no)
			(sheetname "")
		)
		(fill yes
			(thermal_gap 0.5)
			(thermal_bridge_width 0.5)
			(island_removal_mode 0)
		)
		(polygon
			(pts
				(arc
					(start 214.969598 -291.021516)
					(mid 214.984477 -291.057437)
					(end 215.020398 -291.072316)
				)
				(arc
					(start 216.419938 -291.072316)
					(mid 216.455859 -291.057437)
					(end 216.470738 -291.021516)
				)
				(arc
					(start 216.470738 -290.612576)
					(mid 216.455859 -290.576655)
					(end 216.419938 -290.561776)
				)
				(arc
					(start 215.020398 -290.561776)
					(mid 214.984477 -290.576655)
					(end 214.969598 -290.612576)
				)
			)
		)
	)
	(zone
		(layers "In1.Cu" "In2.Cu")
		(hatch none 0.5)
		(connect_pads
			(clearance 0)
		)
		(min_thickness 0.25)
		(keepout
			(tracks not_allowed)
			(vias allowed)
			(pads allowed)
			(copperpour not_allowed)
			(footprints allowed)
		)
		(placement
			(enabled no)
			(sheetname "")
		)
		(fill yes
			(thermal_gap 0.5)
			(thermal_bridge_width 0.5)
			(island_removal_mode 0)
		)
		(polygon
			(pts
				(arc
					(start 210.86953 -240.021364)
					(mid 210.884409 -240.057285)
					(end 210.92033 -240.072164)
				)
				(arc
					(start 212.31987 -240.072164)
					(mid 212.355791 -240.057285)
					(end 212.37067 -240.021364)
				)
				(arc
					(start 212.37067 -239.612424)
					(mid 212.355791 -239.576503)
					(end 212.31987 -239.561624)
				)
				(arc
					(start 210.92033 -239.561624)
					(mid 210.884409 -239.576503)
					(end 210.86953 -239.612424)
				)
			)
		)
	)
	(zone
		(layers "In1.Cu" "In2.Cu")
		(hatch none 0.5)
		(connect_pads
			(clearance 0)
		)
		(min_thickness 0.25)
		(keepout
			(tracks not_allowed)
			(vias allowed)
			(pads allowed)
			(copperpour not_allowed)
			(footprints allowed)
		)
		(placement
			(enabled no)
			(sheetname "")
		)
		(fill yes
			(thermal_gap 0.5)
			(thermal_bridge_width 0.5)
			(island_removal_mode 0)
		)
		(polygon
			(pts
				(arc
					(start 169.706798 -231.521508)
					(mid 169.721677 -231.557429)
					(end 169.757598 -231.572308)
				)
				(arc
					(start 171.157138 -231.572308)
					(mid 171.193059 -231.557429)
					(end 171.207938 -231.521508)
				)
				(arc
					(start 171.207938 -231.112568)
					(mid 171.193059 -231.076647)
					(end 171.157138 -231.061768)
				)
				(arc
					(start 169.757598 -231.061768)
					(mid 169.721677 -231.076647)
					(end 169.706798 -231.112568)
				)
			)
		)
	)
	(zone
		(layers "In1.Cu" "In2.Cu")
		(hatch none 0.5)
		(connect_pads
			(clearance 0)
		)
		(min_thickness 0.25)
		(keepout
			(tracks not_allowed)
			(vias allowed)
			(pads allowed)
			(copperpour not_allowed)
			(footprints allowed)
		)
		(placement
			(enabled no)
			(sheetname "")
		)
		(fill yes
			(thermal_gap 0.5)
			(thermal_bridge_width 0.5)
			(island_removal_mode 0)
		)
		(polygon
			(pts
				(arc
					(start 184.794398 -239.17148)
					(mid 184.809277 -239.207401)
					(end 184.845198 -239.22228)
				)
				(arc
					(start 186.244738 -239.22228)
					(mid 186.280659 -239.207401)
					(end 186.295538 -239.17148)
				)
				(arc
					(start 186.295538 -238.76254)
					(mid 186.280659 -238.726619)
					(end 186.244738 -238.71174)
				)
				(arc
					(start 184.845198 -238.71174)
					(mid 184.809277 -238.726619)
					(end 184.794398 -238.76254)
				)
			)
		)
	)
	(zone
		(layers "In1.Cu" "In2.Cu")
		(hatch none 0.5)
		(connect_pads
			(clearance 0)
		)
		(min_thickness 0.25)
		(keepout
			(tracks not_allowed)
			(vias allowed)
			(pads allowed)
			(copperpour not_allowed)
			(footprints allowed)
		)
		(placement
			(enabled no)
			(sheetname "")
		)
		(fill yes
			(thermal_gap 0.5)
			(thermal_bridge_width 0.5)
			(island_removal_mode 0)
		)
		(polygon
			(pts
				(arc
					(start 406.002998 -308.871366)
					(mid 406.017877 -308.907287)
					(end 406.053798 -308.922166)
				)
				(arc
					(start 407.453338 -308.922166)
					(mid 407.489259 -308.907287)
					(end 407.504138 -308.871366)
				)
				(arc
					(start 407.504138 -308.462426)
					(mid 407.489259 -308.426505)
					(end 407.453338 -308.411626)
				)
				(arc
					(start 406.053798 -308.411626)
					(mid 406.017877 -308.426505)
					(end 406.002998 -308.462426)
				)
			)
		)
	)
	(zone
		(layers "In1.Cu" "In2.Cu")
		(hatch none 0.5)
		(connect_pads
			(clearance 0)
		)
		(min_thickness 0.25)
		(keepout
			(tracks not_allowed)
			(vias allowed)
			(pads allowed)
			(copperpour not_allowed)
			(footprints allowed)
		)
		(placement
			(enabled no)
			(sheetname "")
		)
		(fill yes
			(thermal_gap 0.5)
			(thermal_bridge_width 0.5)
			(island_removal_mode 0)
		)
		(polygon
			(pts
				(arc
					(start 34.121598 -300.37151)
					(mid 34.136477 -300.407431)
					(end 34.172398 -300.42231)
				)
				(arc
					(start 35.571938 -300.42231)
					(mid 35.607859 -300.407431)
					(end 35.622738 -300.37151)
				)
				(arc
					(start 35.622738 -299.96257)
					(mid 35.607859 -299.926649)
					(end 35.571938 -299.91177)
				)
				(arc
					(start 34.172398 -299.91177)
					(mid 34.136477 -299.926649)
					(end 34.121598 -299.96257)
				)
			)
		)
	)
	(zone
		(layers "In1.Cu" "In2.Cu")
		(hatch none 0.5)
		(connect_pads
			(clearance 0)
		)
		(min_thickness 0.25)
		(keepout
			(tracks not_allowed)
			(vias allowed)
			(pads allowed)
			(copperpour not_allowed)
			(footprints allowed)
		)
		(placement
			(enabled no)
			(sheetname "")
		)
		(fill yes
			(thermal_gap 0.5)
			(thermal_bridge_width 0.5)
			(island_removal_mode 0)
		)
		(polygon
			(pts
				(arc
					(start 207.425798 -279.9715)
					(mid 207.440677 -280.007421)
					(end 207.476598 -280.0223)
				)
				(arc
					(start 208.876138 -280.0223)
					(mid 208.912059 -280.007421)
					(end 208.926938 -279.9715)
				)
				(arc
					(start 208.926938 -279.56256)
					(mid 208.912059 -279.526639)
					(end 208.876138 -279.51176)
				)
				(arc
					(start 207.476598 -279.51176)
					(mid 207.440677 -279.526639)
					(end 207.425798 -279.56256)
				)
			)
		)
	)
	(zone
		(layers "In1.Cu" "In2.Cu")
		(hatch none 0.5)
		(connect_pads
			(clearance 0)
		)
		(min_thickness 0.25)
		(keepout
			(tracks not_allowed)
			(vias allowed)
			(pads allowed)
			(copperpour not_allowed)
			(footprints allowed)
		)
		(placement
			(enabled no)
			(sheetname "")
		)
		(fill yes
			(thermal_gap 0.5)
			(thermal_bridge_width 0.5)
			(island_removal_mode 0)
		)
		(polygon
			(pts
				(arc
					(start 282.061666 -272.321528)
					(mid 282.076545 -272.357449)
					(end 282.112466 -272.372328)
				)
				(arc
					(start 283.512006 -272.372328)
					(mid 283.547927 -272.357449)
					(end 283.562806 -272.321528)
				)
				(arc
					(start 283.562806 -271.912588)
					(mid 283.547927 -271.876667)
					(end 283.512006 -271.861788)
				)
				(arc
					(start 282.112466 -271.861788)
					(mid 282.076545 -271.876667)
					(end 282.061666 -271.912588)
				)
			)
		)
	)
	(zone
		(layers "In1.Cu" "In2.Cu")
		(hatch none 0.5)
		(connect_pads
			(clearance 0)
		)
		(min_thickness 0.25)
		(keepout
			(tracks not_allowed)
			(vias allowed)
			(pads allowed)
			(copperpour not_allowed)
			(footprints allowed)
		)
		(placement
			(enabled no)
			(sheetname "")
		)
		(fill yes
			(thermal_gap 0.5)
			(thermal_bridge_width 0.5)
			(island_removal_mode 0)
		)
		(polygon
			(pts
				(arc
					(start 60.19673 -286.771334)
					(mid 60.211609 -286.807255)
					(end 60.24753 -286.822134)
				)
				(arc
					(start 61.64707 -286.822134)
					(mid 61.682991 -286.807255)
					(end 61.69787 -286.771334)
				)
				(arc
					(start 61.69787 -286.362394)
					(mid 61.682991 -286.326473)
					(end 61.64707 -286.311594)
				)
				(arc
					(start 60.24753 -286.311594)
					(mid 60.211609 -286.326473)
					(end 60.19673 -286.362394)
				)
			)
		)
	)
	(zone
		(layers "In1.Cu" "In2.Cu")
		(hatch none 0.5)
		(connect_pads
			(clearance 0)
		)
		(min_thickness 0.25)
		(keepout
			(tracks not_allowed)
			(vias allowed)
			(pads allowed)
			(copperpour not_allowed)
			(footprints allowed)
		)
		(placement
			(enabled no)
			(sheetname "")
		)
		(fill yes
			(thermal_gap 0.5)
			(thermal_bridge_width 0.5)
			(island_removal_mode 0)
		)
		(polygon
			(pts
				(arc
					(start 432.734466 -315.671454)
					(mid 432.749345 -315.707375)
					(end 432.785266 -315.722254)
				)
				(arc
					(start 434.184806 -315.722254)
					(mid 434.220727 -315.707375)
					(end 434.235606 -315.671454)
				)
				(arc
					(start 434.235606 -315.262514)
					(mid 434.220727 -315.226593)
					(end 434.184806 -315.211714)
				)
				(arc
					(start 432.785266 -315.211714)
					(mid 432.749345 -315.226593)
					(end 432.734466 -315.262514)
				)
			)
		)
	)
	(zone
		(layers "In1.Cu" "In2.Cu")
		(hatch none 0.5)
		(connect_pads
			(clearance 0)
		)
		(min_thickness 0.25)
		(keepout
			(tracks not_allowed)
			(vias allowed)
			(pads allowed)
			(copperpour not_allowed)
			(footprints allowed)
		)
		(placement
			(enabled no)
			(sheetname "")
		)
		(fill yes
			(thermal_gap 0.5)
			(thermal_bridge_width 0.5)
			(island_removal_mode 0)
		)
		(polygon
			(pts
				(arc
					(start 293.049198 -310.571388)
					(mid 293.064077 -310.607309)
					(end 293.099998 -310.622188)
				)
				(arc
					(start 294.499538 -310.622188)
					(mid 294.535459 -310.607309)
					(end 294.550338 -310.571388)
				)
				(arc
					(start 294.550338 -310.162448)
					(mid 294.535459 -310.126527)
					(end 294.499538 -310.111648)
				)
				(arc
					(start 293.099998 -310.111648)
					(mid 293.064077 -310.126527)
					(end 293.049198 -310.162448)
				)
			)
		)
	)
	(zone
		(layers "In1.Cu" "In2.Cu")
		(hatch none 0.5)
		(connect_pads
			(clearance 0)
		)
		(min_thickness 0.25)
		(keepout
			(tracks not_allowed)
			(vias allowed)
			(pads allowed)
			(copperpour not_allowed)
			(footprints allowed)
		)
		(placement
			(enabled no)
			(sheetname "")
		)
		(fill yes
			(thermal_gap 0.5)
			(thermal_bridge_width 0.5)
			(island_removal_mode 0)
		)
		(polygon
			(pts
				(arc
					(start 451.265798 -232.371392)
					(mid 451.280677 -232.407313)
					(end 451.316598 -232.422192)
				)
				(arc
					(start 452.716138 -232.422192)
					(mid 452.752059 -232.407313)
					(end 452.766938 -232.371392)
				)
				(arc
					(start 452.766938 -231.962452)
					(mid 452.752059 -231.926531)
					(end 452.716138 -231.911652)
				)
				(arc
					(start 451.316598 -231.911652)
					(mid 451.280677 -231.926531)
					(end 451.265798 -231.962452)
				)
			)
		)
	)
	(zone
		(layers "In1.Cu" "In2.Cu")
		(hatch none 0.5)
		(connect_pads
			(clearance 0)
		)
		(min_thickness 0.25)
		(keepout
			(tracks not_allowed)
			(vias allowed)
			(pads allowed)
			(copperpour not_allowed)
			(footprints allowed)
		)
		(placement
			(enabled no)
			(sheetname "")
		)
		(fill yes
			(thermal_gap 0.5)
			(thermal_bridge_width 0.5)
			(island_removal_mode 0)
		)
		(polygon
			(pts
				(arc
					(start 308.136798 -234.071414)
					(mid 308.151677 -234.107335)
					(end 308.187598 -234.122214)
				)
				(arc
					(start 309.587138 -234.122214)
					(mid 309.623059 -234.107335)
					(end 309.637938 -234.071414)
				)
				(arc
					(start 309.637938 -233.662474)
					(mid 309.623059 -233.626553)
					(end 309.587138 -233.611674)
				)
				(arc
					(start 308.187598 -233.611674)
					(mid 308.151677 -233.626553)
					(end 308.136798 -233.662474)
				)
			)
		)
	)
	(zone
		(layers "In1.Cu" "In2.Cu")
		(hatch none 0.5)
		(connect_pads
			(clearance 0)
		)
		(min_thickness 0.25)
		(keepout
			(tracks not_allowed)
			(vias allowed)
			(pads allowed)
			(copperpour not_allowed)
			(footprints allowed)
		)
		(placement
			(enabled no)
			(sheetname "")
		)
		(fill yes
			(thermal_gap 0.5)
			(thermal_bridge_width 0.5)
			(island_removal_mode 0)
		)
		(polygon
			(pts
				(arc
					(start 14.93393 -200.921366)
					(mid 14.948809 -200.957287)
					(end 14.98473 -200.972166)
				)
				(arc
					(start 16.38427 -200.972166)
					(mid 16.420191 -200.957287)
					(end 16.43507 -200.921366)
				)
				(arc
					(start 16.43507 -200.512426)
					(mid 16.420191 -200.476505)
					(end 16.38427 -200.461626)
				)
				(arc
					(start 14.98473 -200.461626)
					(mid 14.948809 -200.476505)
					(end 14.93393 -200.512426)
				)
			)
		)
	)
	(zone
		(layers "In1.Cu" "In2.Cu")
		(hatch none 0.5)
		(connect_pads
			(clearance 0)
		)
		(min_thickness 0.25)
		(keepout
			(tracks not_allowed)
			(vias allowed)
			(pads allowed)
			(copperpour not_allowed)
			(footprints allowed)
		)
		(placement
			(enabled no)
			(sheetname "")
		)
		(fill yes
			(thermal_gap 0.5)
			(thermal_bridge_width 0.5)
			(island_removal_mode 0)
		)
		(polygon
			(pts
				(arc
					(start 49.209198 -308.021482)
					(mid 49.224077 -308.057403)
					(end 49.259998 -308.072282)
				)
				(arc
					(start 50.659538 -308.072282)
					(mid 50.695459 -308.057403)
					(end 50.710338 -308.021482)
				)
				(arc
					(start 50.710338 -307.612542)
					(mid 50.695459 -307.576621)
					(end 50.659538 -307.561742)
				)
				(arc
					(start 49.259998 -307.561742)
					(mid 49.224077 -307.576621)
					(end 49.209198 -307.612542)
				)
			)
		)
	)
	(zone
		(layers "In1.Cu" "In2.Cu")
		(hatch none 0.5)
		(connect_pads
			(clearance 0)
		)
		(min_thickness 0.25)
		(keepout
			(tracks not_allowed)
			(vias allowed)
			(pads allowed)
			(copperpour not_allowed)
			(footprints allowed)
		)
		(placement
			(enabled no)
			(sheetname "")
		)
		(fill yes
			(thermal_gap 0.5)
			(thermal_bridge_width 0.5)
			(island_removal_mode 0)
		)
		(polygon
			(pts
				(arc
					(start 64.296798 -225.571304)
					(mid 64.311677 -225.607225)
					(end 64.347598 -225.622104)
				)
				(arc
					(start 65.747138 -225.622104)
					(mid 65.783059 -225.607225)
					(end 65.797938 -225.571304)
				)
				(arc
					(start 65.797938 -225.162364)
					(mid 65.783059 -225.126443)
					(end 65.747138 -225.111564)
				)
				(arc
					(start 64.347598 -225.111564)
					(mid 64.311677 -225.126443)
					(end 64.296798 -225.162364)
				)
			)
		)
	)
	(zone
		(layers "In1.Cu" "In2.Cu")
		(hatch none 0.5)
		(connect_pads
			(clearance 0)
		)
		(min_thickness 0.25)
		(keepout
			(tracks not_allowed)
			(vias allowed)
			(pads allowed)
			(copperpour not_allowed)
			(footprints allowed)
		)
		(placement
			(enabled no)
			(sheetname "")
		)
		(fill yes
			(thermal_gap 0.5)
			(thermal_bridge_width 0.5)
			(island_removal_mode 0)
		)
		(polygon
			(pts
				(arc
					(start 26.577798 -268.921484)
					(mid 26.592677 -268.957405)
					(end 26.628598 -268.972284)
				)
				(arc
					(start 28.028138 -268.972284)
					(mid 28.064059 -268.957405)
					(end 28.078938 -268.921484)
				)
				(arc
					(start 28.078938 -268.512544)
					(mid 28.064059 -268.476623)
					(end 28.028138 -268.461744)
				)
				(arc
					(start 26.628598 -268.461744)
					(mid 26.592677 -268.476623)
					(end 26.577798 -268.512544)
				)
			)
		)
	)
	(zone
		(layers "In1.Cu" "In2.Cu")
		(hatch none 0.5)
		(connect_pads
			(clearance 0)
		)
		(min_thickness 0.25)
		(keepout
			(tracks not_allowed)
			(vias allowed)
			(pads allowed)
			(copperpour not_allowed)
			(footprints allowed)
		)
		(placement
			(enabled no)
			(sheetname "")
		)
		(fill yes
			(thermal_gap 0.5)
			(thermal_bridge_width 0.5)
			(island_removal_mode 0)
		)
		(polygon
			(pts
				(arc
					(start 428.634398 -211.971382)
					(mid 428.649277 -212.007303)
					(end 428.685198 -212.022182)
				)
				(arc
					(start 430.084738 -212.022182)
					(mid 430.120659 -212.007303)
					(end 430.135538 -211.971382)
				)
				(arc
					(start 430.135538 -211.562442)
					(mid 430.120659 -211.526521)
					(end 430.084738 -211.511642)
				)
				(arc
					(start 428.685198 -211.511642)
					(mid 428.649277 -211.526521)
					(end 428.634398 -211.562442)
				)
			)
		)
	)
	(zone
		(layers "In1.Cu" "In2.Cu")
		(hatch none 0.5)
		(connect_pads
			(clearance 0)
		)
		(min_thickness 0.25)
		(keepout
			(tracks not_allowed)
			(vias allowed)
			(pads allowed)
			(copperpour not_allowed)
			(footprints allowed)
		)
		(placement
			(enabled no)
			(sheetname "")
		)
		(fill yes
			(thermal_gap 0.5)
			(thermal_bridge_width 0.5)
			(island_removal_mode 0)
		)
		(polygon
			(pts
				(arc
					(start 60.19673 -261.271512)
					(mid 60.211609 -261.307433)
					(end 60.24753 -261.322312)
				)
				(arc
					(start 61.64707 -261.322312)
					(mid 61.682991 -261.307433)
					(end 61.69787 -261.271512)
				)
				(arc
					(start 61.69787 -260.862572)
					(mid 61.682991 -260.826651)
					(end 61.64707 -260.811772)
				)
				(arc
					(start 60.24753 -260.811772)
					(mid 60.211609 -260.826651)
					(end 60.19673 -260.862572)
				)
			)
		)
	)
	(zone
		(layers "In1.Cu" "In2.Cu")
		(hatch none 0.5)
		(connect_pads
			(clearance 0)
		)
		(min_thickness 0.25)
		(keepout
			(tracks not_allowed)
			(vias allowed)
			(pads allowed)
			(copperpour not_allowed)
			(footprints allowed)
		)
		(placement
			(enabled no)
			(sheetname "")
		)
		(fill yes
			(thermal_gap 0.5)
			(thermal_bridge_width 0.5)
			(island_removal_mode 0)
		)
		(polygon
			(pts
				(arc
					(start 165.60673 -251.07138)
					(mid 165.621609 -251.107301)
					(end 165.65753 -251.12218)
				)
				(arc
					(start 167.05707 -251.12218)
					(mid 167.092991 -251.107301)
					(end 167.10787 -251.07138)
				)
				(arc
					(start 167.10787 -250.66244)
					(mid 167.092991 -250.626519)
					(end 167.05707 -250.61164)
				)
				(arc
					(start 165.65753 -250.61164)
					(mid 165.621609 -250.626519)
					(end 165.60673 -250.66244)
				)
			)
		)
	)
	(zone
		(layers "In1.Cu" "In2.Cu")
		(hatch none 0.5)
		(connect_pads
			(clearance 0)
		)
		(min_thickness 0.25)
		(keepout
			(tracks not_allowed)
			(vias allowed)
			(pads allowed)
			(copperpour not_allowed)
			(footprints allowed)
		)
		(placement
			(enabled no)
			(sheetname "")
		)
		(fill yes
			(thermal_gap 0.5)
			(thermal_bridge_width 0.5)
			(island_removal_mode 0)
		)
		(polygon
			(pts
				(arc
					(start 304.693066 -214.521542)
					(mid 304.707945 -214.557463)
					(end 304.743866 -214.572342)
				)
				(arc
					(start 306.143406 -214.572342)
					(mid 306.179327 -214.557463)
					(end 306.194206 -214.521542)
				)
				(arc
					(start 306.194206 -214.112602)
					(mid 306.179327 -214.076681)
					(end 306.143406 -214.061802)
				)
				(arc
					(start 304.743866 -214.061802)
					(mid 304.707945 -214.076681)
					(end 304.693066 -214.112602)
				)
			)
		)
	)
	(zone
		(layers "In1.Cu" "In2.Cu")
		(hatch none 0.5)
		(connect_pads
			(clearance 0)
		)
		(min_thickness 0.25)
		(keepout
			(tracks not_allowed)
			(vias allowed)
			(pads allowed)
			(copperpour not_allowed)
			(footprints allowed)
		)
		(placement
			(enabled no)
			(sheetname "")
		)
		(fill yes
			(thermal_gap 0.5)
			(thermal_bridge_width 0.5)
			(island_removal_mode 0)
		)
		(polygon
			(pts
				(arc
					(start 255.330198 -299.521372)
					(mid 255.345077 -299.557293)
					(end 255.380998 -299.572172)
				)
				(arc
					(start 256.780538 -299.572172)
					(mid 256.816459 -299.557293)
					(end 256.831338 -299.521372)
				)
				(arc
					(start 256.831338 -299.112432)
					(mid 256.816459 -299.076511)
					(end 256.780538 -299.061632)
				)
				(arc
					(start 255.380998 -299.061632)
					(mid 255.345077 -299.076511)
					(end 255.330198 -299.112432)
				)
			)
		)
	)
	(zone
		(layers "In1.Cu" "In2.Cu")
		(hatch none 0.5)
		(connect_pads
			(clearance 0)
		)
		(min_thickness 0.25)
		(keepout
			(tracks not_allowed)
			(vias allowed)
			(pads allowed)
			(copperpour not_allowed)
			(footprints allowed)
		)
		(placement
			(enabled no)
			(sheetname "")
		)
		(fill yes
			(thermal_gap 0.5)
			(thermal_bridge_width 0.5)
			(island_removal_mode 0)
		)
		(polygon
			(pts
				(arc
					(start 14.93393 -235.771436)
					(mid 14.948809 -235.807357)
					(end 14.98473 -235.822236)
				)
				(arc
					(start 16.38427 -235.822236)
					(mid 16.420191 -235.807357)
					(end 16.43507 -235.771436)
				)
				(arc
					(start 16.43507 -235.362496)
					(mid 16.420191 -235.326575)
					(end 16.38427 -235.311696)
				)
				(arc
					(start 14.98473 -235.311696)
					(mid 14.948809 -235.326575)
					(end 14.93393 -235.362496)
				)
			)
		)
	)
	(zone
		(layers "In1.Cu" "In2.Cu")
		(hatch none 0.5)
		(connect_pads
			(clearance 0)
		)
		(min_thickness 0.25)
		(keepout
			(tracks not_allowed)
			(vias allowed)
			(pads allowed)
			(copperpour not_allowed)
			(footprints allowed)
		)
		(placement
			(enabled no)
			(sheetname "")
		)
		(fill yes
			(thermal_gap 0.5)
			(thermal_bridge_width 0.5)
			(island_removal_mode 0)
		)
		(polygon
			(pts
				(arc
					(start 34.121598 -306.32146)
					(mid 34.136477 -306.357381)
					(end 34.172398 -306.37226)
				)
				(arc
					(start 35.571938 -306.37226)
					(mid 35.607859 -306.357381)
					(end 35.622738 -306.32146)
				)
				(arc
					(start 35.622738 -305.91252)
					(mid 35.607859 -305.876599)
					(end 35.571938 -305.86172)
				)
				(arc
					(start 34.172398 -305.86172)
					(mid 34.136477 -305.876599)
					(end 34.121598 -305.91252)
				)
			)
		)
	)
	(zone
		(layers "In1.Cu" "In2.Cu")
		(hatch none 0.5)
		(connect_pads
			(clearance 0)
		)
		(min_thickness 0.25)
		(keepout
			(tracks not_allowed)
			(vias allowed)
			(pads allowed)
			(copperpour not_allowed)
			(footprints allowed)
		)
		(placement
			(enabled no)
			(sheetname "")
		)
		(fill yes
			(thermal_gap 0.5)
			(thermal_bridge_width 0.5)
			(island_removal_mode 0)
		)
		(polygon
			(pts
				(arc
					(start 210.86953 -316.521338)
					(mid 210.884409 -316.557259)
					(end 210.92033 -316.572138)
				)
				(arc
					(start 212.31987 -316.572138)
					(mid 212.355791 -316.557259)
					(end 212.37067 -316.521338)
				)
				(arc
					(start 212.37067 -316.112398)
					(mid 212.355791 -316.076477)
					(end 212.31987 -316.061598)
				)
				(arc
					(start 210.92033 -316.061598)
					(mid 210.884409 -316.076477)
					(end 210.86953 -316.112398)
				)
			)
		)
	)
	(zone
		(layers "In1.Cu" "In2.Cu")
		(hatch none 0.5)
		(connect_pads
			(clearance 0)
		)
		(min_thickness 0.25)
		(keepout
			(tracks not_allowed)
			(vias allowed)
			(pads allowed)
			(copperpour not_allowed)
			(footprints allowed)
		)
		(placement
			(enabled no)
			(sheetname "")
		)
		(fill yes
			(thermal_gap 0.5)
			(thermal_bridge_width 0.5)
			(island_removal_mode 0)
		)
		(polygon
			(pts
				(arc
					(start 11.490198 -220.471492)
					(mid 11.505077 -220.507413)
					(end 11.540998 -220.522292)
				)
				(arc
					(start 12.940538 -220.522292)
					(mid 12.976459 -220.507413)
					(end 12.991338 -220.471492)
				)
				(arc
					(start 12.991338 -220.062552)
					(mid 12.976459 -220.026631)
					(end 12.940538 -220.011752)
				)
				(arc
					(start 11.540998 -220.011752)
					(mid 11.505077 -220.026631)
					(end 11.490198 -220.062552)
				)
			)
		)
	)
	(zone
		(layers "In1.Cu" "In2.Cu")
		(hatch none 0.5)
		(connect_pads
			(clearance 0)
		)
		(min_thickness 0.25)
		(keepout
			(tracks not_allowed)
			(vias allowed)
			(pads allowed)
			(copperpour not_allowed)
			(footprints allowed)
		)
		(placement
			(enabled no)
			(sheetname "")
		)
		(fill yes
			(thermal_gap 0.5)
			(thermal_bridge_width 0.5)
			(island_removal_mode 0)
		)
		(polygon
			(pts
				(arc
					(start 432.734466 -267.221462)
					(mid 432.749345 -267.257383)
					(end 432.785266 -267.272262)
				)
				(arc
					(start 434.184806 -267.272262)
					(mid 434.220727 -267.257383)
					(end 434.235606 -267.221462)
				)
				(arc
					(start 434.235606 -266.812522)
					(mid 434.220727 -266.776601)
					(end 434.184806 -266.761722)
				)
				(arc
					(start 432.785266 -266.761722)
					(mid 432.749345 -266.776601)
					(end 432.734466 -266.812522)
				)
			)
		)
	)
	(zone
		(layers "In1.Cu" "In2.Cu")
		(hatch none 0.5)
		(connect_pads
			(clearance 0)
		)
		(min_thickness 0.25)
		(keepout
			(tracks not_allowed)
			(vias allowed)
			(pads allowed)
			(copperpour not_allowed)
			(footprints allowed)
		)
		(placement
			(enabled no)
			(sheetname "")
		)
		(fill yes
			(thermal_gap 0.5)
			(thermal_bridge_width 0.5)
			(island_removal_mode 0)
		)
		(polygon
			(pts
				(arc
					(start 417.646866 -274.871434)
					(mid 417.661745 -274.907355)
					(end 417.697666 -274.922234)
				)
				(arc
					(start 419.097206 -274.922234)
					(mid 419.133127 -274.907355)
					(end 419.148006 -274.871434)
				)
				(arc
					(start 419.148006 -274.462494)
					(mid 419.133127 -274.426573)
					(end 419.097206 -274.411694)
				)
				(arc
					(start 417.697666 -274.411694)
					(mid 417.661745 -274.426573)
					(end 417.646866 -274.462494)
				)
			)
		)
	)
	(zone
		(layers "In1.Cu" "In2.Cu")
		(hatch none 0.5)
		(connect_pads
			(clearance 0)
		)
		(min_thickness 0.25)
		(keepout
			(tracks not_allowed)
			(vias allowed)
			(pads allowed)
			(copperpour not_allowed)
			(footprints allowed)
		)
		(placement
			(enabled no)
			(sheetname "")
		)
		(fill yes
			(thermal_gap 0.5)
			(thermal_bridge_width 0.5)
			(island_removal_mode 0)
		)
		(polygon
			(pts
				(arc
					(start 428.634398 -310.571388)
					(mid 428.649277 -310.607309)
					(end 428.685198 -310.622188)
				)
				(arc
					(start 430.084738 -310.622188)
					(mid 430.120659 -310.607309)
					(end 430.135538 -310.571388)
				)
				(arc
					(start 430.135538 -310.162448)
					(mid 430.120659 -310.126527)
					(end 430.084738 -310.111648)
				)
				(arc
					(start 428.685198 -310.111648)
					(mid 428.649277 -310.126527)
					(end 428.634398 -310.162448)
				)
			)
		)
	)
	(zone
		(layers "In1.Cu" "In2.Cu")
		(hatch none 0.5)
		(connect_pads
			(clearance 0)
		)
		(min_thickness 0.25)
		(keepout
			(tracks not_allowed)
			(vias allowed)
			(pads allowed)
			(copperpour not_allowed)
			(footprints allowed)
		)
		(placement
			(enabled no)
			(sheetname "")
		)
		(fill yes
			(thermal_gap 0.5)
			(thermal_bridge_width 0.5)
			(island_removal_mode 0)
		)
		(polygon
			(pts
				(arc
					(start 22.47773 -217.071448)
					(mid 22.492609 -217.107369)
					(end 22.52853 -217.122248)
				)
				(arc
					(start 23.92807 -217.122248)
					(mid 23.963991 -217.107369)
					(end 23.97887 -217.071448)
				)
				(arc
					(start 23.97887 -216.662508)
					(mid 23.963991 -216.626587)
					(end 23.92807 -216.611708)
				)
				(arc
					(start 22.52853 -216.611708)
					(mid 22.492609 -216.626587)
					(end 22.47773 -216.662508)
				)
			)
		)
	)
	(zone
		(layers "In1.Cu" "In2.Cu")
		(hatch none 0.5)
		(connect_pads
			(clearance 0)
		)
		(min_thickness 0.25)
		(keepout
			(tracks not_allowed)
			(vias allowed)
			(pads allowed)
			(copperpour not_allowed)
			(footprints allowed)
		)
		(placement
			(enabled no)
			(sheetname "")
		)
		(fill yes
			(thermal_gap 0.5)
			(thermal_bridge_width 0.5)
			(island_removal_mode 0)
		)
		(polygon
			(pts
				(arc
					(start 297.149266 -233.22153)
					(mid 297.164145 -233.257451)
					(end 297.200066 -233.27233)
				)
				(arc
					(start 298.599606 -233.27233)
					(mid 298.635527 -233.257451)
					(end 298.650406 -233.22153)
				)
				(arc
					(start 298.650406 -232.81259)
					(mid 298.635527 -232.776669)
					(end 298.599606 -232.76179)
				)
				(arc
					(start 297.200066 -232.76179)
					(mid 297.164145 -232.776669)
					(end 297.149266 -232.81259)
				)
			)
		)
	)
	(zone
		(layers "In1.Cu" "In2.Cu")
		(hatch none 0.5)
		(connect_pads
			(clearance 0)
		)
		(min_thickness 0.25)
		(keepout
			(tracks not_allowed)
			(vias allowed)
			(pads allowed)
			(copperpour not_allowed)
			(footprints allowed)
		)
		(placement
			(enabled no)
			(sheetname "")
		)
		(fill yes
			(thermal_gap 0.5)
			(thermal_bridge_width 0.5)
			(island_removal_mode 0)
		)
		(polygon
			(pts
				(arc
					(start 41.665398 -218.77147)
					(mid 41.680277 -218.807391)
					(end 41.716198 -218.82227)
				)
				(arc
					(start 43.115738 -218.82227)
					(mid 43.151659 -218.807391)
					(end 43.166538 -218.77147)
				)
				(arc
					(start 43.166538 -218.36253)
					(mid 43.151659 -218.326609)
					(end 43.115738 -218.31173)
				)
				(arc
					(start 41.716198 -218.31173)
					(mid 41.680277 -218.326609)
					(end 41.665398 -218.36253)
				)
			)
		)
	)
	(zone
		(layers "In1.Cu" "In2.Cu")
		(hatch none 0.5)
		(connect_pads
			(clearance 0)
		)
		(min_thickness 0.25)
		(keepout
			(tracks not_allowed)
			(vias allowed)
			(pads allowed)
			(copperpour not_allowed)
			(footprints allowed)
		)
		(placement
			(enabled no)
			(sheetname "")
		)
		(fill yes
			(thermal_gap 0.5)
			(thermal_bridge_width 0.5)
			(island_removal_mode 0)
		)
		(polygon
			(pts
				(arc
					(start 293.049198 -259.57149)
					(mid 293.064077 -259.607411)
					(end 293.099998 -259.62229)
				)
				(arc
					(start 294.499538 -259.62229)
					(mid 294.535459 -259.607411)
					(end 294.550338 -259.57149)
				)
				(arc
					(start 294.550338 -259.16255)
					(mid 294.535459 -259.126629)
					(end 294.499538 -259.11175)
				)
				(arc
					(start 293.099998 -259.11175)
					(mid 293.064077 -259.126629)
					(end 293.049198 -259.16255)
				)
			)
		)
	)
	(zone
		(layers "In1.Cu" "In2.Cu")
		(hatch none 0.5)
		(connect_pads
			(clearance 0)
		)
		(min_thickness 0.25)
		(keepout
			(tracks not_allowed)
			(vias allowed)
			(pads allowed)
			(copperpour not_allowed)
			(footprints allowed)
		)
		(placement
			(enabled no)
			(sheetname "")
		)
		(fill yes
			(thermal_gap 0.5)
			(thermal_bridge_width 0.5)
			(island_removal_mode 0)
		)
		(polygon
			(pts
				(arc
					(start 410.103066 -228.121464)
					(mid 410.117945 -228.157385)
					(end 410.153866 -228.172264)
				)
				(arc
					(start 411.553406 -228.172264)
					(mid 411.589327 -228.157385)
					(end 411.604206 -228.121464)
				)
				(arc
					(start 411.604206 -227.712524)
					(mid 411.589327 -227.676603)
					(end 411.553406 -227.661724)
				)
				(arc
					(start 410.153866 -227.661724)
					(mid 410.117945 -227.676603)
					(end 410.103066 -227.712524)
				)
			)
		)
	)
	(zone
		(layers "In1.Cu" "In2.Cu")
		(hatch none 0.5)
		(connect_pads
			(clearance 0)
		)
		(min_thickness 0.25)
		(keepout
			(tracks not_allowed)
			(vias allowed)
			(pads allowed)
			(copperpour not_allowed)
			(footprints allowed)
		)
		(placement
			(enabled no)
			(sheetname "")
		)
		(fill yes
			(thermal_gap 0.5)
			(thermal_bridge_width 0.5)
			(island_removal_mode 0)
		)
		(polygon
			(pts
				(arc
					(start 451.265798 -308.871366)
					(mid 451.280677 -308.907287)
					(end 451.316598 -308.922166)
				)
				(arc
					(start 452.716138 -308.922166)
					(mid 452.752059 -308.907287)
					(end 452.766938 -308.871366)
				)
				(arc
					(start 452.766938 -308.462426)
					(mid 452.752059 -308.426505)
					(end 452.716138 -308.411626)
				)
				(arc
					(start 451.316598 -308.411626)
					(mid 451.280677 -308.426505)
					(end 451.265798 -308.462426)
				)
			)
		)
	)
	(zone
		(layers "In1.Cu" "In2.Cu")
		(hatch none 0.5)
		(connect_pads
			(clearance 0)
		)
		(min_thickness 0.25)
		(keepout
			(tracks not_allowed)
			(vias allowed)
			(pads allowed)
			(copperpour not_allowed)
			(footprints allowed)
		)
		(placement
			(enabled no)
			(sheetname "")
		)
		(fill yes
			(thermal_gap 0.5)
			(thermal_bridge_width 0.5)
			(island_removal_mode 0)
		)
		(polygon
			(pts
				(arc
					(start 26.577798 -223.871536)
					(mid 26.592677 -223.907457)
					(end 26.628598 -223.922336)
				)
				(arc
					(start 28.028138 -223.922336)
					(mid 28.064059 -223.907457)
					(end 28.078938 -223.871536)
				)
				(arc
					(start 28.078938 -223.462596)
					(mid 28.064059 -223.426675)
					(end 28.028138 -223.411796)
				)
				(arc
					(start 26.628598 -223.411796)
					(mid 26.592677 -223.426675)
					(end 26.577798 -223.462596)
				)
			)
		)
	)
	(zone
		(layers "In1.Cu" "In2.Cu")
		(hatch none 0.5)
		(connect_pads
			(clearance 0)
		)
		(min_thickness 0.25)
		(keepout
			(tracks not_allowed)
			(vias allowed)
			(pads allowed)
			(copperpour not_allowed)
			(footprints allowed)
		)
		(placement
			(enabled no)
			(sheetname "")
		)
		(fill yes
			(thermal_gap 0.5)
			(thermal_bridge_width 0.5)
			(island_removal_mode 0)
		)
		(polygon
			(pts
				(arc
					(start 277.961598 -285.071312)
					(mid 277.976477 -285.107233)
					(end 278.012398 -285.122112)
				)
				(arc
					(start 279.411938 -285.122112)
					(mid 279.447859 -285.107233)
					(end 279.462738 -285.071312)
				)
				(arc
					(start 279.462738 -284.662372)
					(mid 279.447859 -284.626451)
					(end 279.411938 -284.611572)
				)
				(arc
					(start 278.012398 -284.611572)
					(mid 277.976477 -284.626451)
					(end 277.961598 -284.662372)
				)
			)
		)
	)
	(zone
		(layers "In1.Cu" "In2.Cu")
		(hatch none 0.5)
		(connect_pads
			(clearance 0)
		)
		(min_thickness 0.25)
		(keepout
			(tracks not_allowed)
			(vias allowed)
			(pads allowed)
			(copperpour not_allowed)
			(footprints allowed)
		)
		(placement
			(enabled no)
			(sheetname "")
		)
		(fill yes
			(thermal_gap 0.5)
			(thermal_bridge_width 0.5)
			(island_removal_mode 0)
		)
		(polygon
			(pts
				(arc
					(start 312.236866 -233.22153)
					(mid 312.251745 -233.257451)
					(end 312.287666 -233.27233)
				)
				(arc
					(start 313.687206 -233.27233)
					(mid 313.723127 -233.257451)
					(end 313.738006 -233.22153)
				)
				(arc
					(start 313.738006 -232.81259)
					(mid 313.723127 -232.776669)
					(end 313.687206 -232.76179)
				)
				(arc
					(start 312.287666 -232.76179)
					(mid 312.251745 -232.776669)
					(end 312.236866 -232.81259)
				)
			)
		)
	)
	(zone
		(layers "In1.Cu" "In2.Cu")
		(hatch none 0.5)
		(connect_pads
			(clearance 0)
		)
		(min_thickness 0.25)
		(keepout
			(tracks not_allowed)
			(vias allowed)
			(pads allowed)
			(copperpour not_allowed)
			(footprints allowed)
		)
		(placement
			(enabled no)
			(sheetname "")
		)
		(fill yes
			(thermal_gap 0.5)
			(thermal_bridge_width 0.5)
			(island_removal_mode 0)
		)
		(polygon
			(pts
				(arc
					(start 289.605466 -245.12143)
					(mid 289.620345 -245.157351)
					(end 289.656266 -245.17223)
				)
				(arc
					(start 291.055806 -245.17223)
					(mid 291.091727 -245.157351)
					(end 291.106606 -245.12143)
				)
				(arc
					(start 291.106606 -244.71249)
					(mid 291.091727 -244.676569)
					(end 291.055806 -244.66169)
				)
				(arc
					(start 289.656266 -244.66169)
					(mid 289.620345 -244.676569)
					(end 289.605466 -244.71249)
				)
			)
		)
	)
	(zone
		(layers "In1.Cu" "In2.Cu")
		(hatch none 0.5)
		(connect_pads
			(clearance 0)
		)
		(min_thickness 0.25)
		(keepout
			(tracks not_allowed)
			(vias allowed)
			(pads allowed)
			(copperpour not_allowed)
			(footprints allowed)
		)
		(placement
			(enabled no)
			(sheetname "")
		)
		(fill yes
			(thermal_gap 0.5)
			(thermal_bridge_width 0.5)
			(island_removal_mode 0)
		)
		(polygon
			(pts
				(arc
					(start 60.19673 -282.521406)
					(mid 60.211609 -282.557327)
					(end 60.24753 -282.572206)
				)
				(arc
					(start 61.64707 -282.572206)
					(mid 61.682991 -282.557327)
					(end 61.69787 -282.521406)
				)
				(arc
					(start 61.69787 -282.112466)
					(mid 61.682991 -282.076545)
					(end 61.64707 -282.061666)
				)
				(arc
					(start 60.24753 -282.061666)
					(mid 60.211609 -282.076545)
					(end 60.19673 -282.112466)
				)
			)
		)
	)
	(zone
		(layers "In1.Cu" "In2.Cu")
		(hatch none 0.5)
		(connect_pads
			(clearance 0)
		)
		(min_thickness 0.25)
		(keepout
			(tracks not_allowed)
			(vias allowed)
			(pads allowed)
			(copperpour not_allowed)
			(footprints allowed)
		)
		(placement
			(enabled no)
			(sheetname "")
		)
		(fill yes
			(thermal_gap 0.5)
			(thermal_bridge_width 0.5)
			(island_removal_mode 0)
		)
		(polygon
			(pts
				(arc
					(start 45.10913 -223.021398)
					(mid 45.124009 -223.057319)
					(end 45.15993 -223.072198)
				)
				(arc
					(start 46.55947 -223.072198)
					(mid 46.595391 -223.057319)
					(end 46.61027 -223.021398)
				)
				(arc
					(start 46.61027 -222.612458)
					(mid 46.595391 -222.576537)
					(end 46.55947 -222.561658)
				)
				(arc
					(start 45.15993 -222.561658)
					(mid 45.124009 -222.576537)
					(end 45.10913 -222.612458)
				)
			)
		)
	)
	(zone
		(layers "In1.Cu" "In2.Cu")
		(hatch none 0.5)
		(connect_pads
			(clearance 0)
		)
		(min_thickness 0.25)
		(keepout
			(tracks not_allowed)
			(vias allowed)
			(pads allowed)
			(copperpour not_allowed)
			(footprints allowed)
		)
		(placement
			(enabled no)
			(sheetname "")
		)
		(fill yes
			(thermal_gap 0.5)
			(thermal_bridge_width 0.5)
			(island_removal_mode 0)
		)
		(polygon
			(pts
				(arc
					(start 162.162998 -211.121498)
					(mid 162.177877 -211.157419)
					(end 162.213798 -211.172298)
				)
				(arc
					(start 163.613338 -211.172298)
					(mid 163.649259 -211.157419)
					(end 163.664138 -211.121498)
				)
				(arc
					(start 163.664138 -210.712558)
					(mid 163.649259 -210.676637)
					(end 163.613338 -210.661758)
				)
				(arc
					(start 162.213798 -210.661758)
					(mid 162.177877 -210.676637)
					(end 162.162998 -210.712558)
				)
			)
		)
	)
	(zone
		(layers "In1.Cu" "In2.Cu")
		(hatch none 0.5)
		(connect_pads
			(clearance 0)
		)
		(min_thickness 0.25)
		(keepout
			(tracks not_allowed)
			(vias allowed)
			(pads allowed)
			(copperpour not_allowed)
			(footprints allowed)
		)
		(placement
			(enabled no)
			(sheetname "")
		)
		(fill yes
			(thermal_gap 0.5)
			(thermal_bridge_width 0.5)
			(island_removal_mode 0)
		)
		(polygon
			(pts
				(arc
					(start 173.15053 -213.671404)
					(mid 173.165409 -213.707325)
					(end 173.20133 -213.722204)
				)
				(arc
					(start 174.60087 -213.722204)
					(mid 174.636791 -213.707325)
					(end 174.65167 -213.671404)
				)
				(arc
					(start 174.65167 -213.262464)
					(mid 174.636791 -213.226543)
					(end 174.60087 -213.211664)
				)
				(arc
					(start 173.20133 -213.211664)
					(mid 173.165409 -213.226543)
					(end 173.15053 -213.262464)
				)
			)
		)
	)
	(zone
		(layers "In1.Cu" "In2.Cu")
		(hatch none 0.5)
		(connect_pads
			(clearance 0)
		)
		(min_thickness 0.25)
		(keepout
			(tracks not_allowed)
			(vias allowed)
			(pads allowed)
			(copperpour not_allowed)
			(footprints allowed)
		)
		(placement
			(enabled no)
			(sheetname "")
		)
		(fill yes
			(thermal_gap 0.5)
			(thermal_bridge_width 0.5)
			(island_removal_mode 0)
		)
		(polygon
			(pts
				(arc
					(start 60.19673 -297.82135)
					(mid 60.211609 -297.857271)
					(end 60.24753 -297.87215)
				)
				(arc
					(start 61.64707 -297.87215)
					(mid 61.682991 -297.857271)
					(end 61.69787 -297.82135)
				)
				(arc
					(start 61.69787 -297.41241)
					(mid 61.682991 -297.376489)
					(end 61.64707 -297.36161)
				)
				(arc
					(start 60.24753 -297.36161)
					(mid 60.211609 -297.376489)
					(end 60.19673 -297.41241)
				)
			)
		)
	)
	(zone
		(layers "In1.Cu" "In2.Cu")
		(hatch none 0.5)
		(connect_pads
			(clearance 0)
		)
		(min_thickness 0.25)
		(keepout
			(tracks not_allowed)
			(vias allowed)
			(pads allowed)
			(copperpour not_allowed)
			(footprints allowed)
		)
		(placement
			(enabled no)
			(sheetname "")
		)
		(fill yes
			(thermal_gap 0.5)
			(thermal_bridge_width 0.5)
			(island_removal_mode 0)
		)
		(polygon
			(pts
				(arc
					(start 37.56533 -277.42134)
					(mid 37.580209 -277.457261)
					(end 37.61613 -277.47214)
				)
				(arc
					(start 39.01567 -277.47214)
					(mid 39.051591 -277.457261)
					(end 39.06647 -277.42134)
				)
				(arc
					(start 39.06647 -277.0124)
					(mid 39.051591 -276.976479)
					(end 39.01567 -276.9616)
				)
				(arc
					(start 37.61613 -276.9616)
					(mid 37.580209 -276.976479)
					(end 37.56533 -277.0124)
				)
			)
		)
	)
	(zone
		(layers "In1.Cu" "In2.Cu")
		(hatch none 0.5)
		(connect_pads
			(clearance 0)
		)
		(min_thickness 0.25)
		(keepout
			(tracks not_allowed)
			(vias allowed)
			(pads allowed)
			(copperpour not_allowed)
			(footprints allowed)
		)
		(placement
			(enabled no)
			(sheetname "")
		)
		(fill yes
			(thermal_gap 0.5)
			(thermal_bridge_width 0.5)
			(island_removal_mode 0)
		)
		(polygon
			(pts
				(arc
					(start 432.734466 -312.27141)
					(mid 432.749345 -312.307331)
					(end 432.785266 -312.32221)
				)
				(arc
					(start 434.184806 -312.32221)
					(mid 434.220727 -312.307331)
					(end 434.235606 -312.27141)
				)
				(arc
					(start 434.235606 -311.86247)
					(mid 434.220727 -311.826549)
					(end 434.184806 -311.81167)
				)
				(arc
					(start 432.785266 -311.81167)
					(mid 432.749345 -311.826549)
					(end 432.734466 -311.86247)
				)
			)
		)
	)
	(zone
		(layers "In1.Cu" "In2.Cu")
		(hatch none 0.5)
		(connect_pads
			(clearance 0)
		)
		(min_thickness 0.25)
		(keepout
			(tracks not_allowed)
			(vias allowed)
			(pads allowed)
			(copperpour not_allowed)
			(footprints allowed)
		)
		(placement
			(enabled no)
			(sheetname "")
		)
		(fill yes
			(thermal_gap 0.5)
			(thermal_bridge_width 0.5)
			(island_removal_mode 0)
		)
		(polygon
			(pts
				(arc
					(start 184.794398 -212.82152)
					(mid 184.809277 -212.857441)
					(end 184.845198 -212.87232)
				)
				(arc
					(start 186.244738 -212.87232)
					(mid 186.280659 -212.857441)
					(end 186.295538 -212.82152)
				)
				(arc
					(start 186.295538 -212.41258)
					(mid 186.280659 -212.376659)
					(end 186.244738 -212.36178)
				)
				(arc
					(start 184.845198 -212.36178)
					(mid 184.809277 -212.376659)
					(end 184.794398 -212.41258)
				)
			)
		)
	)
	(zone
		(layers "In1.Cu" "In2.Cu")
		(hatch none 0.5)
		(connect_pads
			(clearance 0)
		)
		(min_thickness 0.25)
		(keepout
			(tracks not_allowed)
			(vias allowed)
			(pads allowed)
			(copperpour not_allowed)
			(footprints allowed)
		)
		(placement
			(enabled no)
			(sheetname "")
		)
		(fill yes
			(thermal_gap 0.5)
			(thermal_bridge_width 0.5)
			(island_removal_mode 0)
		)
		(polygon
			(pts
				(arc
					(start 421.090598 -249.371358)
					(mid 421.105477 -249.407279)
					(end 421.141398 -249.422158)
				)
				(arc
					(start 422.540938 -249.422158)
					(mid 422.576859 -249.407279)
					(end 422.591738 -249.371358)
				)
				(arc
					(start 422.591738 -248.962418)
					(mid 422.576859 -248.926497)
					(end 422.540938 -248.911618)
				)
				(arc
					(start 421.141398 -248.911618)
					(mid 421.105477 -248.926497)
					(end 421.090598 -248.962418)
				)
			)
		)
	)
	(zone
		(layers "In1.Cu" "In2.Cu")
		(hatch none 0.5)
		(connect_pads
			(clearance 0)
		)
		(min_thickness 0.25)
		(keepout
			(tracks not_allowed)
			(vias allowed)
			(pads allowed)
			(copperpour not_allowed)
			(footprints allowed)
		)
		(placement
			(enabled no)
			(sheetname "")
		)
		(fill yes
			(thermal_gap 0.5)
			(thermal_bridge_width 0.5)
			(island_removal_mode 0)
		)
		(polygon
			(pts
				(arc
					(start 210.86953 -259.57149)
					(mid 210.884409 -259.607411)
					(end 210.92033 -259.62229)
				)
				(arc
					(start 212.31987 -259.62229)
					(mid 212.355791 -259.607411)
					(end 212.37067 -259.57149)
				)
				(arc
					(start 212.37067 -259.16255)
					(mid 212.355791 -259.126629)
					(end 212.31987 -259.11175)
				)
				(arc
					(start 210.92033 -259.11175)
					(mid 210.884409 -259.126629)
					(end 210.86953 -259.16255)
				)
			)
		)
	)
	(zone
		(layers "In1.Cu" "In2.Cu")
		(hatch none 0.5)
		(connect_pads
			(clearance 0)
		)
		(min_thickness 0.25)
		(keepout
			(tracks not_allowed)
			(vias allowed)
			(pads allowed)
			(copperpour not_allowed)
			(footprints allowed)
		)
		(placement
			(enabled no)
			(sheetname "")
		)
		(fill yes
			(thermal_gap 0.5)
			(thermal_bridge_width 0.5)
			(island_removal_mode 0)
		)
		(polygon
			(pts
				(arc
					(start 255.330198 -237.471458)
					(mid 255.345077 -237.507379)
					(end 255.380998 -237.522258)
				)
				(arc
					(start 256.780538 -237.522258)
					(mid 256.816459 -237.507379)
					(end 256.831338 -237.471458)
				)
				(arc
					(start 256.831338 -237.062518)
					(mid 256.816459 -237.026597)
					(end 256.780538 -237.011718)
				)
				(arc
					(start 255.380998 -237.011718)
					(mid 255.345077 -237.026597)
					(end 255.330198 -237.062518)
				)
			)
		)
	)
	(zone
		(layers "In1.Cu" "In2.Cu")
		(hatch none 0.5)
		(connect_pads
			(clearance 0)
		)
		(min_thickness 0.25)
		(keepout
			(tracks not_allowed)
			(vias allowed)
			(pads allowed)
			(copperpour not_allowed)
			(footprints allowed)
		)
		(placement
			(enabled no)
			(sheetname "")
		)
		(fill yes
			(thermal_gap 0.5)
			(thermal_bridge_width 0.5)
			(island_removal_mode 0)
		)
		(polygon
			(pts
				(arc
					(start 45.10913 -290.171378)
					(mid 45.124009 -290.207299)
					(end 45.15993 -290.222178)
				)
				(arc
					(start 46.55947 -290.222178)
					(mid 46.595391 -290.207299)
					(end 46.61027 -290.171378)
				)
				(arc
					(start 46.61027 -289.762438)
					(mid 46.595391 -289.726517)
					(end 46.55947 -289.711638)
				)
				(arc
					(start 45.15993 -289.711638)
					(mid 45.124009 -289.726517)
					(end 45.10913 -289.762438)
				)
			)
		)
	)
	(zone
		(layers "In1.Cu" "In2.Cu")
		(hatch none 0.5)
		(connect_pads
			(clearance 0)
		)
		(min_thickness 0.25)
		(keepout
			(tracks not_allowed)
			(vias allowed)
			(pads allowed)
			(copperpour not_allowed)
			(footprints allowed)
		)
		(placement
			(enabled no)
			(sheetname "")
		)
		(fill yes
			(thermal_gap 0.5)
			(thermal_bridge_width 0.5)
			(island_removal_mode 0)
		)
		(polygon
			(pts
				(arc
					(start 274.517866 -209.421476)
					(mid 274.532745 -209.457397)
					(end 274.568666 -209.472276)
				)
				(arc
					(start 275.968206 -209.472276)
					(mid 276.004127 -209.457397)
					(end 276.019006 -209.421476)
				)
				(arc
					(start 276.019006 -209.012536)
					(mid 276.004127 -208.976615)
					(end 275.968206 -208.961736)
				)
				(arc
					(start 274.568666 -208.961736)
					(mid 274.532745 -208.976615)
					(end 274.517866 -209.012536)
				)
			)
		)
	)
	(zone
		(layers "In1.Cu" "In2.Cu")
		(hatch none 0.5)
		(connect_pads
			(clearance 0)
		)
		(min_thickness 0.25)
		(keepout
			(tracks not_allowed)
			(vias allowed)
			(pads allowed)
			(copperpour not_allowed)
			(footprints allowed)
		)
		(placement
			(enabled no)
			(sheetname "")
		)
		(fill yes
			(thermal_gap 0.5)
			(thermal_bridge_width 0.5)
			(island_removal_mode 0)
		)
		(polygon
			(pts
				(arc
					(start 421.090598 -264.671302)
					(mid 421.105477 -264.707223)
					(end 421.141398 -264.722102)
				)
				(arc
					(start 422.540938 -264.722102)
					(mid 422.576859 -264.707223)
					(end 422.591738 -264.671302)
				)
				(arc
					(start 422.591738 -264.262362)
					(mid 422.576859 -264.226441)
					(end 422.540938 -264.211562)
				)
				(arc
					(start 421.141398 -264.211562)
					(mid 421.105477 -264.226441)
					(end 421.090598 -264.262362)
				)
			)
		)
	)
	(zone
		(layers "In1.Cu" "In2.Cu")
		(hatch none 0.5)
		(connect_pads
			(clearance 0)
		)
		(min_thickness 0.25)
		(keepout
			(tracks not_allowed)
			(vias allowed)
			(pads allowed)
			(copperpour not_allowed)
			(footprints allowed)
		)
		(placement
			(enabled no)
			(sheetname "")
		)
		(fill yes
			(thermal_gap 0.5)
			(thermal_bridge_width 0.5)
			(island_removal_mode 0)
		)
		(polygon
			(pts
				(arc
					(start 274.517866 -240.871502)
					(mid 274.532745 -240.907423)
					(end 274.568666 -240.922302)
				)
				(arc
					(start 275.968206 -240.922302)
					(mid 276.004127 -240.907423)
					(end 276.019006 -240.871502)
				)
				(arc
					(start 276.019006 -240.462562)
					(mid 276.004127 -240.426641)
					(end 275.968206 -240.411762)
				)
				(arc
					(start 274.568666 -240.411762)
					(mid 274.532745 -240.426641)
					(end 274.517866 -240.462562)
				)
			)
		)
	)
	(zone
		(layers "In1.Cu" "In2.Cu")
		(hatch none 0.5)
		(connect_pads
			(clearance 0)
		)
		(min_thickness 0.25)
		(keepout
			(tracks not_allowed)
			(vias allowed)
			(pads allowed)
			(copperpour not_allowed)
			(footprints allowed)
		)
		(placement
			(enabled no)
			(sheetname "")
		)
		(fill yes
			(thermal_gap 0.5)
			(thermal_bridge_width 0.5)
			(island_removal_mode 0)
		)
		(polygon
			(pts
				(arc
					(start 436.178198 -316.521338)
					(mid 436.193077 -316.557259)
					(end 436.228998 -316.572138)
				)
				(arc
					(start 437.628538 -316.572138)
					(mid 437.664459 -316.557259)
					(end 437.679338 -316.521338)
				)
				(arc
					(start 437.679338 -316.112398)
					(mid 437.664459 -316.076477)
					(end 437.628538 -316.061598)
				)
				(arc
					(start 436.228998 -316.061598)
					(mid 436.193077 -316.076477)
					(end 436.178198 -316.112398)
				)
			)
		)
	)
	(zone
		(layers "In1.Cu" "In2.Cu")
		(hatch none 0.5)
		(connect_pads
			(clearance 0)
		)
		(min_thickness 0.25)
		(keepout
			(tracks not_allowed)
			(vias allowed)
			(pads allowed)
			(copperpour not_allowed)
			(footprints allowed)
		)
		(placement
			(enabled no)
			(sheetname "")
		)
		(fill yes
			(thermal_gap 0.5)
			(thermal_bridge_width 0.5)
			(island_removal_mode 0)
		)
		(polygon
			(pts
				(arc
					(start 277.961598 -286.771334)
					(mid 277.976477 -286.807255)
					(end 278.012398 -286.822134)
				)
				(arc
					(start 279.411938 -286.822134)
					(mid 279.447859 -286.807255)
					(end 279.462738 -286.771334)
				)
				(arc
					(start 279.462738 -286.362394)
					(mid 279.447859 -286.326473)
					(end 279.411938 -286.311594)
				)
				(arc
					(start 278.012398 -286.311594)
					(mid 277.976477 -286.326473)
					(end 277.961598 -286.362394)
				)
			)
		)
	)
	(zone
		(layers "In1.Cu" "In2.Cu")
		(hatch none 0.5)
		(connect_pads
			(clearance 0)
		)
		(min_thickness 0.25)
		(keepout
			(tracks not_allowed)
			(vias allowed)
			(pads allowed)
			(copperpour not_allowed)
			(footprints allowed)
		)
		(placement
			(enabled no)
			(sheetname "")
		)
		(fill yes
			(thermal_gap 0.5)
			(thermal_bridge_width 0.5)
			(island_removal_mode 0)
		)
		(polygon
			(pts
				(arc
					(start 462.909666 -217.921332)
					(mid 462.924545 -217.957253)
					(end 462.960466 -217.972132)
				)
				(arc
					(start 464.360006 -217.972132)
					(mid 464.395927 -217.957253)
					(end 464.410806 -217.921332)
				)
				(arc
					(start 464.410806 -217.512392)
					(mid 464.395927 -217.476471)
					(end 464.360006 -217.461592)
				)
				(arc
					(start 462.960466 -217.461592)
					(mid 462.924545 -217.476471)
					(end 462.909666 -217.512392)
				)
			)
		)
	)
	(zone
		(layers "In1.Cu" "In2.Cu")
		(hatch none 0.5)
		(connect_pads
			(clearance 0)
		)
		(min_thickness 0.25)
		(keepout
			(tracks not_allowed)
			(vias allowed)
			(pads allowed)
			(copperpour not_allowed)
			(footprints allowed)
		)
		(placement
			(enabled no)
			(sheetname "")
		)
		(fill yes
			(thermal_gap 0.5)
			(thermal_bridge_width 0.5)
			(island_removal_mode 0)
		)
		(polygon
			(pts
				(arc
					(start 173.15053 -314.821316)
					(mid 173.165409 -314.857237)
					(end 173.20133 -314.872116)
				)
				(arc
					(start 174.60087 -314.872116)
					(mid 174.636791 -314.857237)
					(end 174.65167 -314.821316)
				)
				(arc
					(start 174.65167 -314.412376)
					(mid 174.636791 -314.376455)
					(end 174.60087 -314.361576)
				)
				(arc
					(start 173.20133 -314.361576)
					(mid 173.165409 -314.376455)
					(end 173.15053 -314.412376)
				)
			)
		)
	)
	(zone
		(layers "In1.Cu" "In2.Cu")
		(hatch none 0.5)
		(connect_pads
			(clearance 0)
		)
		(min_thickness 0.25)
		(keepout
			(tracks not_allowed)
			(vias allowed)
			(pads allowed)
			(copperpour not_allowed)
			(footprints allowed)
		)
		(placement
			(enabled no)
			(sheetname "")
		)
		(fill yes
			(thermal_gap 0.5)
			(thermal_bridge_width 0.5)
			(island_removal_mode 0)
		)
		(polygon
			(pts
				(arc
					(start 443.721998 -286.771334)
					(mid 443.736877 -286.807255)
					(end 443.772798 -286.822134)
				)
				(arc
					(start 445.172338 -286.822134)
					(mid 445.208259 -286.807255)
					(end 445.223138 -286.771334)
				)
				(arc
					(start 445.223138 -286.362394)
					(mid 445.208259 -286.326473)
					(end 445.172338 -286.311594)
				)
				(arc
					(start 443.772798 -286.311594)
					(mid 443.736877 -286.326473)
					(end 443.721998 -286.362394)
				)
			)
		)
	)
	(zone
		(layers "In1.Cu" "In2.Cu")
		(hatch none 0.5)
		(connect_pads
			(clearance 0)
		)
		(min_thickness 0.25)
		(keepout
			(tracks not_allowed)
			(vias allowed)
			(pads allowed)
			(copperpour not_allowed)
			(footprints allowed)
		)
		(placement
			(enabled no)
			(sheetname "")
		)
		(fill yes
			(thermal_gap 0.5)
			(thermal_bridge_width 0.5)
			(island_removal_mode 0)
		)
		(polygon
			(pts
				(arc
					(start 262.873998 -243.421408)
					(mid 262.888877 -243.457329)
					(end 262.924798 -243.472208)
				)
				(arc
					(start 264.324338 -243.472208)
					(mid 264.360259 -243.457329)
					(end 264.375138 -243.421408)
				)
				(arc
					(start 264.375138 -243.012468)
					(mid 264.360259 -242.976547)
					(end 264.324338 -242.961668)
				)
				(arc
					(start 262.924798 -242.961668)
					(mid 262.888877 -242.976547)
					(end 262.873998 -243.012468)
				)
			)
		)
	)
	(zone
		(layers "In1.Cu" "In2.Cu")
		(hatch none 0.5)
		(connect_pads
			(clearance 0)
		)
		(min_thickness 0.25)
		(keepout
			(tracks not_allowed)
			(vias allowed)
			(pads allowed)
			(copperpour not_allowed)
			(footprints allowed)
		)
		(placement
			(enabled no)
			(sheetname "")
		)
		(fill yes
			(thermal_gap 0.5)
			(thermal_bridge_width 0.5)
			(island_removal_mode 0)
		)
		(polygon
			(pts
				(arc
					(start 304.693066 -293.571422)
					(mid 304.707945 -293.607343)
					(end 304.743866 -293.622222)
				)
				(arc
					(start 306.143406 -293.622222)
					(mid 306.179327 -293.607343)
					(end 306.194206 -293.571422)
				)
				(arc
					(start 306.194206 -293.162482)
					(mid 306.179327 -293.126561)
					(end 306.143406 -293.111682)
				)
				(arc
					(start 304.743866 -293.111682)
					(mid 304.707945 -293.126561)
					(end 304.693066 -293.162482)
				)
			)
		)
	)
	(zone
		(layers "In1.Cu" "In2.Cu")
		(hatch none 0.5)
		(connect_pads
			(clearance 0)
		)
		(min_thickness 0.25)
		(keepout
			(tracks not_allowed)
			(vias allowed)
			(pads allowed)
			(copperpour not_allowed)
			(footprints allowed)
		)
		(placement
			(enabled no)
			(sheetname "")
		)
		(fill yes
			(thermal_gap 0.5)
			(thermal_bridge_width 0.5)
			(island_removal_mode 0)
		)
		(polygon
			(pts
				(arc
					(start 255.330198 -226.421442)
					(mid 255.345077 -226.457363)
					(end 255.380998 -226.472242)
				)
				(arc
					(start 256.780538 -226.472242)
					(mid 256.816459 -226.457363)
					(end 256.831338 -226.421442)
				)
				(arc
					(start 256.831338 -226.012502)
					(mid 256.816459 -225.976581)
					(end 256.780538 -225.961702)
				)
				(arc
					(start 255.380998 -225.961702)
					(mid 255.345077 -225.976581)
					(end 255.330198 -226.012502)
				)
			)
		)
	)
	(zone
		(layers "In1.Cu" "In2.Cu")
		(hatch none 0.5)
		(connect_pads
			(clearance 0)
		)
		(min_thickness 0.25)
		(keepout
			(tracks not_allowed)
			(vias allowed)
			(pads allowed)
			(copperpour not_allowed)
			(footprints allowed)
		)
		(placement
			(enabled no)
			(sheetname "")
		)
		(fill yes
			(thermal_gap 0.5)
			(thermal_bridge_width 0.5)
			(island_removal_mode 0)
		)
		(polygon
			(pts
				(arc
					(start 458.809598 -305.471322)
					(mid 458.824477 -305.507243)
					(end 458.860398 -305.522122)
				)
				(arc
					(start 460.259938 -305.522122)
					(mid 460.295859 -305.507243)
					(end 460.310738 -305.471322)
				)
				(arc
					(start 460.310738 -305.062382)
					(mid 460.295859 -305.026461)
					(end 460.259938 -305.011582)
				)
				(arc
					(start 458.860398 -305.011582)
					(mid 458.824477 -305.026461)
					(end 458.809598 -305.062382)
				)
			)
		)
	)
	(zone
		(layers "In1.Cu" "In2.Cu")
		(hatch none 0.5)
		(connect_pads
			(clearance 0)
		)
		(min_thickness 0.25)
		(keepout
			(tracks not_allowed)
			(vias allowed)
			(pads allowed)
			(copperpour not_allowed)
			(footprints allowed)
		)
		(placement
			(enabled no)
			(sheetname "")
		)
		(fill yes
			(thermal_gap 0.5)
			(thermal_bridge_width 0.5)
			(island_removal_mode 0)
		)
		(polygon
			(pts
				(arc
					(start 413.546798 -207.721454)
					(mid 413.561677 -207.757375)
					(end 413.597598 -207.772254)
				)
				(arc
					(start 414.997138 -207.772254)
					(mid 415.033059 -207.757375)
					(end 415.047938 -207.721454)
				)
				(arc
					(start 415.047938 -207.312514)
					(mid 415.033059 -207.276593)
					(end 414.997138 -207.261714)
				)
				(arc
					(start 413.597598 -207.261714)
					(mid 413.561677 -207.276593)
					(end 413.546798 -207.312514)
				)
			)
		)
	)
	(zone
		(layers "In1.Cu" "In2.Cu")
		(hatch none 0.5)
		(connect_pads
			(clearance 0)
		)
		(min_thickness 0.25)
		(keepout
			(tracks not_allowed)
			(vias allowed)
			(pads allowed)
			(copperpour not_allowed)
			(footprints allowed)
		)
		(placement
			(enabled no)
			(sheetname "")
		)
		(fill yes
			(thermal_gap 0.5)
			(thermal_bridge_width 0.5)
			(island_removal_mode 0)
		)
		(polygon
			(pts
				(arc
					(start 203.32573 -271.47139)
					(mid 203.340609 -271.507311)
					(end 203.37653 -271.52219)
				)
				(arc
					(start 204.77607 -271.52219)
					(mid 204.811991 -271.507311)
					(end 204.82687 -271.47139)
				)
				(arc
					(start 204.82687 -271.06245)
					(mid 204.811991 -271.026529)
					(end 204.77607 -271.01165)
				)
				(arc
					(start 203.37653 -271.01165)
					(mid 203.340609 -271.026529)
					(end 203.32573 -271.06245)
				)
			)
		)
	)
	(zone
		(layers "In1.Cu" "In2.Cu")
		(hatch none 0.5)
		(connect_pads
			(clearance 0)
		)
		(min_thickness 0.25)
		(keepout
			(tracks not_allowed)
			(vias allowed)
			(pads allowed)
			(copperpour not_allowed)
			(footprints allowed)
		)
		(placement
			(enabled no)
			(sheetname "")
		)
		(fill yes
			(thermal_gap 0.5)
			(thermal_bridge_width 0.5)
			(island_removal_mode 0)
		)
		(polygon
			(pts
				(arc
					(start 432.734466 -229.821486)
					(mid 432.749345 -229.857407)
					(end 432.785266 -229.872286)
				)
				(arc
					(start 434.184806 -229.872286)
					(mid 434.220727 -229.857407)
					(end 434.235606 -229.821486)
				)
				(arc
					(start 434.235606 -229.412546)
					(mid 434.220727 -229.376625)
					(end 434.184806 -229.361746)
				)
				(arc
					(start 432.785266 -229.361746)
					(mid 432.749345 -229.376625)
					(end 432.734466 -229.412546)
				)
			)
		)
	)
	(zone
		(layers "In1.Cu" "In2.Cu")
		(hatch none 0.5)
		(connect_pads
			(clearance 0)
		)
		(min_thickness 0.25)
		(keepout
			(tracks not_allowed)
			(vias allowed)
			(pads allowed)
			(copperpour not_allowed)
			(footprints allowed)
		)
		(placement
			(enabled no)
			(sheetname "")
		)
		(fill yes
			(thermal_gap 0.5)
			(thermal_bridge_width 0.5)
			(island_removal_mode 0)
		)
		(polygon
			(pts
				(arc
					(start 19.033998 -208.571338)
					(mid 19.048877 -208.607259)
					(end 19.084798 -208.622138)
				)
				(arc
					(start 20.484338 -208.622138)
					(mid 20.520259 -208.607259)
					(end 20.535138 -208.571338)
				)
				(arc
					(start 20.535138 -208.162398)
					(mid 20.520259 -208.126477)
					(end 20.484338 -208.111598)
				)
				(arc
					(start 19.084798 -208.111598)
					(mid 19.048877 -208.126477)
					(end 19.033998 -208.162398)
				)
			)
		)
	)
	(zone
		(layers "In1.Cu" "In2.Cu")
		(hatch none 0.5)
		(connect_pads
			(clearance 0)
		)
		(min_thickness 0.25)
		(keepout
			(tracks not_allowed)
			(vias allowed)
			(pads allowed)
			(copperpour not_allowed)
			(footprints allowed)
		)
		(placement
			(enabled no)
			(sheetname "")
		)
		(fill yes
			(thermal_gap 0.5)
			(thermal_bridge_width 0.5)
			(island_removal_mode 0)
		)
		(polygon
			(pts
				(arc
					(start 60.19673 -294.421306)
					(mid 60.211609 -294.457227)
					(end 60.24753 -294.472106)
				)
				(arc
					(start 61.64707 -294.472106)
					(mid 61.682991 -294.457227)
					(end 61.69787 -294.421306)
				)
				(arc
					(start 61.69787 -294.012366)
					(mid 61.682991 -293.976445)
					(end 61.64707 -293.961566)
				)
				(arc
					(start 60.24753 -293.961566)
					(mid 60.211609 -293.976445)
					(end 60.19673 -294.012366)
				)
			)
		)
	)
	(zone
		(layers "In1.Cu" "In2.Cu")
		(hatch none 0.5)
		(connect_pads
			(clearance 0)
		)
		(min_thickness 0.25)
		(keepout
			(tracks not_allowed)
			(vias allowed)
			(pads allowed)
			(copperpour not_allowed)
			(footprints allowed)
		)
		(placement
			(enabled no)
			(sheetname "")
		)
		(fill yes
			(thermal_gap 0.5)
			(thermal_bridge_width 0.5)
			(island_removal_mode 0)
		)
		(polygon
			(pts
				(arc
					(start 443.721998 -241.721386)
					(mid 443.736877 -241.757307)
					(end 443.772798 -241.772186)
				)
				(arc
					(start 445.172338 -241.772186)
					(mid 445.208259 -241.757307)
					(end 445.223138 -241.721386)
				)
				(arc
					(start 445.223138 -241.312446)
					(mid 445.208259 -241.276525)
					(end 445.172338 -241.261646)
				)
				(arc
					(start 443.772798 -241.261646)
					(mid 443.736877 -241.276525)
					(end 443.721998 -241.312446)
				)
			)
		)
	)
	(zone
		(layers "In1.Cu" "In2.Cu")
		(hatch none 0.5)
		(connect_pads
			(clearance 0)
		)
		(min_thickness 0.25)
		(keepout
			(tracks not_allowed)
			(vias allowed)
			(pads allowed)
			(copperpour not_allowed)
			(footprints allowed)
		)
		(placement
			(enabled no)
			(sheetname "")
		)
		(fill yes
			(thermal_gap 0.5)
			(thermal_bridge_width 0.5)
			(island_removal_mode 0)
		)
		(polygon
			(pts
				(arc
					(start 451.265798 -261.271512)
					(mid 451.280677 -261.307433)
					(end 451.316598 -261.322312)
				)
				(arc
					(start 452.716138 -261.322312)
					(mid 452.752059 -261.307433)
					(end 452.766938 -261.271512)
				)
				(arc
					(start 452.766938 -260.862572)
					(mid 452.752059 -260.826651)
					(end 452.716138 -260.811772)
				)
				(arc
					(start 451.316598 -260.811772)
					(mid 451.280677 -260.826651)
					(end 451.265798 -260.862572)
				)
			)
		)
	)
	(zone
		(layers "In1.Cu" "In2.Cu")
		(hatch none 0.5)
		(connect_pads
			(clearance 0)
		)
		(min_thickness 0.25)
		(keepout
			(tracks not_allowed)
			(vias allowed)
			(pads allowed)
			(copperpour not_allowed)
			(footprints allowed)
		)
		(placement
			(enabled no)
			(sheetname "")
		)
		(fill yes
			(thermal_gap 0.5)
			(thermal_bridge_width 0.5)
			(island_removal_mode 0)
		)
		(polygon
			(pts
				(arc
					(start 22.47773 -297.82135)
					(mid 22.492609 -297.857271)
					(end 22.52853 -297.87215)
				)
				(arc
					(start 23.92807 -297.87215)
					(mid 23.963991 -297.857271)
					(end 23.97887 -297.82135)
				)
				(arc
					(start 23.97887 -297.41241)
					(mid 23.963991 -297.376489)
					(end 23.92807 -297.36161)
				)
				(arc
					(start 22.52853 -297.36161)
					(mid 22.492609 -297.376489)
					(end 22.47773 -297.41241)
				)
			)
		)
	)
	(zone
		(layers "In1.Cu" "In2.Cu")
		(hatch none 0.5)
		(connect_pads
			(clearance 0)
		)
		(min_thickness 0.25)
		(keepout
			(tracks not_allowed)
			(vias allowed)
			(pads allowed)
			(copperpour not_allowed)
			(footprints allowed)
		)
		(placement
			(enabled no)
			(sheetname "")
		)
		(fill yes
			(thermal_gap 0.5)
			(thermal_bridge_width 0.5)
			(island_removal_mode 0)
		)
		(polygon
			(pts
				(arc
					(start 417.646866 -283.371544)
					(mid 417.661745 -283.407465)
					(end 417.697666 -283.422344)
				)
				(arc
					(start 419.097206 -283.422344)
					(mid 419.133127 -283.407465)
					(end 419.148006 -283.371544)
				)
				(arc
					(start 419.148006 -282.962604)
					(mid 419.133127 -282.926683)
					(end 419.097206 -282.911804)
				)
				(arc
					(start 417.697666 -282.911804)
					(mid 417.661745 -282.926683)
					(end 417.646866 -282.962604)
				)
			)
		)
	)
	(zone
		(layers "In1.Cu" "In2.Cu")
		(hatch none 0.5)
		(connect_pads
			(clearance 0)
		)
		(min_thickness 0.25)
		(keepout
			(tracks not_allowed)
			(vias allowed)
			(pads allowed)
			(copperpour not_allowed)
			(footprints allowed)
		)
		(placement
			(enabled no)
			(sheetname "")
		)
		(fill yes
			(thermal_gap 0.5)
			(thermal_bridge_width 0.5)
			(island_removal_mode 0)
		)
		(polygon
			(pts
				(arc
					(start 436.178198 -240.021364)
					(mid 436.193077 -240.057285)
					(end 436.228998 -240.072164)
				)
				(arc
					(start 437.628538 -240.072164)
					(mid 437.664459 -240.057285)
					(end 437.679338 -240.021364)
				)
				(arc
					(start 437.679338 -239.612424)
					(mid 437.664459 -239.576503)
					(end 437.628538 -239.561624)
				)
				(arc
					(start 436.228998 -239.561624)
					(mid 436.193077 -239.576503)
					(end 436.178198 -239.612424)
				)
			)
		)
	)
	(zone
		(layers "In1.Cu" "In2.Cu")
		(hatch none 0.5)
		(connect_pads
			(clearance 0)
		)
		(min_thickness 0.25)
		(keepout
			(tracks not_allowed)
			(vias allowed)
			(pads allowed)
			(copperpour not_allowed)
			(footprints allowed)
		)
		(placement
			(enabled no)
			(sheetname "")
		)
		(fill yes
			(thermal_gap 0.5)
			(thermal_bridge_width 0.5)
			(island_removal_mode 0)
		)
		(polygon
			(pts
				(arc
					(start 406.002998 -245.971314)
					(mid 406.017877 -246.007235)
					(end 406.053798 -246.022114)
				)
				(arc
					(start 407.453338 -246.022114)
					(mid 407.489259 -246.007235)
					(end 407.504138 -245.971314)
				)
				(arc
					(start 407.504138 -245.562374)
					(mid 407.489259 -245.526453)
					(end 407.453338 -245.511574)
				)
				(arc
					(start 406.053798 -245.511574)
					(mid 406.017877 -245.526453)
					(end 406.002998 -245.562374)
				)
			)
		)
	)
	(zone
		(layers "In1.Cu" "In2.Cu")
		(hatch none 0.5)
		(connect_pads
			(clearance 0)
		)
		(min_thickness 0.25)
		(keepout
			(tracks not_allowed)
			(vias allowed)
			(pads allowed)
			(copperpour not_allowed)
			(footprints allowed)
		)
		(placement
			(enabled no)
			(sheetname "")
		)
		(fill yes
			(thermal_gap 0.5)
			(thermal_bridge_width 0.5)
			(island_removal_mode 0)
		)
		(polygon
			(pts
				(arc
					(start 41.665398 -216.22131)
					(mid 41.680277 -216.257231)
					(end 41.716198 -216.27211)
				)
				(arc
					(start 43.115738 -216.27211)
					(mid 43.151659 -216.257231)
					(end 43.166538 -216.22131)
				)
				(arc
					(start 43.166538 -215.81237)
					(mid 43.151659 -215.776449)
					(end 43.115738 -215.76157)
				)
				(arc
					(start 41.716198 -215.76157)
					(mid 41.680277 -215.776449)
					(end 41.665398 -215.81237)
				)
			)
		)
	)
	(zone
		(layers "In1.Cu" "In2.Cu")
		(hatch none 0.5)
		(connect_pads
			(clearance 0)
		)
		(min_thickness 0.25)
		(keepout
			(tracks not_allowed)
			(vias allowed)
			(pads allowed)
			(copperpour not_allowed)
			(footprints allowed)
		)
		(placement
			(enabled no)
			(sheetname "")
		)
		(fill yes
			(thermal_gap 0.5)
			(thermal_bridge_width 0.5)
			(island_removal_mode 0)
		)
		(polygon
			(pts
				(arc
					(start 300.592998 -243.421408)
					(mid 300.607877 -243.457329)
					(end 300.643798 -243.472208)
				)
				(arc
					(start 302.043338 -243.472208)
					(mid 302.079259 -243.457329)
					(end 302.094138 -243.421408)
				)
				(arc
					(start 302.094138 -243.012468)
					(mid 302.079259 -242.976547)
					(end 302.043338 -242.961668)
				)
				(arc
					(start 300.643798 -242.961668)
					(mid 300.607877 -242.976547)
					(end 300.592998 -243.012468)
				)
			)
		)
	)
	(zone
		(layers "In1.Cu" "In2.Cu")
		(hatch none 0.5)
		(connect_pads
			(clearance 0)
		)
		(min_thickness 0.25)
		(keepout
			(tracks not_allowed)
			(vias allowed)
			(pads allowed)
			(copperpour not_allowed)
			(footprints allowed)
		)
		(placement
			(enabled no)
			(sheetname "")
		)
		(fill yes
			(thermal_gap 0.5)
			(thermal_bridge_width 0.5)
			(island_removal_mode 0)
		)
		(polygon
			(pts
				(arc
					(start 162.162998 -278.271478)
					(mid 162.177877 -278.307399)
					(end 162.213798 -278.322278)
				)
				(arc
					(start 163.613338 -278.322278)
					(mid 163.649259 -278.307399)
					(end 163.664138 -278.271478)
				)
				(arc
					(start 163.664138 -277.862538)
					(mid 163.649259 -277.826617)
					(end 163.613338 -277.811738)
				)
				(arc
					(start 162.213798 -277.811738)
					(mid 162.177877 -277.826617)
					(end 162.162998 -277.862538)
				)
			)
		)
	)
	(zone
		(layers "In1.Cu" "In2.Cu")
		(hatch none 0.5)
		(connect_pads
			(clearance 0)
		)
		(min_thickness 0.25)
		(keepout
			(tracks not_allowed)
			(vias allowed)
			(pads allowed)
			(copperpour not_allowed)
			(footprints allowed)
		)
		(placement
			(enabled no)
			(sheetname "")
		)
		(fill yes
			(thermal_gap 0.5)
			(thermal_bridge_width 0.5)
			(island_removal_mode 0)
		)
		(polygon
			(pts
				(arc
					(start 158.06293 -251.07138)
					(mid 158.077809 -251.107301)
					(end 158.11373 -251.12218)
				)
				(arc
					(start 159.51327 -251.12218)
					(mid 159.549191 -251.107301)
					(end 159.56407 -251.07138)
				)
				(arc
					(start 159.56407 -250.66244)
					(mid 159.549191 -250.626519)
					(end 159.51327 -250.61164)
				)
				(arc
					(start 158.11373 -250.61164)
					(mid 158.077809 -250.626519)
					(end 158.06293 -250.66244)
				)
			)
		)
	)
	(zone
		(layers "In1.Cu" "In2.Cu")
		(hatch none 0.5)
		(connect_pads
			(clearance 0)
		)
		(min_thickness 0.25)
		(keepout
			(tracks not_allowed)
			(vias allowed)
			(pads allowed)
			(copperpour not_allowed)
			(footprints allowed)
		)
		(placement
			(enabled no)
			(sheetname "")
		)
		(fill yes
			(thermal_gap 0.5)
			(thermal_bridge_width 0.5)
			(island_removal_mode 0)
		)
		(polygon
			(pts
				(arc
					(start 413.546798 -235.771436)
					(mid 413.561677 -235.807357)
					(end 413.597598 -235.822236)
				)
				(arc
					(start 414.997138 -235.822236)
					(mid 415.033059 -235.807357)
					(end 415.047938 -235.771436)
				)
				(arc
					(start 415.047938 -235.362496)
					(mid 415.033059 -235.326575)
					(end 414.997138 -235.311696)
				)
				(arc
					(start 413.597598 -235.311696)
					(mid 413.561677 -235.326575)
					(end 413.546798 -235.362496)
				)
			)
		)
	)
	(zone
		(layers "In1.Cu" "In2.Cu")
		(hatch none 0.5)
		(connect_pads
			(clearance 0)
		)
		(min_thickness 0.25)
		(keepout
			(tracks not_allowed)
			(vias allowed)
			(pads allowed)
			(copperpour not_allowed)
			(footprints allowed)
		)
		(placement
			(enabled no)
			(sheetname "")
		)
		(fill yes
			(thermal_gap 0.5)
			(thermal_bridge_width 0.5)
			(island_removal_mode 0)
		)
		(polygon
			(pts
				(arc
					(start 34.121598 -313.971432)
					(mid 34.136477 -314.007353)
					(end 34.172398 -314.022232)
				)
				(arc
					(start 35.571938 -314.022232)
					(mid 35.607859 -314.007353)
					(end 35.622738 -313.971432)
				)
				(arc
					(start 35.622738 -313.562492)
					(mid 35.607859 -313.526571)
					(end 35.571938 -313.511692)
				)
				(arc
					(start 34.172398 -313.511692)
					(mid 34.136477 -313.526571)
					(end 34.121598 -313.562492)
				)
			)
		)
	)
	(zone
		(layers "In1.Cu" "In2.Cu")
		(hatch none 0.5)
		(connect_pads
			(clearance 0)
		)
		(min_thickness 0.25)
		(keepout
			(tracks not_allowed)
			(vias allowed)
			(pads allowed)
			(copperpour not_allowed)
			(footprints allowed)
		)
		(placement
			(enabled no)
			(sheetname "")
		)
		(fill yes
			(thermal_gap 0.5)
			(thermal_bridge_width 0.5)
			(island_removal_mode 0)
		)
		(polygon
			(pts
				(arc
					(start 259.430266 -231.521508)
					(mid 259.445145 -231.557429)
					(end 259.481066 -231.572308)
				)
				(arc
					(start 260.880606 -231.572308)
					(mid 260.916527 -231.557429)
					(end 260.931406 -231.521508)
				)
				(arc
					(start 260.931406 -231.112568)
					(mid 260.916527 -231.076647)
					(end 260.880606 -231.061768)
				)
				(arc
					(start 259.481066 -231.061768)
					(mid 259.445145 -231.076647)
					(end 259.430266 -231.112568)
				)
			)
		)
	)
	(zone
		(layers "In1.Cu" "In2.Cu")
		(hatch none 0.5)
		(connect_pads
			(clearance 0)
		)
		(min_thickness 0.25)
		(keepout
			(tracks not_allowed)
			(vias allowed)
			(pads allowed)
			(copperpour not_allowed)
			(footprints allowed)
		)
		(placement
			(enabled no)
			(sheetname "")
		)
		(fill yes
			(thermal_gap 0.5)
			(thermal_bridge_width 0.5)
			(island_removal_mode 0)
		)
		(polygon
			(pts
				(arc
					(start 259.430266 -274.871434)
					(mid 259.445145 -274.907355)
					(end 259.481066 -274.922234)
				)
				(arc
					(start 260.880606 -274.922234)
					(mid 260.916527 -274.907355)
					(end 260.931406 -274.871434)
				)
				(arc
					(start 260.931406 -274.462494)
					(mid 260.916527 -274.426573)
					(end 260.880606 -274.411694)
				)
				(arc
					(start 259.481066 -274.411694)
					(mid 259.445145 -274.426573)
					(end 259.430266 -274.462494)
				)
			)
		)
	)
	(zone
		(layers "In1.Cu" "In2.Cu")
		(hatch none 0.5)
		(connect_pads
			(clearance 0)
		)
		(min_thickness 0.25)
		(keepout
			(tracks not_allowed)
			(vias allowed)
			(pads allowed)
			(copperpour not_allowed)
			(footprints allowed)
		)
		(placement
			(enabled no)
			(sheetname "")
		)
		(fill yes
			(thermal_gap 0.5)
			(thermal_bridge_width 0.5)
			(island_removal_mode 0)
		)
		(polygon
			(pts
				(arc
					(start 259.430266 -229.821486)
					(mid 259.445145 -229.857407)
					(end 259.481066 -229.872286)
				)
				(arc
					(start 260.880606 -229.872286)
					(mid 260.916527 -229.857407)
					(end 260.931406 -229.821486)
				)
				(arc
					(start 260.931406 -229.412546)
					(mid 260.916527 -229.376625)
					(end 260.880606 -229.361746)
				)
				(arc
					(start 259.481066 -229.361746)
					(mid 259.445145 -229.376625)
					(end 259.430266 -229.412546)
				)
			)
		)
	)
	(zone
		(layers "In1.Cu" "In2.Cu")
		(hatch none 0.5)
		(connect_pads
			(clearance 0)
		)
		(min_thickness 0.25)
		(keepout
			(tracks not_allowed)
			(vias allowed)
			(pads allowed)
			(copperpour not_allowed)
			(footprints allowed)
		)
		(placement
			(enabled no)
			(sheetname "")
		)
		(fill yes
			(thermal_gap 0.5)
			(thermal_bridge_width 0.5)
			(island_removal_mode 0)
		)
		(polygon
			(pts
				(arc
					(start 19.033998 -200.071482)
					(mid 19.048877 -200.107403)
					(end 19.084798 -200.122282)
				)
				(arc
					(start 20.484338 -200.122282)
					(mid 20.520259 -200.107403)
					(end 20.535138 -200.071482)
				)
				(arc
					(start 20.535138 -199.662542)
					(mid 20.520259 -199.626621)
					(end 20.484338 -199.611742)
				)
				(arc
					(start 19.084798 -199.611742)
					(mid 19.048877 -199.626621)
					(end 19.033998 -199.662542)
				)
			)
		)
	)
	(zone
		(layers "In1.Cu" "In2.Cu")
		(hatch none 0.5)
		(connect_pads
			(clearance 0)
		)
		(min_thickness 0.25)
		(keepout
			(tracks not_allowed)
			(vias allowed)
			(pads allowed)
			(copperpour not_allowed)
			(footprints allowed)
		)
		(placement
			(enabled no)
			(sheetname "")
		)
		(fill yes
			(thermal_gap 0.5)
			(thermal_bridge_width 0.5)
			(island_removal_mode 0)
		)
		(polygon
			(pts
				(arc
					(start 410.103066 -274.02155)
					(mid 410.117945 -274.057471)
					(end 410.153866 -274.07235)
				)
				(arc
					(start 411.553406 -274.07235)
					(mid 411.589327 -274.057471)
					(end 411.604206 -274.02155)
				)
				(arc
					(start 411.604206 -273.61261)
					(mid 411.589327 -273.576689)
					(end 411.553406 -273.56181)
				)
				(arc
					(start 410.153866 -273.56181)
					(mid 410.117945 -273.576689)
					(end 410.103066 -273.61261)
				)
			)
		)
	)
	(zone
		(layers "In1.Cu" "In2.Cu")
		(hatch none 0.5)
		(connect_pads
			(clearance 0)
		)
		(min_thickness 0.25)
		(keepout
			(tracks not_allowed)
			(vias allowed)
			(pads allowed)
			(copperpour not_allowed)
			(footprints allowed)
		)
		(placement
			(enabled no)
			(sheetname "")
		)
		(fill yes
			(thermal_gap 0.5)
			(thermal_bridge_width 0.5)
			(island_removal_mode 0)
		)
		(polygon
			(pts
				(arc
					(start 455.365866 -292.721538)
					(mid 455.380745 -292.757459)
					(end 455.416666 -292.772338)
				)
				(arc
					(start 456.816206 -292.772338)
					(mid 456.852127 -292.757459)
					(end 456.867006 -292.721538)
				)
				(arc
					(start 456.867006 -292.312598)
					(mid 456.852127 -292.276677)
					(end 456.816206 -292.261798)
				)
				(arc
					(start 455.416666 -292.261798)
					(mid 455.380745 -292.276677)
					(end 455.365866 -292.312598)
				)
			)
		)
	)
	(zone
		(layers "In1.Cu" "In2.Cu")
		(hatch none 0.5)
		(connect_pads
			(clearance 0)
		)
		(min_thickness 0.25)
		(keepout
			(tracks not_allowed)
			(vias allowed)
			(pads allowed)
			(copperpour not_allowed)
			(footprints allowed)
		)
		(placement
			(enabled no)
			(sheetname "")
		)
		(fill yes
			(thermal_gap 0.5)
			(thermal_bridge_width 0.5)
			(island_removal_mode 0)
		)
		(polygon
			(pts
				(arc
					(start 297.149266 -302.071532)
					(mid 297.164145 -302.107453)
					(end 297.200066 -302.122332)
				)
				(arc
					(start 298.599606 -302.122332)
					(mid 298.635527 -302.107453)
					(end 298.650406 -302.071532)
				)
				(arc
					(start 298.650406 -301.662592)
					(mid 298.635527 -301.626671)
					(end 298.599606 -301.611792)
				)
				(arc
					(start 297.200066 -301.611792)
					(mid 297.164145 -301.626671)
					(end 297.149266 -301.662592)
				)
			)
		)
	)
	(zone
		(layers "In1.Cu" "In2.Cu")
		(hatch none 0.5)
		(connect_pads
			(clearance 0)
		)
		(min_thickness 0.25)
		(keepout
			(tracks not_allowed)
			(vias allowed)
			(pads allowed)
			(copperpour not_allowed)
			(footprints allowed)
		)
		(placement
			(enabled no)
			(sheetname "")
		)
		(fill yes
			(thermal_gap 0.5)
			(thermal_bridge_width 0.5)
			(island_removal_mode 0)
		)
		(polygon
			(pts
				(arc
					(start 277.961598 -297.82135)
					(mid 277.976477 -297.857271)
					(end 278.012398 -297.87215)
				)
				(arc
					(start 279.411938 -297.87215)
					(mid 279.447859 -297.857271)
					(end 279.462738 -297.82135)
				)
				(arc
					(start 279.462738 -297.41241)
					(mid 279.447859 -297.376489)
					(end 279.411938 -297.36161)
				)
				(arc
					(start 278.012398 -297.36161)
					(mid 277.976477 -297.376489)
					(end 277.961598 -297.41241)
				)
			)
		)
	)
	(zone
		(layers "In1.Cu" "In2.Cu")
		(hatch none 0.5)
		(connect_pads
			(clearance 0)
		)
		(min_thickness 0.25)
		(keepout
			(tracks not_allowed)
			(vias allowed)
			(pads allowed)
			(copperpour not_allowed)
			(footprints allowed)
		)
		(placement
			(enabled no)
			(sheetname "")
		)
		(fill yes
			(thermal_gap 0.5)
			(thermal_bridge_width 0.5)
			(island_removal_mode 0)
		)
		(polygon
			(pts
				(arc
					(start 458.809598 -296.121328)
					(mid 458.824477 -296.157249)
					(end 458.860398 -296.172128)
				)
				(arc
					(start 460.259938 -296.172128)
					(mid 460.295859 -296.157249)
					(end 460.310738 -296.121328)
				)
				(arc
					(start 460.310738 -295.712388)
					(mid 460.295859 -295.676467)
					(end 460.259938 -295.661588)
				)
				(arc
					(start 458.860398 -295.661588)
					(mid 458.824477 -295.676467)
					(end 458.809598 -295.712388)
				)
			)
		)
	)
	(zone
		(layers "In1.Cu" "In2.Cu")
		(hatch none 0.5)
		(connect_pads
			(clearance 0)
		)
		(min_thickness 0.25)
		(keepout
			(tracks not_allowed)
			(vias allowed)
			(pads allowed)
			(copperpour not_allowed)
			(footprints allowed)
		)
		(placement
			(enabled no)
			(sheetname "")
		)
		(fill yes
			(thermal_gap 0.5)
			(thermal_bridge_width 0.5)
			(island_removal_mode 0)
		)
		(polygon
			(pts
				(arc
					(start 443.721998 -232.371392)
					(mid 443.736877 -232.407313)
					(end 443.772798 -232.422192)
				)
				(arc
					(start 445.172338 -232.422192)
					(mid 445.208259 -232.407313)
					(end 445.223138 -232.371392)
				)
				(arc
					(start 445.223138 -231.962452)
					(mid 445.208259 -231.926531)
					(end 445.172338 -231.911652)
				)
				(arc
					(start 443.772798 -231.911652)
					(mid 443.736877 -231.926531)
					(end 443.721998 -231.962452)
				)
			)
		)
	)
	(zone
		(layers "In1.Cu" "In2.Cu")
		(hatch none 0.5)
		(connect_pads
			(clearance 0)
		)
		(min_thickness 0.25)
		(keepout
			(tracks not_allowed)
			(vias allowed)
			(pads allowed)
			(copperpour not_allowed)
			(footprints allowed)
		)
		(placement
			(enabled no)
			(sheetname "")
		)
		(fill yes
			(thermal_gap 0.5)
			(thermal_bridge_width 0.5)
			(island_removal_mode 0)
		)
		(polygon
			(pts
				(arc
					(start 406.002998 -279.121362)
					(mid 406.017877 -279.157283)
					(end 406.053798 -279.172162)
				)
				(arc
					(start 407.453338 -279.172162)
					(mid 407.489259 -279.157283)
					(end 407.504138 -279.121362)
				)
				(arc
					(start 407.504138 -278.712422)
					(mid 407.489259 -278.676501)
					(end 407.453338 -278.661622)
				)
				(arc
					(start 406.053798 -278.661622)
					(mid 406.017877 -278.676501)
					(end 406.002998 -278.712422)
				)
			)
		)
	)
	(zone
		(layers "In1.Cu" "In2.Cu")
		(hatch none 0.5)
		(connect_pads
			(clearance 0)
		)
		(min_thickness 0.25)
		(keepout
			(tracks not_allowed)
			(vias allowed)
			(pads allowed)
			(copperpour not_allowed)
			(footprints allowed)
		)
		(placement
			(enabled no)
			(sheetname "")
		)
		(fill yes
			(thermal_gap 0.5)
			(thermal_bridge_width 0.5)
			(island_removal_mode 0)
		)
		(polygon
			(pts
				(arc
					(start 184.794398 -214.521542)
					(mid 184.809277 -214.557463)
					(end 184.845198 -214.572342)
				)
				(arc
					(start 186.244738 -214.572342)
					(mid 186.280659 -214.557463)
					(end 186.295538 -214.521542)
				)
				(arc
					(start 186.295538 -214.112602)
					(mid 186.280659 -214.076681)
					(end 186.244738 -214.061802)
				)
				(arc
					(start 184.845198 -214.061802)
					(mid 184.809277 -214.076681)
					(end 184.794398 -214.112602)
				)
			)
		)
	)
	(zone
		(layers "In1.Cu" "In2.Cu")
		(hatch none 0.5)
		(connect_pads
			(clearance 0)
		)
		(min_thickness 0.25)
		(keepout
			(tracks not_allowed)
			(vias allowed)
			(pads allowed)
			(copperpour not_allowed)
			(footprints allowed)
		)
		(placement
			(enabled no)
			(sheetname "")
		)
		(fill yes
			(thermal_gap 0.5)
			(thermal_bridge_width 0.5)
			(island_removal_mode 0)
		)
		(polygon
			(pts
				(arc
					(start 188.23813 -290.171378)
					(mid 188.253009 -290.207299)
					(end 188.28893 -290.222178)
				)
				(arc
					(start 189.68847 -290.222178)
					(mid 189.724391 -290.207299)
					(end 189.73927 -290.171378)
				)
				(arc
					(start 189.73927 -289.762438)
					(mid 189.724391 -289.726517)
					(end 189.68847 -289.711638)
				)
				(arc
					(start 188.28893 -289.711638)
					(mid 188.253009 -289.726517)
					(end 188.23813 -289.762438)
				)
			)
		)
	)
	(zone
		(layers "In1.Cu" "In2.Cu")
		(hatch none 0.5)
		(connect_pads
			(clearance 0)
		)
		(min_thickness 0.25)
		(keepout
			(tracks not_allowed)
			(vias allowed)
			(pads allowed)
			(copperpour not_allowed)
			(footprints allowed)
		)
		(placement
			(enabled no)
			(sheetname "")
		)
		(fill yes
			(thermal_gap 0.5)
			(thermal_bridge_width 0.5)
			(island_removal_mode 0)
		)
		(polygon
			(pts
				(arc
					(start 308.136798 -284.221428)
					(mid 308.151677 -284.257349)
					(end 308.187598 -284.272228)
				)
				(arc
					(start 309.587138 -284.272228)
					(mid 309.623059 -284.257349)
					(end 309.637938 -284.221428)
				)
				(arc
					(start 309.637938 -283.812488)
					(mid 309.623059 -283.776567)
					(end 309.587138 -283.761688)
				)
				(arc
					(start 308.187598 -283.761688)
					(mid 308.151677 -283.776567)
					(end 308.136798 -283.812488)
				)
			)
		)
	)
	(zone
		(layers "In1.Cu" "In2.Cu")
		(hatch none 0.5)
		(connect_pads
			(clearance 0)
		)
		(min_thickness 0.25)
		(keepout
			(tracks not_allowed)
			(vias allowed)
			(pads allowed)
			(copperpour not_allowed)
			(footprints allowed)
		)
		(placement
			(enabled no)
			(sheetname "")
		)
		(fill yes
			(thermal_gap 0.5)
			(thermal_bridge_width 0.5)
			(island_removal_mode 0)
		)
		(polygon
			(pts
				(arc
					(start 425.190666 -262.121396)
					(mid 425.205545 -262.157317)
					(end 425.241466 -262.172196)
				)
				(arc
					(start 426.641006 -262.172196)
					(mid 426.676927 -262.157317)
					(end 426.691806 -262.121396)
				)
				(arc
					(start 426.691806 -261.712456)
					(mid 426.676927 -261.676535)
					(end 426.641006 -261.661656)
				)
				(arc
					(start 425.241466 -261.661656)
					(mid 425.205545 -261.676535)
					(end 425.190666 -261.712456)
				)
			)
		)
	)
	(zone
		(layers "In1.Cu" "In2.Cu")
		(hatch none 0.5)
		(connect_pads
			(clearance 0)
		)
		(min_thickness 0.25)
		(keepout
			(tracks not_allowed)
			(vias allowed)
			(pads allowed)
			(copperpour not_allowed)
			(footprints allowed)
		)
		(placement
			(enabled no)
			(sheetname "")
		)
		(fill yes
			(thermal_gap 0.5)
			(thermal_bridge_width 0.5)
			(island_removal_mode 0)
		)
		(polygon
			(pts
				(arc
					(start 425.190666 -270.621506)
					(mid 425.205545 -270.657427)
					(end 425.241466 -270.672306)
				)
				(arc
					(start 426.641006 -270.672306)
					(mid 426.676927 -270.657427)
					(end 426.691806 -270.621506)
				)
				(arc
					(start 426.691806 -270.212566)
					(mid 426.676927 -270.176645)
					(end 426.641006 -270.161766)
				)
				(arc
					(start 425.241466 -270.161766)
					(mid 425.205545 -270.176645)
					(end 425.190666 -270.212566)
				)
			)
		)
	)
	(zone
		(layers "In1.Cu" "In2.Cu")
		(hatch none 0.5)
		(connect_pads
			(clearance 0)
		)
		(min_thickness 0.25)
		(keepout
			(tracks not_allowed)
			(vias allowed)
			(pads allowed)
			(copperpour not_allowed)
			(footprints allowed)
		)
		(placement
			(enabled no)
			(sheetname "")
		)
		(fill yes
			(thermal_gap 0.5)
			(thermal_bridge_width 0.5)
			(island_removal_mode 0)
		)
		(polygon
			(pts
				(arc
					(start 274.517866 -267.221462)
					(mid 274.532745 -267.257383)
					(end 274.568666 -267.272262)
				)
				(arc
					(start 275.968206 -267.272262)
					(mid 276.004127 -267.257383)
					(end 276.019006 -267.221462)
				)
				(arc
					(start 276.019006 -266.812522)
					(mid 276.004127 -266.776601)
					(end 275.968206 -266.761722)
				)
				(arc
					(start 274.568666 -266.761722)
					(mid 274.532745 -266.776601)
					(end 274.517866 -266.812522)
				)
			)
		)
	)
	(zone
		(layers "In1.Cu" "In2.Cu")
		(hatch none 0.5)
		(connect_pads
			(clearance 0)
		)
		(min_thickness 0.25)
		(keepout
			(tracks not_allowed)
			(vias allowed)
			(pads allowed)
			(copperpour not_allowed)
			(footprints allowed)
		)
		(placement
			(enabled no)
			(sheetname "")
		)
		(fill yes
			(thermal_gap 0.5)
			(thermal_bridge_width 0.5)
			(island_removal_mode 0)
		)
		(polygon
			(pts
				(arc
					(start 173.15053 -198.37146)
					(mid 173.165409 -198.407381)
					(end 173.20133 -198.42226)
				)
				(arc
					(start 174.60087 -198.42226)
					(mid 174.636791 -198.407381)
					(end 174.65167 -198.37146)
				)
				(arc
					(start 174.65167 -197.96252)
					(mid 174.636791 -197.926599)
					(end 174.60087 -197.91172)
				)
				(arc
					(start 173.20133 -197.91172)
					(mid 173.165409 -197.926599)
					(end 173.15053 -197.96252)
				)
			)
		)
	)
	(zone
		(layers "In1.Cu" "In2.Cu")
		(hatch none 0.5)
		(connect_pads
			(clearance 0)
		)
		(min_thickness 0.25)
		(keepout
			(tracks not_allowed)
			(vias allowed)
			(pads allowed)
			(copperpour not_allowed)
			(footprints allowed)
		)
		(placement
			(enabled no)
			(sheetname "")
		)
		(fill yes
			(thermal_gap 0.5)
			(thermal_bridge_width 0.5)
			(island_removal_mode 0)
		)
		(polygon
			(pts
				(arc
					(start 199.881998 -302.071532)
					(mid 199.896877 -302.107453)
					(end 199.932798 -302.122332)
				)
				(arc
					(start 201.332338 -302.122332)
					(mid 201.368259 -302.107453)
					(end 201.383138 -302.071532)
				)
				(arc
					(start 201.383138 -301.662592)
					(mid 201.368259 -301.626671)
					(end 201.332338 -301.611792)
				)
				(arc
					(start 199.932798 -301.611792)
					(mid 199.896877 -301.626671)
					(end 199.881998 -301.662592)
				)
			)
		)
	)
	(zone
		(layers "In1.Cu" "In2.Cu")
		(hatch none 0.5)
		(connect_pads
			(clearance 0)
		)
		(min_thickness 0.25)
		(keepout
			(tracks not_allowed)
			(vias allowed)
			(pads allowed)
			(copperpour not_allowed)
			(footprints allowed)
		)
		(placement
			(enabled no)
			(sheetname "")
		)
		(fill yes
			(thermal_gap 0.5)
			(thermal_bridge_width 0.5)
			(island_removal_mode 0)
		)
		(polygon
			(pts
				(arc
					(start 274.517866 -239.17148)
					(mid 274.532745 -239.207401)
					(end 274.568666 -239.22228)
				)
				(arc
					(start 275.968206 -239.22228)
					(mid 276.004127 -239.207401)
					(end 276.019006 -239.17148)
				)
				(arc
					(start 276.019006 -238.76254)
					(mid 276.004127 -238.726619)
					(end 275.968206 -238.71174)
				)
				(arc
					(start 274.568666 -238.71174)
					(mid 274.532745 -238.726619)
					(end 274.517866 -238.76254)
				)
			)
		)
	)
	(zone
		(layers "In1.Cu" "In2.Cu")
		(hatch none 0.5)
		(connect_pads
			(clearance 0)
		)
		(min_thickness 0.25)
		(keepout
			(tracks not_allowed)
			(vias allowed)
			(pads allowed)
			(copperpour not_allowed)
			(footprints allowed)
		)
		(placement
			(enabled no)
			(sheetname "")
		)
		(fill yes
			(thermal_gap 0.5)
			(thermal_bridge_width 0.5)
			(island_removal_mode 0)
		)
		(polygon
			(pts
				(arc
					(start 289.605466 -278.271478)
					(mid 289.620345 -278.307399)
					(end 289.656266 -278.322278)
				)
				(arc
					(start 291.055806 -278.322278)
					(mid 291.091727 -278.307399)
					(end 291.106606 -278.271478)
				)
				(arc
					(start 291.106606 -277.862538)
					(mid 291.091727 -277.826617)
					(end 291.055806 -277.811738)
				)
				(arc
					(start 289.656266 -277.811738)
					(mid 289.620345 -277.826617)
					(end 289.605466 -277.862538)
				)
			)
		)
	)
	(zone
		(layers "In1.Cu" "In2.Cu")
		(hatch none 0.5)
		(connect_pads
			(clearance 0)
		)
		(min_thickness 0.25)
		(keepout
			(tracks not_allowed)
			(vias allowed)
			(pads allowed)
			(copperpour not_allowed)
			(footprints allowed)
		)
		(placement
			(enabled no)
			(sheetname "")
		)
		(fill yes
			(thermal_gap 0.5)
			(thermal_bridge_width 0.5)
			(island_removal_mode 0)
		)
		(polygon
			(pts
				(arc
					(start 425.190666 -278.271478)
					(mid 425.205545 -278.307399)
					(end 425.241466 -278.322278)
				)
				(arc
					(start 426.641006 -278.322278)
					(mid 426.676927 -278.307399)
					(end 426.691806 -278.271478)
				)
				(arc
					(start 426.691806 -277.862538)
					(mid 426.676927 -277.826617)
					(end 426.641006 -277.811738)
				)
				(arc
					(start 425.241466 -277.811738)
					(mid 425.205545 -277.826617)
					(end 425.190666 -277.862538)
				)
			)
		)
	)
	(zone
		(layers "In1.Cu" "In2.Cu")
		(hatch none 0.5)
		(connect_pads
			(clearance 0)
		)
		(min_thickness 0.25)
		(keepout
			(tracks not_allowed)
			(vias allowed)
			(pads allowed)
			(copperpour not_allowed)
			(footprints allowed)
		)
		(placement
			(enabled no)
			(sheetname "")
		)
		(fill yes
			(thermal_gap 0.5)
			(thermal_bridge_width 0.5)
			(island_removal_mode 0)
		)
		(polygon
			(pts
				(arc
					(start 413.546798 -285.071312)
					(mid 413.561677 -285.107233)
					(end 413.597598 -285.122112)
				)
				(arc
					(start 414.997138 -285.122112)
					(mid 415.033059 -285.107233)
					(end 415.047938 -285.071312)
				)
				(arc
					(start 415.047938 -284.662372)
					(mid 415.033059 -284.626451)
					(end 414.997138 -284.611572)
				)
				(arc
					(start 413.597598 -284.611572)
					(mid 413.561677 -284.626451)
					(end 413.546798 -284.662372)
				)
			)
		)
	)
	(zone
		(layers "In1.Cu" "In2.Cu")
		(hatch none 0.5)
		(connect_pads
			(clearance 0)
		)
		(min_thickness 0.25)
		(keepout
			(tracks not_allowed)
			(vias allowed)
			(pads allowed)
			(copperpour not_allowed)
			(footprints allowed)
		)
		(placement
			(enabled no)
			(sheetname "")
		)
		(fill yes
			(thermal_gap 0.5)
			(thermal_bridge_width 0.5)
			(island_removal_mode 0)
		)
		(polygon
			(pts
				(arc
					(start 173.15053 -210.27136)
					(mid 173.165409 -210.307281)
					(end 173.20133 -210.32216)
				)
				(arc
					(start 174.60087 -210.32216)
					(mid 174.636791 -210.307281)
					(end 174.65167 -210.27136)
				)
				(arc
					(start 174.65167 -209.86242)
					(mid 174.636791 -209.826499)
					(end 174.60087 -209.81162)
				)
				(arc
					(start 173.20133 -209.81162)
					(mid 173.165409 -209.826499)
					(end 173.15053 -209.86242)
				)
			)
		)
	)
	(zone
		(layers "In1.Cu" "In2.Cu")
		(hatch none 0.5)
		(connect_pads
			(clearance 0)
		)
		(min_thickness 0.25)
		(keepout
			(tracks not_allowed)
			(vias allowed)
			(pads allowed)
			(copperpour not_allowed)
			(footprints allowed)
		)
		(placement
			(enabled no)
			(sheetname "")
		)
		(fill yes
			(thermal_gap 0.5)
			(thermal_bridge_width 0.5)
			(island_removal_mode 0)
		)
		(polygon
			(pts
				(arc
					(start 436.178198 -244.271292)
					(mid 436.193077 -244.307213)
					(end 436.228998 -244.322092)
				)
				(arc
					(start 437.628538 -244.322092)
					(mid 437.664459 -244.307213)
					(end 437.679338 -244.271292)
				)
				(arc
					(start 437.679338 -243.862352)
					(mid 437.664459 -243.826431)
					(end 437.628538 -243.811552)
				)
				(arc
					(start 436.228998 -243.811552)
					(mid 436.193077 -243.826431)
					(end 436.178198 -243.862352)
				)
			)
		)
	)
	(zone
		(layers "In1.Cu" "In2.Cu")
		(hatch none 0.5)
		(connect_pads
			(clearance 0)
		)
		(min_thickness 0.25)
		(keepout
			(tracks not_allowed)
			(vias allowed)
			(pads allowed)
			(copperpour not_allowed)
			(footprints allowed)
		)
		(placement
			(enabled no)
			(sheetname "")
		)
		(fill yes
			(thermal_gap 0.5)
			(thermal_bridge_width 0.5)
			(island_removal_mode 0)
		)
		(polygon
			(pts
				(arc
					(start 173.15053 -294.421306)
					(mid 173.165409 -294.457227)
					(end 173.20133 -294.472106)
				)
				(arc
					(start 174.60087 -294.472106)
					(mid 174.636791 -294.457227)
					(end 174.65167 -294.421306)
				)
				(arc
					(start 174.65167 -294.012366)
					(mid 174.636791 -293.976445)
					(end 174.60087 -293.961566)
				)
				(arc
					(start 173.20133 -293.961566)
					(mid 173.165409 -293.976445)
					(end 173.15053 -294.012366)
				)
			)
		)
	)
	(zone
		(layers "In1.Cu" "In2.Cu")
		(hatch none 0.5)
		(connect_pads
			(clearance 0)
		)
		(min_thickness 0.25)
		(keepout
			(tracks not_allowed)
			(vias allowed)
			(pads allowed)
			(copperpour not_allowed)
			(footprints allowed)
		)
		(placement
			(enabled no)
			(sheetname "")
		)
		(fill yes
			(thermal_gap 0.5)
			(thermal_bridge_width 0.5)
			(island_removal_mode 0)
		)
		(polygon
			(pts
				(arc
					(start 425.190666 -237.471458)
					(mid 425.205545 -237.507379)
					(end 425.241466 -237.522258)
				)
				(arc
					(start 426.641006 -237.522258)
					(mid 426.676927 -237.507379)
					(end 426.691806 -237.471458)
				)
				(arc
					(start 426.691806 -237.062518)
					(mid 426.676927 -237.026597)
					(end 426.641006 -237.011718)
				)
				(arc
					(start 425.241466 -237.011718)
					(mid 425.205545 -237.026597)
					(end 425.190666 -237.062518)
				)
			)
		)
	)
	(zone
		(layers "In1.Cu" "In2.Cu")
		(hatch none 0.5)
		(connect_pads
			(clearance 0)
		)
		(min_thickness 0.25)
		(keepout
			(tracks not_allowed)
			(vias allowed)
			(pads allowed)
			(copperpour not_allowed)
			(footprints allowed)
		)
		(placement
			(enabled no)
			(sheetname "")
		)
		(fill yes
			(thermal_gap 0.5)
			(thermal_bridge_width 0.5)
			(island_removal_mode 0)
		)
		(polygon
			(pts
				(arc
					(start 285.505398 -204.32141)
					(mid 285.520277 -204.357331)
					(end 285.556198 -204.37221)
				)
				(arc
					(start 286.955738 -204.37221)
					(mid 286.991659 -204.357331)
					(end 287.006538 -204.32141)
				)
				(arc
					(start 287.006538 -203.91247)
					(mid 286.991659 -203.876549)
					(end 286.955738 -203.86167)
				)
				(arc
					(start 285.556198 -203.86167)
					(mid 285.520277 -203.876549)
					(end 285.505398 -203.91247)
				)
			)
		)
	)
	(zone
		(layers "In1.Cu" "In2.Cu")
		(hatch none 0.5)
		(connect_pads
			(clearance 0)
		)
		(min_thickness 0.25)
		(keepout
			(tracks not_allowed)
			(vias allowed)
			(pads allowed)
			(copperpour not_allowed)
			(footprints allowed)
		)
		(placement
			(enabled no)
			(sheetname "")
		)
		(fill yes
			(thermal_gap 0.5)
			(thermal_bridge_width 0.5)
			(island_removal_mode 0)
		)
		(polygon
			(pts
				(arc
					(start 19.033998 -246.821452)
					(mid 19.048877 -246.857373)
					(end 19.084798 -246.872252)
				)
				(arc
					(start 20.484338 -246.872252)
					(mid 20.520259 -246.857373)
					(end 20.535138 -246.821452)
				)
				(arc
					(start 20.535138 -246.412512)
					(mid 20.520259 -246.376591)
					(end 20.484338 -246.361712)
				)
				(arc
					(start 19.084798 -246.361712)
					(mid 19.048877 -246.376591)
					(end 19.033998 -246.412512)
				)
			)
		)
	)
	(zone
		(layers "In1.Cu" "In2.Cu")
		(hatch none 0.5)
		(connect_pads
			(clearance 0)
		)
		(min_thickness 0.25)
		(keepout
			(tracks not_allowed)
			(vias allowed)
			(pads allowed)
			(copperpour not_allowed)
			(footprints allowed)
		)
		(placement
			(enabled no)
			(sheetname "")
		)
		(fill yes
			(thermal_gap 0.5)
			(thermal_bridge_width 0.5)
			(island_removal_mode 0)
		)
		(polygon
			(pts
				(arc
					(start 210.86953 -198.37146)
					(mid 210.884409 -198.407381)
					(end 210.92033 -198.42226)
				)
				(arc
					(start 212.31987 -198.42226)
					(mid 212.355791 -198.407381)
					(end 212.37067 -198.37146)
				)
				(arc
					(start 212.37067 -197.96252)
					(mid 212.355791 -197.926599)
					(end 212.31987 -197.91172)
				)
				(arc
					(start 210.92033 -197.91172)
					(mid 210.884409 -197.926599)
					(end 210.86953 -197.96252)
				)
			)
		)
	)
	(zone
		(layers "In1.Cu" "In2.Cu")
		(hatch none 0.5)
		(connect_pads
			(clearance 0)
		)
		(min_thickness 0.25)
		(keepout
			(tracks not_allowed)
			(vias allowed)
			(pads allowed)
			(copperpour not_allowed)
			(footprints allowed)
		)
		(placement
			(enabled no)
			(sheetname "")
		)
		(fill yes
			(thermal_gap 0.5)
			(thermal_bridge_width 0.5)
			(island_removal_mode 0)
		)
		(polygon
			(pts
				(arc
					(start 285.505398 -259.57149)
					(mid 285.520277 -259.607411)
					(end 285.556198 -259.62229)
				)
				(arc
					(start 286.955738 -259.62229)
					(mid 286.991659 -259.607411)
					(end 287.006538 -259.57149)
				)
				(arc
					(start 287.006538 -259.16255)
					(mid 286.991659 -259.126629)
					(end 286.955738 -259.11175)
				)
				(arc
					(start 285.556198 -259.11175)
					(mid 285.520277 -259.126629)
					(end 285.505398 -259.16255)
				)
			)
		)
	)
	(zone
		(layers "In1.Cu" "In2.Cu")
		(hatch none 0.5)
		(connect_pads
			(clearance 0)
		)
		(min_thickness 0.25)
		(keepout
			(tracks not_allowed)
			(vias allowed)
			(pads allowed)
			(copperpour not_allowed)
			(footprints allowed)
		)
		(placement
			(enabled no)
			(sheetname "")
		)
		(fill yes
			(thermal_gap 0.5)
			(thermal_bridge_width 0.5)
			(island_removal_mode 0)
		)
		(polygon
			(pts
				(arc
					(start 274.517866 -293.571422)
					(mid 274.532745 -293.607343)
					(end 274.568666 -293.622222)
				)
				(arc
					(start 275.968206 -293.622222)
					(mid 276.004127 -293.607343)
					(end 276.019006 -293.571422)
				)
				(arc
					(start 276.019006 -293.162482)
					(mid 276.004127 -293.126561)
					(end 275.968206 -293.111682)
				)
				(arc
					(start 274.568666 -293.111682)
					(mid 274.532745 -293.126561)
					(end 274.517866 -293.162482)
				)
			)
		)
	)
	(zone
		(layers "In1.Cu" "In2.Cu")
		(hatch none 0.5)
		(connect_pads
			(clearance 0)
		)
		(min_thickness 0.25)
		(keepout
			(tracks not_allowed)
			(vias allowed)
			(pads allowed)
			(copperpour not_allowed)
			(footprints allowed)
		)
		(placement
			(enabled no)
			(sheetname "")
		)
		(fill yes
			(thermal_gap 0.5)
			(thermal_bridge_width 0.5)
			(island_removal_mode 0)
		)
		(polygon
			(pts
				(arc
					(start 7.39013 -259.57149)
					(mid 7.405009 -259.607411)
					(end 7.44093 -259.62229)
				)
				(arc
					(start 8.84047 -259.62229)
					(mid 8.876391 -259.607411)
					(end 8.89127 -259.57149)
				)
				(arc
					(start 8.89127 -259.16255)
					(mid 8.876391 -259.126629)
					(end 8.84047 -259.11175)
				)
				(arc
					(start 7.44093 -259.11175)
					(mid 7.405009 -259.126629)
					(end 7.39013 -259.16255)
				)
			)
		)
	)
	(zone
		(layers "In1.Cu" "In2.Cu")
		(hatch none 0.5)
		(connect_pads
			(clearance 0)
		)
		(min_thickness 0.25)
		(keepout
			(tracks not_allowed)
			(vias allowed)
			(pads allowed)
			(copperpour not_allowed)
			(footprints allowed)
		)
		(placement
			(enabled no)
			(sheetname "")
		)
		(fill yes
			(thermal_gap 0.5)
			(thermal_bridge_width 0.5)
			(island_removal_mode 0)
		)
		(polygon
			(pts
				(arc
					(start 300.592998 -308.871366)
					(mid 300.607877 -308.907287)
					(end 300.643798 -308.922166)
				)
				(arc
					(start 302.043338 -308.922166)
					(mid 302.079259 -308.907287)
					(end 302.094138 -308.871366)
				)
				(arc
					(start 302.094138 -308.462426)
					(mid 302.079259 -308.426505)
					(end 302.043338 -308.411626)
				)
				(arc
					(start 300.643798 -308.411626)
					(mid 300.607877 -308.426505)
					(end 300.592998 -308.462426)
				)
			)
		)
	)
	(zone
		(layers "In1.Cu" "In2.Cu")
		(hatch none 0.5)
		(connect_pads
			(clearance 0)
		)
		(min_thickness 0.25)
		(keepout
			(tracks not_allowed)
			(vias allowed)
			(pads allowed)
			(copperpour not_allowed)
			(footprints allowed)
		)
		(placement
			(enabled no)
			(sheetname "")
		)
		(fill yes
			(thermal_gap 0.5)
			(thermal_bridge_width 0.5)
			(island_removal_mode 0)
		)
		(polygon
			(pts
				(arc
					(start 304.693066 -278.271478)
					(mid 304.707945 -278.307399)
					(end 304.743866 -278.322278)
				)
				(arc
					(start 306.143406 -278.322278)
					(mid 306.179327 -278.307399)
					(end 306.194206 -278.271478)
				)
				(arc
					(start 306.194206 -277.862538)
					(mid 306.179327 -277.826617)
					(end 306.143406 -277.811738)
				)
				(arc
					(start 304.743866 -277.811738)
					(mid 304.707945 -277.826617)
					(end 304.693066 -277.862538)
				)
			)
		)
	)
	(zone
		(layers "In1.Cu" "In2.Cu")
		(hatch none 0.5)
		(connect_pads
			(clearance 0)
		)
		(min_thickness 0.25)
		(keepout
			(tracks not_allowed)
			(vias allowed)
			(pads allowed)
			(copperpour not_allowed)
			(footprints allowed)
		)
		(placement
			(enabled no)
			(sheetname "")
		)
		(fill yes
			(thermal_gap 0.5)
			(thermal_bridge_width 0.5)
			(island_removal_mode 0)
		)
		(polygon
			(pts
				(arc
					(start 455.365866 -220.471492)
					(mid 455.380745 -220.507413)
					(end 455.416666 -220.522292)
				)
				(arc
					(start 456.816206 -220.522292)
					(mid 456.852127 -220.507413)
					(end 456.867006 -220.471492)
				)
				(arc
					(start 456.867006 -220.062552)
					(mid 456.852127 -220.026631)
					(end 456.816206 -220.011752)
				)
				(arc
					(start 455.416666 -220.011752)
					(mid 455.380745 -220.026631)
					(end 455.365866 -220.062552)
				)
			)
		)
	)
	(zone
		(layers "In1.Cu" "In2.Cu")
		(hatch none 0.5)
		(connect_pads
			(clearance 0)
		)
		(min_thickness 0.25)
		(keepout
			(tracks not_allowed)
			(vias allowed)
			(pads allowed)
			(copperpour not_allowed)
			(footprints allowed)
		)
		(placement
			(enabled no)
			(sheetname "")
		)
		(fill yes
			(thermal_gap 0.5)
			(thermal_bridge_width 0.5)
			(island_removal_mode 0)
		)
		(polygon
			(pts
				(arc
					(start 199.881998 -246.821452)
					(mid 199.896877 -246.857373)
					(end 199.932798 -246.872252)
				)
				(arc
					(start 201.332338 -246.872252)
					(mid 201.368259 -246.857373)
					(end 201.383138 -246.821452)
				)
				(arc
					(start 201.383138 -246.412512)
					(mid 201.368259 -246.376591)
					(end 201.332338 -246.361712)
				)
				(arc
					(start 199.932798 -246.361712)
					(mid 199.896877 -246.376591)
					(end 199.881998 -246.412512)
				)
			)
		)
	)
	(zone
		(layers "In1.Cu" "In2.Cu")
		(hatch none 0.5)
		(connect_pads
			(clearance 0)
		)
		(min_thickness 0.25)
		(keepout
			(tracks not_allowed)
			(vias allowed)
			(pads allowed)
			(copperpour not_allowed)
			(footprints allowed)
		)
		(placement
			(enabled no)
			(sheetname "")
		)
		(fill yes
			(thermal_gap 0.5)
			(thermal_bridge_width 0.5)
			(island_removal_mode 0)
		)
		(polygon
			(pts
				(arc
					(start 14.93393 -224.72142)
					(mid 14.948809 -224.757341)
					(end 14.98473 -224.77222)
				)
				(arc
					(start 16.38427 -224.77222)
					(mid 16.420191 -224.757341)
					(end 16.43507 -224.72142)
				)
				(arc
					(start 16.43507 -224.31248)
					(mid 16.420191 -224.276559)
					(end 16.38427 -224.26168)
				)
				(arc
					(start 14.98473 -224.26168)
					(mid 14.948809 -224.276559)
					(end 14.93393 -224.31248)
				)
			)
		)
	)
	(zone
		(layers "In1.Cu" "In2.Cu")
		(hatch none 0.5)
		(connect_pads
			(clearance 0)
		)
		(min_thickness 0.25)
		(keepout
			(tracks not_allowed)
			(vias allowed)
			(pads allowed)
			(copperpour not_allowed)
			(footprints allowed)
		)
		(placement
			(enabled no)
			(sheetname "")
		)
		(fill yes
			(thermal_gap 0.5)
			(thermal_bridge_width 0.5)
			(island_removal_mode 0)
		)
		(polygon
			(pts
				(arc
					(start 432.734466 -262.121396)
					(mid 432.749345 -262.157317)
					(end 432.785266 -262.172196)
				)
				(arc
					(start 434.184806 -262.172196)
					(mid 434.220727 -262.157317)
					(end 434.235606 -262.121396)
				)
				(arc
					(start 434.235606 -261.712456)
					(mid 434.220727 -261.676535)
					(end 434.184806 -261.661656)
				)
				(arc
					(start 432.785266 -261.661656)
					(mid 432.749345 -261.676535)
					(end 432.734466 -261.712456)
				)
			)
		)
	)
	(zone
		(layers "In1.Cu" "In2.Cu")
		(hatch none 0.5)
		(connect_pads
			(clearance 0)
		)
		(min_thickness 0.25)
		(keepout
			(tracks not_allowed)
			(vias allowed)
			(pads allowed)
			(copperpour not_allowed)
			(footprints allowed)
		)
		(placement
			(enabled no)
			(sheetname "")
		)
		(fill yes
			(thermal_gap 0.5)
			(thermal_bridge_width 0.5)
			(island_removal_mode 0)
		)
		(polygon
			(pts
				(arc
					(start 192.338198 -295.271444)
					(mid 192.353077 -295.307365)
					(end 192.388998 -295.322244)
				)
				(arc
					(start 193.788538 -295.322244)
					(mid 193.824459 -295.307365)
					(end 193.839338 -295.271444)
				)
				(arc
					(start 193.839338 -294.862504)
					(mid 193.824459 -294.826583)
					(end 193.788538 -294.811704)
				)
				(arc
					(start 192.388998 -294.811704)
					(mid 192.353077 -294.826583)
					(end 192.338198 -294.862504)
				)
			)
		)
	)
	(zone
		(layers "In1.Cu" "In2.Cu")
		(hatch none 0.5)
		(connect_pads
			(clearance 0)
		)
		(min_thickness 0.25)
		(keepout
			(tracks not_allowed)
			(vias allowed)
			(pads allowed)
			(copperpour not_allowed)
			(footprints allowed)
		)
		(placement
			(enabled no)
			(sheetname "")
		)
		(fill yes
			(thermal_gap 0.5)
			(thermal_bridge_width 0.5)
			(island_removal_mode 0)
		)
		(polygon
			(pts
				(arc
					(start 285.505398 -297.82135)
					(mid 285.520277 -297.857271)
					(end 285.556198 -297.87215)
				)
				(arc
					(start 286.955738 -297.87215)
					(mid 286.991659 -297.857271)
					(end 287.006538 -297.82135)
				)
				(arc
					(start 287.006538 -297.41241)
					(mid 286.991659 -297.376489)
					(end 286.955738 -297.36161)
				)
				(arc
					(start 285.556198 -297.36161)
					(mid 285.520277 -297.376489)
					(end 285.505398 -297.41241)
				)
			)
		)
	)
	(zone
		(layers "In1.Cu" "In2.Cu")
		(hatch none 0.5)
		(connect_pads
			(clearance 0)
		)
		(min_thickness 0.25)
		(keepout
			(tracks not_allowed)
			(vias allowed)
			(pads allowed)
			(copperpour not_allowed)
			(footprints allowed)
		)
		(placement
			(enabled no)
			(sheetname "")
		)
		(fill yes
			(thermal_gap 0.5)
			(thermal_bridge_width 0.5)
			(island_removal_mode 0)
		)
		(polygon
			(pts
				(arc
					(start 188.23813 -296.121328)
					(mid 188.253009 -296.157249)
					(end 188.28893 -296.172128)
				)
				(arc
					(start 189.68847 -296.172128)
					(mid 189.724391 -296.157249)
					(end 189.73927 -296.121328)
				)
				(arc
					(start 189.73927 -295.712388)
					(mid 189.724391 -295.676467)
					(end 189.68847 -295.661588)
				)
				(arc
					(start 188.28893 -295.661588)
					(mid 188.253009 -295.676467)
					(end 188.23813 -295.712388)
				)
			)
		)
	)
	(zone
		(layers "In1.Cu" "In2.Cu")
		(hatch none 0.5)
		(connect_pads
			(clearance 0)
		)
		(min_thickness 0.25)
		(keepout
			(tracks not_allowed)
			(vias allowed)
			(pads allowed)
			(copperpour not_allowed)
			(footprints allowed)
		)
		(placement
			(enabled no)
			(sheetname "")
		)
		(fill yes
			(thermal_gap 0.5)
			(thermal_bridge_width 0.5)
			(island_removal_mode 0)
		)
		(polygon
			(pts
				(arc
					(start 458.809598 -269.771368)
					(mid 458.824477 -269.807289)
					(end 458.860398 -269.822168)
				)
				(arc
					(start 460.259938 -269.822168)
					(mid 460.295859 -269.807289)
					(end 460.310738 -269.771368)
				)
				(arc
					(start 460.310738 -269.362428)
					(mid 460.295859 -269.326507)
					(end 460.259938 -269.311628)
				)
				(arc
					(start 458.860398 -269.311628)
					(mid 458.824477 -269.326507)
					(end 458.809598 -269.362428)
				)
			)
		)
	)
	(zone
		(layers "In1.Cu" "In2.Cu")
		(hatch none 0.5)
		(connect_pads
			(clearance 0)
		)
		(min_thickness 0.25)
		(keepout
			(tracks not_allowed)
			(vias allowed)
			(pads allowed)
			(copperpour not_allowed)
			(footprints allowed)
		)
		(placement
			(enabled no)
			(sheetname "")
		)
		(fill yes
			(thermal_gap 0.5)
			(thermal_bridge_width 0.5)
			(island_removal_mode 0)
		)
		(polygon
			(pts
				(arc
					(start 184.794398 -263.821418)
					(mid 184.809277 -263.857339)
					(end 184.845198 -263.872218)
				)
				(arc
					(start 186.244738 -263.872218)
					(mid 186.280659 -263.857339)
					(end 186.295538 -263.821418)
				)
				(arc
					(start 186.295538 -263.412478)
					(mid 186.280659 -263.376557)
					(end 186.244738 -263.361678)
				)
				(arc
					(start 184.845198 -263.361678)
					(mid 184.809277 -263.376557)
					(end 184.794398 -263.412478)
				)
			)
		)
	)
	(zone
		(layers "In1.Cu" "In2.Cu")
		(hatch none 0.5)
		(connect_pads
			(clearance 0)
		)
		(min_thickness 0.25)
		(keepout
			(tracks not_allowed)
			(vias allowed)
			(pads allowed)
			(copperpour not_allowed)
			(footprints allowed)
		)
		(placement
			(enabled no)
			(sheetname "")
		)
		(fill yes
			(thermal_gap 0.5)
			(thermal_bridge_width 0.5)
			(island_removal_mode 0)
		)
		(polygon
			(pts
				(arc
					(start 177.250598 -209.421476)
					(mid 177.265477 -209.457397)
					(end 177.301398 -209.472276)
				)
				(arc
					(start 178.700938 -209.472276)
					(mid 178.736859 -209.457397)
					(end 178.751738 -209.421476)
				)
				(arc
					(start 178.751738 -209.012536)
					(mid 178.736859 -208.976615)
					(end 178.700938 -208.961736)
				)
				(arc
					(start 177.301398 -208.961736)
					(mid 177.265477 -208.976615)
					(end 177.250598 -209.012536)
				)
			)
		)
	)
	(zone
		(layers "In1.Cu" "In2.Cu")
		(hatch none 0.5)
		(connect_pads
			(clearance 0)
		)
		(min_thickness 0.25)
		(keepout
			(tracks not_allowed)
			(vias allowed)
			(pads allowed)
			(copperpour not_allowed)
			(footprints allowed)
		)
		(placement
			(enabled no)
			(sheetname "")
		)
		(fill yes
			(thermal_gap 0.5)
			(thermal_bridge_width 0.5)
			(island_removal_mode 0)
		)
		(polygon
			(pts
				(arc
					(start 52.65293 -284.221428)
					(mid 52.667809 -284.257349)
					(end 52.70373 -284.272228)
				)
				(arc
					(start 54.10327 -284.272228)
					(mid 54.139191 -284.257349)
					(end 54.15407 -284.221428)
				)
				(arc
					(start 54.15407 -283.812488)
					(mid 54.139191 -283.776567)
					(end 54.10327 -283.761688)
				)
				(arc
					(start 52.70373 -283.761688)
					(mid 52.667809 -283.776567)
					(end 52.65293 -283.812488)
				)
			)
		)
	)
	(zone
		(layers "In1.Cu" "In2.Cu")
		(hatch none 0.5)
		(connect_pads
			(clearance 0)
		)
		(min_thickness 0.25)
		(keepout
			(tracks not_allowed)
			(vias allowed)
			(pads allowed)
			(copperpour not_allowed)
			(footprints allowed)
		)
		(placement
			(enabled no)
			(sheetname "")
		)
		(fill yes
			(thermal_gap 0.5)
			(thermal_bridge_width 0.5)
			(island_removal_mode 0)
		)
		(polygon
			(pts
				(arc
					(start 293.049198 -271.47139)
					(mid 293.064077 -271.507311)
					(end 293.099998 -271.52219)
				)
				(arc
					(start 294.499538 -271.52219)
					(mid 294.535459 -271.507311)
					(end 294.550338 -271.47139)
				)
				(arc
					(start 294.550338 -271.06245)
					(mid 294.535459 -271.026529)
					(end 294.499538 -271.01165)
				)
				(arc
					(start 293.099998 -271.01165)
					(mid 293.064077 -271.026529)
					(end 293.049198 -271.06245)
				)
			)
		)
	)
	(zone
		(layers "In1.Cu" "In2.Cu")
		(hatch none 0.5)
		(connect_pads
			(clearance 0)
		)
		(min_thickness 0.25)
		(keepout
			(tracks not_allowed)
			(vias allowed)
			(pads allowed)
			(copperpour not_allowed)
			(footprints allowed)
		)
		(placement
			(enabled no)
			(sheetname "")
		)
		(fill yes
			(thermal_gap 0.5)
			(thermal_bridge_width 0.5)
			(island_removal_mode 0)
		)
		(polygon
			(pts
				(arc
					(start 37.56533 -226.421442)
					(mid 37.580209 -226.457363)
					(end 37.61613 -226.472242)
				)
				(arc
					(start 39.01567 -226.472242)
					(mid 39.051591 -226.457363)
					(end 39.06647 -226.421442)
				)
				(arc
					(start 39.06647 -226.012502)
					(mid 39.051591 -225.976581)
					(end 39.01567 -225.961702)
				)
				(arc
					(start 37.61613 -225.961702)
					(mid 37.580209 -225.976581)
					(end 37.56533 -226.012502)
				)
			)
		)
	)
	(zone
		(layers "In1.Cu" "In2.Cu")
		(hatch none 0.5)
		(connect_pads
			(clearance 0)
		)
		(min_thickness 0.25)
		(keepout
			(tracks not_allowed)
			(vias allowed)
			(pads allowed)
			(copperpour not_allowed)
			(footprints allowed)
		)
		(placement
			(enabled no)
			(sheetname "")
		)
		(fill yes
			(thermal_gap 0.5)
			(thermal_bridge_width 0.5)
			(island_removal_mode 0)
		)
		(polygon
			(pts
				(arc
					(start 162.162998 -195.821554)
					(mid 162.177877 -195.857475)
					(end 162.213798 -195.872354)
				)
				(arc
					(start 163.613338 -195.872354)
					(mid 163.649259 -195.857475)
					(end 163.664138 -195.821554)
				)
				(arc
					(start 163.664138 -195.412614)
					(mid 163.649259 -195.376693)
					(end 163.613338 -195.361814)
				)
				(arc
					(start 162.213798 -195.361814)
					(mid 162.177877 -195.376693)
					(end 162.162998 -195.412614)
				)
			)
		)
	)
	(zone
		(layers "In1.Cu" "In2.Cu")
		(hatch none 0.5)
		(connect_pads
			(clearance 0)
		)
		(min_thickness 0.25)
		(keepout
			(tracks not_allowed)
			(vias allowed)
			(pads allowed)
			(copperpour not_allowed)
			(footprints allowed)
		)
		(placement
			(enabled no)
			(sheetname "")
		)
		(fill yes
			(thermal_gap 0.5)
			(thermal_bridge_width 0.5)
			(island_removal_mode 0)
		)
		(polygon
			(pts
				(arc
					(start 285.505398 -305.471322)
					(mid 285.520277 -305.507243)
					(end 285.556198 -305.522122)
				)
				(arc
					(start 286.955738 -305.522122)
					(mid 286.991659 -305.507243)
					(end 287.006538 -305.471322)
				)
				(arc
					(start 287.006538 -305.062382)
					(mid 286.991659 -305.026461)
					(end 286.955738 -305.011582)
				)
				(arc
					(start 285.556198 -305.011582)
					(mid 285.520277 -305.026461)
					(end 285.505398 -305.062382)
				)
			)
		)
	)
	(zone
		(layers "In1.Cu" "In2.Cu")
		(hatch none 0.5)
		(connect_pads
			(clearance 0)
		)
		(min_thickness 0.25)
		(keepout
			(tracks not_allowed)
			(vias allowed)
			(pads allowed)
			(copperpour not_allowed)
			(footprints allowed)
		)
		(placement
			(enabled no)
			(sheetname "")
		)
		(fill yes
			(thermal_gap 0.5)
			(thermal_bridge_width 0.5)
			(island_removal_mode 0)
		)
		(polygon
			(pts
				(arc
					(start 259.430266 -216.22131)
					(mid 259.445145 -216.257231)
					(end 259.481066 -216.27211)
				)
				(arc
					(start 260.880606 -216.27211)
					(mid 260.916527 -216.257231)
					(end 260.931406 -216.22131)
				)
				(arc
					(start 260.931406 -215.81237)
					(mid 260.916527 -215.776449)
					(end 260.880606 -215.76157)
				)
				(arc
					(start 259.481066 -215.76157)
					(mid 259.445145 -215.776449)
					(end 259.430266 -215.81237)
				)
			)
		)
	)
	(zone
		(layers "In1.Cu" "In2.Cu")
		(hatch none 0.5)
		(connect_pads
			(clearance 0)
		)
		(min_thickness 0.25)
		(keepout
			(tracks not_allowed)
			(vias allowed)
			(pads allowed)
			(copperpour not_allowed)
			(footprints allowed)
		)
		(placement
			(enabled no)
			(sheetname "")
		)
		(fill yes
			(thermal_gap 0.5)
			(thermal_bridge_width 0.5)
			(island_removal_mode 0)
		)
		(polygon
			(pts
				(arc
					(start 458.809598 -200.921366)
					(mid 458.824477 -200.957287)
					(end 458.860398 -200.972166)
				)
				(arc
					(start 460.259938 -200.972166)
					(mid 460.295859 -200.957287)
					(end 460.310738 -200.921366)
				)
				(arc
					(start 460.310738 -200.512426)
					(mid 460.295859 -200.476505)
					(end 460.259938 -200.461626)
				)
				(arc
					(start 458.860398 -200.461626)
					(mid 458.824477 -200.476505)
					(end 458.809598 -200.512426)
				)
			)
		)
	)
	(zone
		(layers "In1.Cu" "In2.Cu")
		(hatch none 0.5)
		(connect_pads
			(clearance 0)
		)
		(min_thickness 0.25)
		(keepout
			(tracks not_allowed)
			(vias allowed)
			(pads allowed)
			(copperpour not_allowed)
			(footprints allowed)
		)
		(placement
			(enabled no)
			(sheetname "")
		)
		(fill yes
			(thermal_gap 0.5)
			(thermal_bridge_width 0.5)
			(island_removal_mode 0)
		)
		(polygon
			(pts
				(arc
					(start 293.049198 -308.871366)
					(mid 293.064077 -308.907287)
					(end 293.099998 -308.922166)
				)
				(arc
					(start 294.499538 -308.922166)
					(mid 294.535459 -308.907287)
					(end 294.550338 -308.871366)
				)
				(arc
					(start 294.550338 -308.462426)
					(mid 294.535459 -308.426505)
					(end 294.499538 -308.411626)
				)
				(arc
					(start 293.099998 -308.411626)
					(mid 293.064077 -308.426505)
					(end 293.049198 -308.462426)
				)
			)
		)
	)
	(zone
		(layers "In1.Cu" "In2.Cu")
		(hatch none 0.5)
		(connect_pads
			(clearance 0)
		)
		(min_thickness 0.25)
		(keepout
			(tracks not_allowed)
			(vias allowed)
			(pads allowed)
			(copperpour not_allowed)
			(footprints allowed)
		)
		(placement
			(enabled no)
			(sheetname "")
		)
		(fill yes
			(thermal_gap 0.5)
			(thermal_bridge_width 0.5)
			(island_removal_mode 0)
		)
		(polygon
			(pts
				(arc
					(start 165.60673 -198.37146)
					(mid 165.621609 -198.407381)
					(end 165.65753 -198.42226)
				)
				(arc
					(start 167.05707 -198.42226)
					(mid 167.092991 -198.407381)
					(end 167.10787 -198.37146)
				)
				(arc
					(start 167.10787 -197.96252)
					(mid 167.092991 -197.926599)
					(end 167.05707 -197.91172)
				)
				(arc
					(start 165.65753 -197.91172)
					(mid 165.621609 -197.926599)
					(end 165.60673 -197.96252)
				)
			)
		)
	)
	(zone
		(layers "In1.Cu" "In2.Cu")
		(hatch none 0.5)
		(connect_pads
			(clearance 0)
		)
		(min_thickness 0.25)
		(keepout
			(tracks not_allowed)
			(vias allowed)
			(pads allowed)
			(copperpour not_allowed)
			(footprints allowed)
		)
		(placement
			(enabled no)
			(sheetname "")
		)
		(fill yes
			(thermal_gap 0.5)
			(thermal_bridge_width 0.5)
			(island_removal_mode 0)
		)
		(polygon
			(pts
				(arc
					(start 210.86953 -274.871434)
					(mid 210.884409 -274.907355)
					(end 210.92033 -274.922234)
				)
				(arc
					(start 212.31987 -274.922234)
					(mid 212.355791 -274.907355)
					(end 212.37067 -274.871434)
				)
				(arc
					(start 212.37067 -274.462494)
					(mid 212.355791 -274.426573)
					(end 212.31987 -274.411694)
				)
				(arc
					(start 210.92033 -274.411694)
					(mid 210.884409 -274.426573)
					(end 210.86953 -274.462494)
				)
			)
		)
	)
	(zone
		(layers "In1.Cu" "In2.Cu")
		(hatch none 0.5)
		(connect_pads
			(clearance 0)
		)
		(min_thickness 0.25)
		(keepout
			(tracks not_allowed)
			(vias allowed)
			(pads allowed)
			(copperpour not_allowed)
			(footprints allowed)
		)
		(placement
			(enabled no)
			(sheetname "")
		)
		(fill yes
			(thermal_gap 0.5)
			(thermal_bridge_width 0.5)
			(island_removal_mode 0)
		)
		(polygon
			(pts
				(arc
					(start 49.209198 -234.921298)
					(mid 49.224077 -234.957219)
					(end 49.259998 -234.972098)
				)
				(arc
					(start 50.659538 -234.972098)
					(mid 50.695459 -234.957219)
					(end 50.710338 -234.921298)
				)
				(arc
					(start 50.710338 -234.512358)
					(mid 50.695459 -234.476437)
					(end 50.659538 -234.461558)
				)
				(arc
					(start 49.259998 -234.461558)
					(mid 49.224077 -234.476437)
					(end 49.209198 -234.512358)
				)
			)
		)
	)
	(zone
		(layers "In1.Cu" "In2.Cu")
		(hatch none 0.5)
		(connect_pads
			(clearance 0)
		)
		(min_thickness 0.25)
		(keepout
			(tracks not_allowed)
			(vias allowed)
			(pads allowed)
			(copperpour not_allowed)
			(footprints allowed)
		)
		(placement
			(enabled no)
			(sheetname "")
		)
		(fill yes
			(thermal_gap 0.5)
			(thermal_bridge_width 0.5)
			(island_removal_mode 0)
		)
		(polygon
			(pts
				(arc
					(start 312.236866 -272.321528)
					(mid 312.251745 -272.357449)
					(end 312.287666 -272.372328)
				)
				(arc
					(start 313.687206 -272.372328)
					(mid 313.723127 -272.357449)
					(end 313.738006 -272.321528)
				)
				(arc
					(start 313.738006 -271.912588)
					(mid 313.723127 -271.876667)
					(end 313.687206 -271.861788)
				)
				(arc
					(start 312.287666 -271.861788)
					(mid 312.251745 -271.876667)
					(end 312.236866 -271.912588)
				)
			)
		)
	)
	(zone
		(layers "In1.Cu" "In2.Cu")
		(hatch none 0.5)
		(connect_pads
			(clearance 0)
		)
		(min_thickness 0.25)
		(keepout
			(tracks not_allowed)
			(vias allowed)
			(pads allowed)
			(copperpour not_allowed)
			(footprints allowed)
		)
		(placement
			(enabled no)
			(sheetname "")
		)
		(fill yes
			(thermal_gap 0.5)
			(thermal_bridge_width 0.5)
			(island_removal_mode 0)
		)
		(polygon
			(pts
				(arc
					(start 312.236866 -212.82152)
					(mid 312.251745 -212.857441)
					(end 312.287666 -212.87232)
				)
				(arc
					(start 313.687206 -212.87232)
					(mid 313.723127 -212.857441)
					(end 313.738006 -212.82152)
				)
				(arc
					(start 313.738006 -212.41258)
					(mid 313.723127 -212.376659)
					(end 313.687206 -212.36178)
				)
				(arc
					(start 312.287666 -212.36178)
					(mid 312.251745 -212.376659)
					(end 312.236866 -212.41258)
				)
			)
		)
	)
	(zone
		(layers "In1.Cu" "In2.Cu")
		(hatch none 0.5)
		(connect_pads
			(clearance 0)
		)
		(min_thickness 0.25)
		(keepout
			(tracks not_allowed)
			(vias allowed)
			(pads allowed)
			(copperpour not_allowed)
			(footprints allowed)
		)
		(placement
			(enabled no)
			(sheetname "")
		)
		(fill yes
			(thermal_gap 0.5)
			(thermal_bridge_width 0.5)
			(island_removal_mode 0)
		)
		(polygon
			(pts
				(arc
					(start 165.60673 -228.971348)
					(mid 165.621609 -229.007269)
					(end 165.65753 -229.022148)
				)
				(arc
					(start 167.05707 -229.022148)
					(mid 167.092991 -229.007269)
					(end 167.10787 -228.971348)
				)
				(arc
					(start 167.10787 -228.562408)
					(mid 167.092991 -228.526487)
					(end 167.05707 -228.511608)
				)
				(arc
					(start 165.65753 -228.511608)
					(mid 165.621609 -228.526487)
					(end 165.60673 -228.562408)
				)
			)
		)
	)
	(zone
		(layers "In1.Cu" "In2.Cu")
		(hatch none 0.5)
		(connect_pads
			(clearance 0)
		)
		(min_thickness 0.25)
		(keepout
			(tracks not_allowed)
			(vias allowed)
			(pads allowed)
			(copperpour not_allowed)
			(footprints allowed)
		)
		(placement
			(enabled no)
			(sheetname "")
		)
		(fill yes
			(thermal_gap 0.5)
			(thermal_bridge_width 0.5)
			(island_removal_mode 0)
		)
		(polygon
			(pts
				(arc
					(start 199.881998 -268.921484)
					(mid 199.896877 -268.957405)
					(end 199.932798 -268.972284)
				)
				(arc
					(start 201.332338 -268.972284)
					(mid 201.368259 -268.957405)
					(end 201.383138 -268.921484)
				)
				(arc
					(start 201.383138 -268.512544)
					(mid 201.368259 -268.476623)
					(end 201.332338 -268.461744)
				)
				(arc
					(start 199.932798 -268.461744)
					(mid 199.896877 -268.476623)
					(end 199.881998 -268.512544)
				)
			)
		)
	)
	(zone
		(layers "In1.Cu" "In2.Cu")
		(hatch none 0.5)
		(connect_pads
			(clearance 0)
		)
		(min_thickness 0.25)
		(keepout
			(tracks not_allowed)
			(vias allowed)
			(pads allowed)
			(copperpour not_allowed)
			(footprints allowed)
		)
		(placement
			(enabled no)
			(sheetname "")
		)
		(fill yes
			(thermal_gap 0.5)
			(thermal_bridge_width 0.5)
			(island_removal_mode 0)
		)
		(polygon
			(pts
				(arc
					(start 417.646866 -206.871316)
					(mid 417.661745 -206.907237)
					(end 417.697666 -206.922116)
				)
				(arc
					(start 419.097206 -206.922116)
					(mid 419.133127 -206.907237)
					(end 419.148006 -206.871316)
				)
				(arc
					(start 419.148006 -206.462376)
					(mid 419.133127 -206.426455)
					(end 419.097206 -206.411576)
				)
				(arc
					(start 417.697666 -206.411576)
					(mid 417.661745 -206.426455)
					(end 417.646866 -206.462376)
				)
			)
		)
	)
	(zone
		(layers "In1.Cu" "In2.Cu")
		(hatch none 0.5)
		(connect_pads
			(clearance 0)
		)
		(min_thickness 0.25)
		(keepout
			(tracks not_allowed)
			(vias allowed)
			(pads allowed)
			(copperpour not_allowed)
			(footprints allowed)
		)
		(placement
			(enabled no)
			(sheetname "")
		)
		(fill yes
			(thermal_gap 0.5)
			(thermal_bridge_width 0.5)
			(island_removal_mode 0)
		)
		(polygon
			(pts
				(arc
					(start 19.033998 -293.571422)
					(mid 19.048877 -293.607343)
					(end 19.084798 -293.622222)
				)
				(arc
					(start 20.484338 -293.622222)
					(mid 20.520259 -293.607343)
					(end 20.535138 -293.571422)
				)
				(arc
					(start 20.535138 -293.162482)
					(mid 20.520259 -293.126561)
					(end 20.484338 -293.111682)
				)
				(arc
					(start 19.084798 -293.111682)
					(mid 19.048877 -293.126561)
					(end 19.033998 -293.162482)
				)
			)
		)
	)
	(zone
		(layers "In1.Cu" "In2.Cu")
		(hatch none 0.5)
		(connect_pads
			(clearance 0)
		)
		(min_thickness 0.25)
		(keepout
			(tracks not_allowed)
			(vias allowed)
			(pads allowed)
			(copperpour not_allowed)
			(footprints allowed)
		)
		(placement
			(enabled no)
			(sheetname "")
		)
		(fill yes
			(thermal_gap 0.5)
			(thermal_bridge_width 0.5)
			(island_removal_mode 0)
		)
		(polygon
			(pts
				(arc
					(start 192.338198 -200.071482)
					(mid 192.353077 -200.107403)
					(end 192.388998 -200.122282)
				)
				(arc
					(start 193.788538 -200.122282)
					(mid 193.824459 -200.107403)
					(end 193.839338 -200.071482)
				)
				(arc
					(start 193.839338 -199.662542)
					(mid 193.824459 -199.626621)
					(end 193.788538 -199.611742)
				)
				(arc
					(start 192.388998 -199.611742)
					(mid 192.353077 -199.626621)
					(end 192.338198 -199.662542)
				)
			)
		)
	)
	(zone
		(layers "In1.Cu" "In2.Cu")
		(hatch none 0.5)
		(connect_pads
			(clearance 0)
		)
		(min_thickness 0.25)
		(keepout
			(tracks not_allowed)
			(vias allowed)
			(pads allowed)
			(copperpour not_allowed)
			(footprints allowed)
		)
		(placement
			(enabled no)
			(sheetname "")
		)
		(fill yes
			(thermal_gap 0.5)
			(thermal_bridge_width 0.5)
			(island_removal_mode 0)
		)
		(polygon
			(pts
				(arc
					(start 49.209198 -237.471458)
					(mid 49.224077 -237.507379)
					(end 49.259998 -237.522258)
				)
				(arc
					(start 50.659538 -237.522258)
					(mid 50.695459 -237.507379)
					(end 50.710338 -237.471458)
				)
				(arc
					(start 50.710338 -237.062518)
					(mid 50.695459 -237.026597)
					(end 50.659538 -237.011718)
				)
				(arc
					(start 49.259998 -237.011718)
					(mid 49.224077 -237.026597)
					(end 49.209198 -237.062518)
				)
			)
		)
	)
	(zone
		(layers "In1.Cu" "In2.Cu")
		(hatch none 0.5)
		(connect_pads
			(clearance 0)
		)
		(min_thickness 0.25)
		(keepout
			(tracks not_allowed)
			(vias allowed)
			(pads allowed)
			(copperpour not_allowed)
			(footprints allowed)
		)
		(placement
			(enabled no)
			(sheetname "")
		)
		(fill yes
			(thermal_gap 0.5)
			(thermal_bridge_width 0.5)
			(island_removal_mode 0)
		)
		(polygon
			(pts
				(arc
					(start 455.365866 -214.521542)
					(mid 455.380745 -214.557463)
					(end 455.416666 -214.572342)
				)
				(arc
					(start 456.816206 -214.572342)
					(mid 456.852127 -214.557463)
					(end 456.867006 -214.521542)
				)
				(arc
					(start 456.867006 -214.112602)
					(mid 456.852127 -214.076681)
					(end 456.816206 -214.061802)
				)
				(arc
					(start 455.416666 -214.061802)
					(mid 455.380745 -214.076681)
					(end 455.365866 -214.112602)
				)
			)
		)
	)
	(zone
		(layers "In1.Cu" "In2.Cu")
		(hatch none 0.5)
		(connect_pads
			(clearance 0)
		)
		(min_thickness 0.25)
		(keepout
			(tracks not_allowed)
			(vias allowed)
			(pads allowed)
			(copperpour not_allowed)
			(footprints allowed)
		)
		(placement
			(enabled no)
			(sheetname "")
		)
		(fill yes
			(thermal_gap 0.5)
			(thermal_bridge_width 0.5)
			(island_removal_mode 0)
		)
		(polygon
			(pts
				(arc
					(start 184.794398 -246.821452)
					(mid 184.809277 -246.857373)
					(end 184.845198 -246.872252)
				)
				(arc
					(start 186.244738 -246.872252)
					(mid 186.280659 -246.857373)
					(end 186.295538 -246.821452)
				)
				(arc
					(start 186.295538 -246.412512)
					(mid 186.280659 -246.376591)
					(end 186.244738 -246.361712)
				)
				(arc
					(start 184.845198 -246.361712)
					(mid 184.809277 -246.376591)
					(end 184.794398 -246.412512)
				)
			)
		)
	)
	(zone
		(layers "In1.Cu" "In2.Cu")
		(hatch none 0.5)
		(connect_pads
			(clearance 0)
		)
		(min_thickness 0.25)
		(keepout
			(tracks not_allowed)
			(vias allowed)
			(pads allowed)
			(copperpour not_allowed)
			(footprints allowed)
		)
		(placement
			(enabled no)
			(sheetname "")
		)
		(fill yes
			(thermal_gap 0.5)
			(thermal_bridge_width 0.5)
			(island_removal_mode 0)
		)
		(polygon
			(pts
				(arc
					(start 203.32573 -310.571388)
					(mid 203.340609 -310.607309)
					(end 203.37653 -310.622188)
				)
				(arc
					(start 204.77607 -310.622188)
					(mid 204.811991 -310.607309)
					(end 204.82687 -310.571388)
				)
				(arc
					(start 204.82687 -310.162448)
					(mid 204.811991 -310.126527)
					(end 204.77607 -310.111648)
				)
				(arc
					(start 203.37653 -310.111648)
					(mid 203.340609 -310.126527)
					(end 203.32573 -310.162448)
				)
			)
		)
	)
	(zone
		(layers "In1.Cu" "In2.Cu")
		(hatch none 0.5)
		(connect_pads
			(clearance 0)
		)
		(min_thickness 0.25)
		(keepout
			(tracks not_allowed)
			(vias allowed)
			(pads allowed)
			(copperpour not_allowed)
			(footprints allowed)
		)
		(placement
			(enabled no)
			(sheetname "")
		)
		(fill yes
			(thermal_gap 0.5)
			(thermal_bridge_width 0.5)
			(island_removal_mode 0)
		)
		(polygon
			(pts
				(arc
					(start 184.794398 -308.021482)
					(mid 184.809277 -308.057403)
					(end 184.845198 -308.072282)
				)
				(arc
					(start 186.244738 -308.072282)
					(mid 186.280659 -308.057403)
					(end 186.295538 -308.021482)
				)
				(arc
					(start 186.295538 -307.612542)
					(mid 186.280659 -307.576621)
					(end 186.244738 -307.561742)
				)
				(arc
					(start 184.845198 -307.561742)
					(mid 184.809277 -307.576621)
					(end 184.794398 -307.612542)
				)
			)
		)
	)
	(zone
		(layers "In1.Cu" "In2.Cu")
		(hatch none 0.5)
		(connect_pads
			(clearance 0)
		)
		(min_thickness 0.25)
		(keepout
			(tracks not_allowed)
			(vias allowed)
			(pads allowed)
			(copperpour not_allowed)
			(footprints allowed)
		)
		(placement
			(enabled no)
			(sheetname "")
		)
		(fill yes
			(thermal_gap 0.5)
			(thermal_bridge_width 0.5)
			(island_removal_mode 0)
		)
		(polygon
			(pts
				(arc
					(start 173.15053 -271.47139)
					(mid 173.165409 -271.507311)
					(end 173.20133 -271.52219)
				)
				(arc
					(start 174.60087 -271.52219)
					(mid 174.636791 -271.507311)
					(end 174.65167 -271.47139)
				)
				(arc
					(start 174.65167 -271.06245)
					(mid 174.636791 -271.026529)
					(end 174.60087 -271.01165)
				)
				(arc
					(start 173.20133 -271.01165)
					(mid 173.165409 -271.026529)
					(end 173.15053 -271.06245)
				)
			)
		)
	)
	(zone
		(layers "In1.Cu" "In2.Cu")
		(hatch none 0.5)
		(connect_pads
			(clearance 0)
		)
		(min_thickness 0.25)
		(keepout
			(tracks not_allowed)
			(vias allowed)
			(pads allowed)
			(copperpour not_allowed)
			(footprints allowed)
		)
		(placement
			(enabled no)
			(sheetname "")
		)
		(fill yes
			(thermal_gap 0.5)
			(thermal_bridge_width 0.5)
			(island_removal_mode 0)
		)
		(polygon
			(pts
				(arc
					(start 462.909666 -270.621506)
					(mid 462.924545 -270.657427)
					(end 462.960466 -270.672306)
				)
				(arc
					(start 464.360006 -270.672306)
					(mid 464.395927 -270.657427)
					(end 464.410806 -270.621506)
				)
				(arc
					(start 464.410806 -270.212566)
					(mid 464.395927 -270.176645)
					(end 464.360006 -270.161766)
				)
				(arc
					(start 462.960466 -270.161766)
					(mid 462.924545 -270.176645)
					(end 462.909666 -270.212566)
				)
			)
		)
	)
	(zone
		(layers "In1.Cu" "In2.Cu")
		(hatch none 0.5)
		(connect_pads
			(clearance 0)
		)
		(min_thickness 0.25)
		(keepout
			(tracks not_allowed)
			(vias allowed)
			(pads allowed)
			(copperpour not_allowed)
			(footprints allowed)
		)
		(placement
			(enabled no)
			(sheetname "")
		)
		(fill yes
			(thermal_gap 0.5)
			(thermal_bridge_width 0.5)
			(island_removal_mode 0)
		)
		(polygon
			(pts
				(arc
					(start 37.56533 -301.221394)
					(mid 37.580209 -301.257315)
					(end 37.61613 -301.272194)
				)
				(arc
					(start 39.01567 -301.272194)
					(mid 39.051591 -301.257315)
					(end 39.06647 -301.221394)
				)
				(arc
					(start 39.06647 -300.812454)
					(mid 39.051591 -300.776533)
					(end 39.01567 -300.761654)
				)
				(arc
					(start 37.61613 -300.761654)
					(mid 37.580209 -300.776533)
					(end 37.56533 -300.812454)
				)
			)
		)
	)
	(zone
		(layers "In1.Cu" "In2.Cu")
		(hatch none 0.5)
		(connect_pads
			(clearance 0)
		)
		(min_thickness 0.25)
		(keepout
			(tracks not_allowed)
			(vias allowed)
			(pads allowed)
			(copperpour not_allowed)
			(footprints allowed)
		)
		(placement
			(enabled no)
			(sheetname "")
		)
		(fill yes
			(thermal_gap 0.5)
			(thermal_bridge_width 0.5)
			(island_removal_mode 0)
		)
		(polygon
			(pts
				(arc
					(start 45.10913 -226.421442)
					(mid 45.124009 -226.457363)
					(end 45.15993 -226.472242)
				)
				(arc
					(start 46.55947 -226.472242)
					(mid 46.595391 -226.457363)
					(end 46.61027 -226.421442)
				)
				(arc
					(start 46.61027 -226.012502)
					(mid 46.595391 -225.976581)
					(end 46.55947 -225.961702)
				)
				(arc
					(start 45.15993 -225.961702)
					(mid 45.124009 -225.976581)
					(end 45.10913 -226.012502)
				)
			)
		)
	)
	(zone
		(layers "In1.Cu" "In2.Cu")
		(hatch none 0.5)
		(connect_pads
			(clearance 0)
		)
		(min_thickness 0.25)
		(keepout
			(tracks not_allowed)
			(vias allowed)
			(pads allowed)
			(copperpour not_allowed)
			(footprints allowed)
		)
		(placement
			(enabled no)
			(sheetname "")
		)
		(fill yes
			(thermal_gap 0.5)
			(thermal_bridge_width 0.5)
			(island_removal_mode 0)
		)
		(polygon
			(pts
				(arc
					(start 410.103066 -298.671488)
					(mid 410.117945 -298.707409)
					(end 410.153866 -298.722288)
				)
				(arc
					(start 411.553406 -298.722288)
					(mid 411.589327 -298.707409)
					(end 411.604206 -298.671488)
				)
				(arc
					(start 411.604206 -298.262548)
					(mid 411.589327 -298.226627)
					(end 411.553406 -298.211748)
				)
				(arc
					(start 410.153866 -298.211748)
					(mid 410.117945 -298.226627)
					(end 410.103066 -298.262548)
				)
			)
		)
	)
	(zone
		(layers "In1.Cu" "In2.Cu")
		(hatch none 0.5)
		(connect_pads
			(clearance 0)
		)
		(min_thickness 0.25)
		(keepout
			(tracks not_allowed)
			(vias allowed)
			(pads allowed)
			(copperpour not_allowed)
			(footprints allowed)
		)
		(placement
			(enabled no)
			(sheetname "")
		)
		(fill yes
			(thermal_gap 0.5)
			(thermal_bridge_width 0.5)
			(island_removal_mode 0)
		)
		(polygon
			(pts
				(arc
					(start 64.296798 -267.221462)
					(mid 64.311677 -267.257383)
					(end 64.347598 -267.272262)
				)
				(arc
					(start 65.747138 -267.272262)
					(mid 65.783059 -267.257383)
					(end 65.797938 -267.221462)
				)
				(arc
					(start 65.797938 -266.812522)
					(mid 65.783059 -266.776601)
					(end 65.747138 -266.761722)
				)
				(arc
					(start 64.347598 -266.761722)
					(mid 64.311677 -266.776601)
					(end 64.296798 -266.812522)
				)
			)
		)
	)
	(zone
		(layers "In1.Cu" "In2.Cu")
		(hatch none 0.5)
		(connect_pads
			(clearance 0)
		)
		(min_thickness 0.25)
		(keepout
			(tracks not_allowed)
			(vias allowed)
			(pads allowed)
			(copperpour not_allowed)
			(footprints allowed)
		)
		(placement
			(enabled no)
			(sheetname "")
		)
		(fill yes
			(thermal_gap 0.5)
			(thermal_bridge_width 0.5)
			(island_removal_mode 0)
		)
		(polygon
			(pts
				(arc
					(start 428.634398 -291.8714)
					(mid 428.649277 -291.907321)
					(end 428.685198 -291.9222)
				)
				(arc
					(start 430.084738 -291.9222)
					(mid 430.120659 -291.907321)
					(end 430.135538 -291.8714)
				)
				(arc
					(start 430.135538 -291.46246)
					(mid 430.120659 -291.426539)
					(end 430.084738 -291.41166)
				)
				(arc
					(start 428.685198 -291.41166)
					(mid 428.649277 -291.426539)
					(end 428.634398 -291.46246)
				)
			)
		)
	)
	(zone
		(layers "In1.Cu" "In2.Cu")
		(hatch none 0.5)
		(connect_pads
			(clearance 0)
		)
		(min_thickness 0.25)
		(keepout
			(tracks not_allowed)
			(vias allowed)
			(pads allowed)
			(copperpour not_allowed)
			(footprints allowed)
		)
		(placement
			(enabled no)
			(sheetname "")
		)
		(fill yes
			(thermal_gap 0.5)
			(thermal_bridge_width 0.5)
			(island_removal_mode 0)
		)
		(polygon
			(pts
				(arc
					(start 184.794398 -267.221462)
					(mid 184.809277 -267.257383)
					(end 184.845198 -267.272262)
				)
				(arc
					(start 186.244738 -267.272262)
					(mid 186.280659 -267.257383)
					(end 186.295538 -267.221462)
				)
				(arc
					(start 186.295538 -266.812522)
					(mid 186.280659 -266.776601)
					(end 186.244738 -266.761722)
				)
				(arc
					(start 184.845198 -266.761722)
					(mid 184.809277 -266.776601)
					(end 184.794398 -266.812522)
				)
			)
		)
	)
	(zone
		(layers "In1.Cu" "In2.Cu")
		(hatch none 0.5)
		(connect_pads
			(clearance 0)
		)
		(min_thickness 0.25)
		(keepout
			(tracks not_allowed)
			(vias allowed)
			(pads allowed)
			(copperpour not_allowed)
			(footprints allowed)
		)
		(placement
			(enabled no)
			(sheetname "")
		)
		(fill yes
			(thermal_gap 0.5)
			(thermal_bridge_width 0.5)
			(island_removal_mode 0)
		)
		(polygon
			(pts
				(arc
					(start 14.93393 -277.42134)
					(mid 14.948809 -277.457261)
					(end 14.98473 -277.47214)
				)
				(arc
					(start 16.38427 -277.47214)
					(mid 16.420191 -277.457261)
					(end 16.43507 -277.42134)
				)
				(arc
					(start 16.43507 -277.0124)
					(mid 16.420191 -276.976479)
					(end 16.38427 -276.9616)
				)
				(arc
					(start 14.98473 -276.9616)
					(mid 14.948809 -276.976479)
					(end 14.93393 -277.0124)
				)
			)
		)
	)
	(zone
		(layers "In1.Cu" "In2.Cu")
		(hatch none 0.5)
		(connect_pads
			(clearance 0)
		)
		(min_thickness 0.25)
		(keepout
			(tracks not_allowed)
			(vias allowed)
			(pads allowed)
			(copperpour not_allowed)
			(footprints allowed)
		)
		(placement
			(enabled no)
			(sheetname "")
		)
		(fill yes
			(thermal_gap 0.5)
			(thermal_bridge_width 0.5)
			(island_removal_mode 0)
		)
		(polygon
			(pts
				(arc
					(start 45.10913 -221.321376)
					(mid 45.124009 -221.357297)
					(end 45.15993 -221.372176)
				)
				(arc
					(start 46.55947 -221.372176)
					(mid 46.595391 -221.357297)
					(end 46.61027 -221.321376)
				)
				(arc
					(start 46.61027 -220.912436)
					(mid 46.595391 -220.876515)
					(end 46.55947 -220.861636)
				)
				(arc
					(start 45.15993 -220.861636)
					(mid 45.124009 -220.876515)
					(end 45.10913 -220.912436)
				)
			)
		)
	)
	(zone
		(layers "In1.Cu" "In2.Cu")
		(hatch none 0.5)
		(connect_pads
			(clearance 0)
		)
		(min_thickness 0.25)
		(keepout
			(tracks not_allowed)
			(vias allowed)
			(pads allowed)
			(copperpour not_allowed)
			(footprints allowed)
		)
		(placement
			(enabled no)
			(sheetname "")
		)
		(fill yes
			(thermal_gap 0.5)
			(thermal_bridge_width 0.5)
			(island_removal_mode 0)
		)
		(polygon
			(pts
				(arc
					(start 406.002998 -209.421476)
					(mid 406.017877 -209.457397)
					(end 406.053798 -209.472276)
				)
				(arc
					(start 407.453338 -209.472276)
					(mid 407.489259 -209.457397)
					(end 407.504138 -209.421476)
				)
				(arc
					(start 407.504138 -209.012536)
					(mid 407.489259 -208.976615)
					(end 407.453338 -208.961736)
				)
				(arc
					(start 406.053798 -208.961736)
					(mid 406.017877 -208.976615)
					(end 406.002998 -209.012536)
				)
			)
		)
	)
	(zone
		(layers "In1.Cu" "In2.Cu")
		(hatch none 0.5)
		(connect_pads
			(clearance 0)
		)
		(min_thickness 0.25)
		(keepout
			(tracks not_allowed)
			(vias allowed)
			(pads allowed)
			(copperpour not_allowed)
			(footprints allowed)
		)
		(placement
			(enabled no)
			(sheetname "")
		)
		(fill yes
			(thermal_gap 0.5)
			(thermal_bridge_width 0.5)
			(island_removal_mode 0)
		)
		(polygon
			(pts
				(arc
					(start 462.909666 -227.271326)
					(mid 462.924545 -227.307247)
					(end 462.960466 -227.322126)
				)
				(arc
					(start 464.360006 -227.322126)
					(mid 464.395927 -227.307247)
					(end 464.410806 -227.271326)
				)
				(arc
					(start 464.410806 -226.862386)
					(mid 464.395927 -226.826465)
					(end 464.360006 -226.811586)
				)
				(arc
					(start 462.960466 -226.811586)
					(mid 462.924545 -226.826465)
					(end 462.909666 -226.862386)
				)
			)
		)
	)
	(zone
		(layers "In1.Cu" "In2.Cu")
		(hatch none 0.5)
		(connect_pads
			(clearance 0)
		)
		(min_thickness 0.25)
		(keepout
			(tracks not_allowed)
			(vias allowed)
			(pads allowed)
			(copperpour not_allowed)
			(footprints allowed)
		)
		(placement
			(enabled no)
			(sheetname "")
		)
		(fill yes
			(thermal_gap 0.5)
			(thermal_bridge_width 0.5)
			(island_removal_mode 0)
		)
		(polygon
			(pts
				(arc
					(start 308.136798 -198.37146)
					(mid 308.151677 -198.407381)
					(end 308.187598 -198.42226)
				)
				(arc
					(start 309.587138 -198.42226)
					(mid 309.623059 -198.407381)
					(end 309.637938 -198.37146)
				)
				(arc
					(start 309.637938 -197.96252)
					(mid 309.623059 -197.926599)
					(end 309.587138 -197.91172)
				)
				(arc
					(start 308.187598 -197.91172)
					(mid 308.151677 -197.926599)
					(end 308.136798 -197.96252)
				)
			)
		)
	)
	(zone
		(layers "In1.Cu" "In2.Cu")
		(hatch none 0.5)
		(connect_pads
			(clearance 0)
		)
		(min_thickness 0.25)
		(keepout
			(tracks not_allowed)
			(vias allowed)
			(pads allowed)
			(copperpour not_allowed)
			(footprints allowed)
		)
		(placement
			(enabled no)
			(sheetname "")
		)
		(fill yes
			(thermal_gap 0.5)
			(thermal_bridge_width 0.5)
			(island_removal_mode 0)
		)
		(polygon
			(pts
				(arc
					(start 289.605466 -272.321528)
					(mid 289.620345 -272.357449)
					(end 289.656266 -272.372328)
				)
				(arc
					(start 291.055806 -272.372328)
					(mid 291.091727 -272.357449)
					(end 291.106606 -272.321528)
				)
				(arc
					(start 291.106606 -271.912588)
					(mid 291.091727 -271.876667)
					(end 291.055806 -271.861788)
				)
				(arc
					(start 289.656266 -271.861788)
					(mid 289.620345 -271.876667)
					(end 289.605466 -271.912588)
				)
			)
		)
	)
	(zone
		(layers "In1.Cu" "In2.Cu")
		(hatch none 0.5)
		(connect_pads
			(clearance 0)
		)
		(min_thickness 0.25)
		(keepout
			(tracks not_allowed)
			(vias allowed)
			(pads allowed)
			(copperpour not_allowed)
			(footprints allowed)
		)
		(placement
			(enabled no)
			(sheetname "")
		)
		(fill yes
			(thermal_gap 0.5)
			(thermal_bridge_width 0.5)
			(island_removal_mode 0)
		)
		(polygon
			(pts
				(arc
					(start 266.974066 -197.521322)
					(mid 266.988945 -197.557243)
					(end 267.024866 -197.572122)
				)
				(arc
					(start 268.424406 -197.572122)
					(mid 268.460327 -197.557243)
					(end 268.475206 -197.521322)
				)
				(arc
					(start 268.475206 -197.112382)
					(mid 268.460327 -197.076461)
					(end 268.424406 -197.061582)
				)
				(arc
					(start 267.024866 -197.061582)
					(mid 266.988945 -197.076461)
					(end 266.974066 -197.112382)
				)
			)
		)
	)
	(zone
		(layers "In1.Cu" "In2.Cu")
		(hatch none 0.5)
		(connect_pads
			(clearance 0)
		)
		(min_thickness 0.25)
		(keepout
			(tracks not_allowed)
			(vias allowed)
			(pads allowed)
			(copperpour not_allowed)
			(footprints allowed)
		)
		(placement
			(enabled no)
			(sheetname "")
		)
		(fill yes
			(thermal_gap 0.5)
			(thermal_bridge_width 0.5)
			(island_removal_mode 0)
		)
		(polygon
			(pts
				(arc
					(start 184.794398 -248.521474)
					(mid 184.809277 -248.557395)
					(end 184.845198 -248.572274)
				)
				(arc
					(start 186.244738 -248.572274)
					(mid 186.280659 -248.557395)
					(end 186.295538 -248.521474)
				)
				(arc
					(start 186.295538 -248.112534)
					(mid 186.280659 -248.076613)
					(end 186.244738 -248.061734)
				)
				(arc
					(start 184.845198 -248.061734)
					(mid 184.809277 -248.076613)
					(end 184.794398 -248.112534)
				)
			)
		)
	)
	(zone
		(layers "In1.Cu" "In2.Cu")
		(hatch none 0.5)
		(connect_pads
			(clearance 0)
		)
		(min_thickness 0.25)
		(keepout
			(tracks not_allowed)
			(vias allowed)
			(pads allowed)
			(copperpour not_allowed)
			(footprints allowed)
		)
		(placement
			(enabled no)
			(sheetname "")
		)
		(fill yes
			(thermal_gap 0.5)
			(thermal_bridge_width 0.5)
			(island_removal_mode 0)
		)
		(polygon
			(pts
				(arc
					(start 14.93393 -302.921416)
					(mid 14.948809 -302.957337)
					(end 14.98473 -302.972216)
				)
				(arc
					(start 16.38427 -302.972216)
					(mid 16.420191 -302.957337)
					(end 16.43507 -302.921416)
				)
				(arc
					(start 16.43507 -302.512476)
					(mid 16.420191 -302.476555)
					(end 16.38427 -302.461676)
				)
				(arc
					(start 14.98473 -302.461676)
					(mid 14.948809 -302.476555)
					(end 14.93393 -302.512476)
				)
			)
		)
	)
	(zone
		(layers "In1.Cu" "In2.Cu")
		(hatch none 0.5)
		(connect_pads
			(clearance 0)
		)
		(min_thickness 0.25)
		(keepout
			(tracks not_allowed)
			(vias allowed)
			(pads allowed)
			(copperpour not_allowed)
			(footprints allowed)
		)
		(placement
			(enabled no)
			(sheetname "")
		)
		(fill yes
			(thermal_gap 0.5)
			(thermal_bridge_width 0.5)
			(island_removal_mode 0)
		)
		(polygon
			(pts
				(arc
					(start 270.417798 -221.321376)
					(mid 270.432677 -221.357297)
					(end 270.468598 -221.372176)
				)
				(arc
					(start 271.868138 -221.372176)
					(mid 271.904059 -221.357297)
					(end 271.918938 -221.321376)
				)
				(arc
					(start 271.918938 -220.912436)
					(mid 271.904059 -220.876515)
					(end 271.868138 -220.861636)
				)
				(arc
					(start 270.468598 -220.861636)
					(mid 270.432677 -220.876515)
					(end 270.417798 -220.912436)
				)
			)
		)
	)
	(zone
		(layers "In1.Cu" "In2.Cu")
		(hatch none 0.5)
		(connect_pads
			(clearance 0)
		)
		(min_thickness 0.25)
		(keepout
			(tracks not_allowed)
			(vias allowed)
			(pads allowed)
			(copperpour not_allowed)
			(footprints allowed)
		)
		(placement
			(enabled no)
			(sheetname "")
		)
		(fill yes
			(thermal_gap 0.5)
			(thermal_bridge_width 0.5)
			(island_removal_mode 0)
		)
		(polygon
			(pts
				(arc
					(start 282.061666 -199.221344)
					(mid 282.076545 -199.257265)
					(end 282.112466 -199.272144)
				)
				(arc
					(start 283.512006 -199.272144)
					(mid 283.547927 -199.257265)
					(end 283.562806 -199.221344)
				)
				(arc
					(start 283.562806 -198.812404)
					(mid 283.547927 -198.776483)
					(end 283.512006 -198.761604)
				)
				(arc
					(start 282.112466 -198.761604)
					(mid 282.076545 -198.776483)
					(end 282.061666 -198.812404)
				)
			)
		)
	)
	(zone
		(layers "In1.Cu" "In2.Cu")
		(hatch none 0.5)
		(connect_pads
			(clearance 0)
		)
		(min_thickness 0.25)
		(keepout
			(tracks not_allowed)
			(vias allowed)
			(pads allowed)
			(copperpour not_allowed)
			(footprints allowed)
		)
		(placement
			(enabled no)
			(sheetname "")
		)
		(fill yes
			(thermal_gap 0.5)
			(thermal_bridge_width 0.5)
			(island_removal_mode 0)
		)
		(polygon
			(pts
				(arc
					(start 173.15053 -316.521338)
					(mid 173.165409 -316.557259)
					(end 173.20133 -316.572138)
				)
				(arc
					(start 174.60087 -316.572138)
					(mid 174.636791 -316.557259)
					(end 174.65167 -316.521338)
				)
				(arc
					(start 174.65167 -316.112398)
					(mid 174.636791 -316.076477)
					(end 174.60087 -316.061598)
				)
				(arc
					(start 173.20133 -316.061598)
					(mid 173.165409 -316.076477)
					(end 173.15053 -316.112398)
				)
			)
		)
	)
	(zone
		(layers "In1.Cu" "In2.Cu")
		(hatch none 0.5)
		(connect_pads
			(clearance 0)
		)
		(min_thickness 0.25)
		(keepout
			(tracks not_allowed)
			(vias allowed)
			(pads allowed)
			(copperpour not_allowed)
			(footprints allowed)
		)
		(placement
			(enabled no)
			(sheetname "")
		)
		(fill yes
			(thermal_gap 0.5)
			(thermal_bridge_width 0.5)
			(island_removal_mode 0)
		)
		(polygon
			(pts
				(arc
					(start 462.909666 -220.471492)
					(mid 462.924545 -220.507413)
					(end 462.960466 -220.522292)
				)
				(arc
					(start 464.360006 -220.522292)
					(mid 464.395927 -220.507413)
					(end 464.410806 -220.471492)
				)
				(arc
					(start 464.410806 -220.062552)
					(mid 464.395927 -220.026631)
					(end 464.360006 -220.011752)
				)
				(arc
					(start 462.960466 -220.011752)
					(mid 462.924545 -220.026631)
					(end 462.909666 -220.062552)
				)
			)
		)
	)
	(zone
		(layers "In1.Cu" "In2.Cu")
		(hatch none 0.5)
		(connect_pads
			(clearance 0)
		)
		(min_thickness 0.25)
		(keepout
			(tracks not_allowed)
			(vias allowed)
			(pads allowed)
			(copperpour not_allowed)
			(footprints allowed)
		)
		(placement
			(enabled no)
			(sheetname "")
		)
		(fill yes
			(thermal_gap 0.5)
			(thermal_bridge_width 0.5)
			(island_removal_mode 0)
		)
		(polygon
			(pts
				(arc
					(start 37.56533 -228.121464)
					(mid 37.580209 -228.157385)
					(end 37.61613 -228.172264)
				)
				(arc
					(start 39.01567 -228.172264)
					(mid 39.051591 -228.157385)
					(end 39.06647 -228.121464)
				)
				(arc
					(start 39.06647 -227.712524)
					(mid 39.051591 -227.676603)
					(end 39.01567 -227.661724)
				)
				(arc
					(start 37.61613 -227.661724)
					(mid 37.580209 -227.676603)
					(end 37.56533 -227.712524)
				)
			)
		)
	)
	(zone
		(layers "In1.Cu" "In2.Cu")
		(hatch none 0.5)
		(connect_pads
			(clearance 0)
		)
		(min_thickness 0.25)
		(keepout
			(tracks not_allowed)
			(vias allowed)
			(pads allowed)
			(copperpour not_allowed)
			(footprints allowed)
		)
		(placement
			(enabled no)
			(sheetname "")
		)
		(fill yes
			(thermal_gap 0.5)
			(thermal_bridge_width 0.5)
			(island_removal_mode 0)
		)
		(polygon
			(pts
				(arc
					(start 289.605466 -292.721538)
					(mid 289.620345 -292.757459)
					(end 289.656266 -292.772338)
				)
				(arc
					(start 291.055806 -292.772338)
					(mid 291.091727 -292.757459)
					(end 291.106606 -292.721538)
				)
				(arc
					(start 291.106606 -292.312598)
					(mid 291.091727 -292.276677)
					(end 291.055806 -292.261798)
				)
				(arc
					(start 289.656266 -292.261798)
					(mid 289.620345 -292.276677)
					(end 289.605466 -292.312598)
				)
			)
		)
	)
	(zone
		(layers "In1.Cu" "In2.Cu")
		(hatch none 0.5)
		(connect_pads
			(clearance 0)
		)
		(min_thickness 0.25)
		(keepout
			(tracks not_allowed)
			(vias allowed)
			(pads allowed)
			(copperpour not_allowed)
			(footprints allowed)
		)
		(placement
			(enabled no)
			(sheetname "")
		)
		(fill yes
			(thermal_gap 0.5)
			(thermal_bridge_width 0.5)
			(island_removal_mode 0)
		)
		(polygon
			(pts
				(arc
					(start 19.033998 -222.171514)
					(mid 19.048877 -222.207435)
					(end 19.084798 -222.222314)
				)
				(arc
					(start 20.484338 -222.222314)
					(mid 20.520259 -222.207435)
					(end 20.535138 -222.171514)
				)
				(arc
					(start 20.535138 -221.762574)
					(mid 20.520259 -221.726653)
					(end 20.484338 -221.711774)
				)
				(arc
					(start 19.084798 -221.711774)
					(mid 19.048877 -221.726653)
					(end 19.033998 -221.762574)
				)
			)
		)
	)
	(zone
		(layers "In1.Cu" "In2.Cu")
		(hatch none 0.5)
		(connect_pads
			(clearance 0)
		)
		(min_thickness 0.25)
		(keepout
			(tracks not_allowed)
			(vias allowed)
			(pads allowed)
			(copperpour not_allowed)
			(footprints allowed)
		)
		(placement
			(enabled no)
			(sheetname "")
		)
		(fill yes
			(thermal_gap 0.5)
			(thermal_bridge_width 0.5)
			(island_removal_mode 0)
		)
		(polygon
			(pts
				(arc
					(start 162.162998 -229.821486)
					(mid 162.177877 -229.857407)
					(end 162.213798 -229.872286)
				)
				(arc
					(start 163.613338 -229.872286)
					(mid 163.649259 -229.857407)
					(end 163.664138 -229.821486)
				)
				(arc
					(start 163.664138 -229.412546)
					(mid 163.649259 -229.376625)
					(end 163.613338 -229.361746)
				)
				(arc
					(start 162.213798 -229.361746)
					(mid 162.177877 -229.376625)
					(end 162.162998 -229.412546)
				)
			)
		)
	)
	(zone
		(layers "In1.Cu" "In2.Cu")
		(hatch none 0.5)
		(connect_pads
			(clearance 0)
		)
		(min_thickness 0.25)
		(keepout
			(tracks not_allowed)
			(vias allowed)
			(pads allowed)
			(copperpour not_allowed)
			(footprints allowed)
		)
		(placement
			(enabled no)
			(sheetname "")
		)
		(fill yes
			(thermal_gap 0.5)
			(thermal_bridge_width 0.5)
			(island_removal_mode 0)
		)
		(polygon
			(pts
				(arc
					(start 195.78193 -228.971348)
					(mid 195.796809 -229.007269)
					(end 195.83273 -229.022148)
				)
				(arc
					(start 197.23227 -229.022148)
					(mid 197.268191 -229.007269)
					(end 197.28307 -228.971348)
				)
				(arc
					(start 197.28307 -228.562408)
					(mid 197.268191 -228.526487)
					(end 197.23227 -228.511608)
				)
				(arc
					(start 195.83273 -228.511608)
					(mid 195.796809 -228.526487)
					(end 195.78193 -228.562408)
				)
			)
		)
	)
	(zone
		(layers "In1.Cu" "In2.Cu")
		(hatch none 0.5)
		(connect_pads
			(clearance 0)
		)
		(min_thickness 0.25)
		(keepout
			(tracks not_allowed)
			(vias allowed)
			(pads allowed)
			(copperpour not_allowed)
			(footprints allowed)
		)
		(placement
			(enabled no)
			(sheetname "")
		)
		(fill yes
			(thermal_gap 0.5)
			(thermal_bridge_width 0.5)
			(island_removal_mode 0)
		)
		(polygon
			(pts
				(arc
					(start 451.265798 -259.57149)
					(mid 451.280677 -259.607411)
					(end 451.316598 -259.62229)
				)
				(arc
					(start 452.716138 -259.62229)
					(mid 452.752059 -259.607411)
					(end 452.766938 -259.57149)
				)
				(arc
					(start 452.766938 -259.16255)
					(mid 452.752059 -259.126629)
					(end 452.716138 -259.11175)
				)
				(arc
					(start 451.316598 -259.11175)
					(mid 451.280677 -259.126629)
					(end 451.265798 -259.16255)
				)
			)
		)
	)
	(zone
		(layers "In1.Cu" "In2.Cu")
		(hatch none 0.5)
		(connect_pads
			(clearance 0)
		)
		(min_thickness 0.25)
		(keepout
			(tracks not_allowed)
			(vias allowed)
			(pads allowed)
			(copperpour not_allowed)
			(footprints allowed)
		)
		(placement
			(enabled no)
			(sheetname "")
		)
		(fill yes
			(thermal_gap 0.5)
			(thermal_bridge_width 0.5)
			(island_removal_mode 0)
		)
		(polygon
			(pts
				(arc
					(start 266.974066 -278.271478)
					(mid 266.988945 -278.307399)
					(end 267.024866 -278.322278)
				)
				(arc
					(start 268.424406 -278.322278)
					(mid 268.460327 -278.307399)
					(end 268.475206 -278.271478)
				)
				(arc
					(start 268.475206 -277.862538)
					(mid 268.460327 -277.826617)
					(end 268.424406 -277.811738)
				)
				(arc
					(start 267.024866 -277.811738)
					(mid 266.988945 -277.826617)
					(end 266.974066 -277.862538)
				)
			)
		)
	)
	(zone
		(layers "In1.Cu" "In2.Cu")
		(hatch none 0.5)
		(connect_pads
			(clearance 0)
		)
		(min_thickness 0.25)
		(keepout
			(tracks not_allowed)
			(vias allowed)
			(pads allowed)
			(copperpour not_allowed)
			(footprints allowed)
		)
		(placement
			(enabled no)
			(sheetname "")
		)
		(fill yes
			(thermal_gap 0.5)
			(thermal_bridge_width 0.5)
			(island_removal_mode 0)
		)
		(polygon
			(pts
				(arc
					(start 410.103066 -234.921298)
					(mid 410.117945 -234.957219)
					(end 410.153866 -234.972098)
				)
				(arc
					(start 411.553406 -234.972098)
					(mid 411.589327 -234.957219)
					(end 411.604206 -234.921298)
				)
				(arc
					(start 411.604206 -234.512358)
					(mid 411.589327 -234.476437)
					(end 411.553406 -234.461558)
				)
				(arc
					(start 410.153866 -234.461558)
					(mid 410.117945 -234.476437)
					(end 410.103066 -234.512358)
				)
			)
		)
	)
	(zone
		(layers "In1.Cu" "In2.Cu")
		(hatch none 0.5)
		(connect_pads
			(clearance 0)
		)
		(min_thickness 0.25)
		(keepout
			(tracks not_allowed)
			(vias allowed)
			(pads allowed)
			(copperpour not_allowed)
			(footprints allowed)
		)
		(placement
			(enabled no)
			(sheetname "")
		)
		(fill yes
			(thermal_gap 0.5)
			(thermal_bridge_width 0.5)
			(island_removal_mode 0)
		)
		(polygon
			(pts
				(arc
					(start 64.296798 -223.871536)
					(mid 64.311677 -223.907457)
					(end 64.347598 -223.922336)
				)
				(arc
					(start 65.747138 -223.922336)
					(mid 65.783059 -223.907457)
					(end 65.797938 -223.871536)
				)
				(arc
					(start 65.797938 -223.462596)
					(mid 65.783059 -223.426675)
					(end 65.747138 -223.411796)
				)
				(arc
					(start 64.347598 -223.411796)
					(mid 64.311677 -223.426675)
					(end 64.296798 -223.462596)
				)
			)
		)
	)
	(zone
		(layers "In1.Cu" "In2.Cu")
		(hatch none 0.5)
		(connect_pads
			(clearance 0)
		)
		(min_thickness 0.25)
		(keepout
			(tracks not_allowed)
			(vias allowed)
			(pads allowed)
			(copperpour not_allowed)
			(footprints allowed)
		)
		(placement
			(enabled no)
			(sheetname "")
		)
		(fill yes
			(thermal_gap 0.5)
			(thermal_bridge_width 0.5)
			(island_removal_mode 0)
		)
		(polygon
			(pts
				(arc
					(start 169.706798 -274.871434)
					(mid 169.721677 -274.907355)
					(end 169.757598 -274.922234)
				)
				(arc
					(start 171.157138 -274.922234)
					(mid 171.193059 -274.907355)
					(end 171.207938 -274.871434)
				)
				(arc
					(start 171.207938 -274.462494)
					(mid 171.193059 -274.426573)
					(end 171.157138 -274.411694)
				)
				(arc
					(start 169.757598 -274.411694)
					(mid 169.721677 -274.426573)
					(end 169.706798 -274.462494)
				)
			)
		)
	)
	(zone
		(layers "In1.Cu" "In2.Cu")
		(hatch none 0.5)
		(connect_pads
			(clearance 0)
		)
		(min_thickness 0.25)
		(keepout
			(tracks not_allowed)
			(vias allowed)
			(pads allowed)
			(copperpour not_allowed)
			(footprints allowed)
		)
		(placement
			(enabled no)
			(sheetname "")
		)
		(fill yes
			(thermal_gap 0.5)
			(thermal_bridge_width 0.5)
			(island_removal_mode 0)
		)
		(polygon
			(pts
				(arc
					(start 440.278266 -195.821554)
					(mid 440.293145 -195.857475)
					(end 440.329066 -195.872354)
				)
				(arc
					(start 441.728606 -195.872354)
					(mid 441.764527 -195.857475)
					(end 441.779406 -195.821554)
				)
				(arc
					(start 441.779406 -195.412614)
					(mid 441.764527 -195.376693)
					(end 441.728606 -195.361814)
				)
				(arc
					(start 440.329066 -195.361814)
					(mid 440.293145 -195.376693)
					(end 440.278266 -195.412614)
				)
			)
		)
	)
	(zone
		(layers "In1.Cu" "In2.Cu")
		(hatch none 0.5)
		(connect_pads
			(clearance 0)
		)
		(min_thickness 0.25)
		(keepout
			(tracks not_allowed)
			(vias allowed)
			(pads allowed)
			(copperpour not_allowed)
			(footprints allowed)
		)
		(placement
			(enabled no)
			(sheetname "")
		)
		(fill yes
			(thermal_gap 0.5)
			(thermal_bridge_width 0.5)
			(island_removal_mode 0)
		)
		(polygon
			(pts
				(arc
					(start 203.32573 -264.671302)
					(mid 203.340609 -264.707223)
					(end 203.37653 -264.722102)
				)
				(arc
					(start 204.77607 -264.722102)
					(mid 204.811991 -264.707223)
					(end 204.82687 -264.671302)
				)
				(arc
					(start 204.82687 -264.262362)
					(mid 204.811991 -264.226441)
					(end 204.77607 -264.211562)
				)
				(arc
					(start 203.37653 -264.211562)
					(mid 203.340609 -264.226441)
					(end 203.32573 -264.262362)
				)
			)
		)
	)
	(zone
		(layers "In1.Cu" "In2.Cu")
		(hatch none 0.5)
		(connect_pads
			(clearance 0)
		)
		(min_thickness 0.25)
		(keepout
			(tracks not_allowed)
			(vias allowed)
			(pads allowed)
			(copperpour not_allowed)
			(footprints allowed)
		)
		(placement
			(enabled no)
			(sheetname "")
		)
		(fill yes
			(thermal_gap 0.5)
			(thermal_bridge_width 0.5)
			(island_removal_mode 0)
		)
		(polygon
			(pts
				(arc
					(start 30.02153 -237.471458)
					(mid 30.036409 -237.507379)
					(end 30.07233 -237.522258)
				)
				(arc
					(start 31.47187 -237.522258)
					(mid 31.507791 -237.507379)
					(end 31.52267 -237.471458)
				)
				(arc
					(start 31.52267 -237.062518)
					(mid 31.507791 -237.026597)
					(end 31.47187 -237.011718)
				)
				(arc
					(start 30.07233 -237.011718)
					(mid 30.036409 -237.026597)
					(end 30.02153 -237.062518)
				)
			)
		)
	)
	(zone
		(layers "In1.Cu" "In2.Cu")
		(hatch none 0.5)
		(connect_pads
			(clearance 0)
		)
		(min_thickness 0.25)
		(keepout
			(tracks not_allowed)
			(vias allowed)
			(pads allowed)
			(copperpour not_allowed)
			(footprints allowed)
		)
		(placement
			(enabled no)
			(sheetname "")
		)
		(fill yes
			(thermal_gap 0.5)
			(thermal_bridge_width 0.5)
			(island_removal_mode 0)
		)
		(polygon
			(pts
				(arc
					(start 192.338198 -195.821554)
					(mid 192.353077 -195.857475)
					(end 192.388998 -195.872354)
				)
				(arc
					(start 193.788538 -195.872354)
					(mid 193.824459 -195.857475)
					(end 193.839338 -195.821554)
				)
				(arc
					(start 193.839338 -195.412614)
					(mid 193.824459 -195.376693)
					(end 193.788538 -195.361814)
				)
				(arc
					(start 192.388998 -195.361814)
					(mid 192.353077 -195.376693)
					(end 192.338198 -195.412614)
				)
			)
		)
	)
	(zone
		(layers "In1.Cu" "In2.Cu")
		(hatch none 0.5)
		(connect_pads
			(clearance 0)
		)
		(min_thickness 0.25)
		(keepout
			(tracks not_allowed)
			(vias allowed)
			(pads allowed)
			(copperpour not_allowed)
			(footprints allowed)
		)
		(placement
			(enabled no)
			(sheetname "")
		)
		(fill yes
			(thermal_gap 0.5)
			(thermal_bridge_width 0.5)
			(island_removal_mode 0)
		)
		(polygon
			(pts
				(arc
					(start 158.06293 -252.771402)
					(mid 158.077809 -252.807323)
					(end 158.11373 -252.822202)
				)
				(arc
					(start 159.51327 -252.822202)
					(mid 159.549191 -252.807323)
					(end 159.56407 -252.771402)
				)
				(arc
					(start 159.56407 -252.362462)
					(mid 159.549191 -252.326541)
					(end 159.51327 -252.311662)
				)
				(arc
					(start 158.11373 -252.311662)
					(mid 158.077809 -252.326541)
					(end 158.06293 -252.362462)
				)
			)
		)
	)
	(zone
		(layers "In1.Cu" "In2.Cu")
		(hatch none 0.5)
		(connect_pads
			(clearance 0)
		)
		(min_thickness 0.25)
		(keepout
			(tracks not_allowed)
			(vias allowed)
			(pads allowed)
			(copperpour not_allowed)
			(footprints allowed)
		)
		(placement
			(enabled no)
			(sheetname "")
		)
		(fill yes
			(thermal_gap 0.5)
			(thermal_bridge_width 0.5)
			(island_removal_mode 0)
		)
		(polygon
			(pts
				(arc
					(start 19.033998 -239.17148)
					(mid 19.048877 -239.207401)
					(end 19.084798 -239.22228)
				)
				(arc
					(start 20.484338 -239.22228)
					(mid 20.520259 -239.207401)
					(end 20.535138 -239.17148)
				)
				(arc
					(start 20.535138 -238.76254)
					(mid 20.520259 -238.726619)
					(end 20.484338 -238.71174)
				)
				(arc
					(start 19.084798 -238.71174)
					(mid 19.048877 -238.726619)
					(end 19.033998 -238.76254)
				)
			)
		)
	)
	(zone
		(layers "In1.Cu" "In2.Cu")
		(hatch none 0.5)
		(connect_pads
			(clearance 0)
		)
		(min_thickness 0.25)
		(keepout
			(tracks not_allowed)
			(vias allowed)
			(pads allowed)
			(copperpour not_allowed)
			(footprints allowed)
		)
		(placement
			(enabled no)
			(sheetname "")
		)
		(fill yes
			(thermal_gap 0.5)
			(thermal_bridge_width 0.5)
			(island_removal_mode 0)
		)
		(polygon
			(pts
				(arc
					(start 285.505398 -316.521338)
					(mid 285.520277 -316.557259)
					(end 285.556198 -316.572138)
				)
				(arc
					(start 286.955738 -316.572138)
					(mid 286.991659 -316.557259)
					(end 287.006538 -316.521338)
				)
				(arc
					(start 287.006538 -316.112398)
					(mid 286.991659 -316.076477)
					(end 286.955738 -316.061598)
				)
				(arc
					(start 285.556198 -316.061598)
					(mid 285.520277 -316.076477)
					(end 285.505398 -316.112398)
				)
			)
		)
	)
	(zone
		(layers "In1.Cu" "In2.Cu")
		(hatch none 0.5)
		(connect_pads
			(clearance 0)
		)
		(min_thickness 0.25)
		(keepout
			(tracks not_allowed)
			(vias allowed)
			(pads allowed)
			(copperpour not_allowed)
			(footprints allowed)
		)
		(placement
			(enabled no)
			(sheetname "")
		)
		(fill yes
			(thermal_gap 0.5)
			(thermal_bridge_width 0.5)
			(island_removal_mode 0)
		)
		(polygon
			(pts
				(arc
					(start 22.47773 -312.27141)
					(mid 22.492609 -312.307331)
					(end 22.52853 -312.32221)
				)
				(arc
					(start 23.92807 -312.32221)
					(mid 23.963991 -312.307331)
					(end 23.97887 -312.27141)
				)
				(arc
					(start 23.97887 -311.86247)
					(mid 23.963991 -311.826549)
					(end 23.92807 -311.81167)
				)
				(arc
					(start 22.52853 -311.81167)
					(mid 22.492609 -311.826549)
					(end 22.47773 -311.86247)
				)
			)
		)
	)
	(zone
		(layers "In1.Cu" "In2.Cu")
		(hatch none 0.5)
		(connect_pads
			(clearance 0)
		)
		(min_thickness 0.25)
		(keepout
			(tracks not_allowed)
			(vias allowed)
			(pads allowed)
			(copperpour not_allowed)
			(footprints allowed)
		)
		(placement
			(enabled no)
			(sheetname "")
		)
		(fill yes
			(thermal_gap 0.5)
			(thermal_bridge_width 0.5)
			(island_removal_mode 0)
		)
		(polygon
			(pts
				(arc
					(start 270.417798 -274.871434)
					(mid 270.432677 -274.907355)
					(end 270.468598 -274.922234)
				)
				(arc
					(start 271.868138 -274.922234)
					(mid 271.904059 -274.907355)
					(end 271.918938 -274.871434)
				)
				(arc
					(start 271.918938 -274.462494)
					(mid 271.904059 -274.426573)
					(end 271.868138 -274.411694)
				)
				(arc
					(start 270.468598 -274.411694)
					(mid 270.432677 -274.426573)
					(end 270.417798 -274.462494)
				)
			)
		)
	)
	(zone
		(layers "In1.Cu" "In2.Cu")
		(hatch none 0.5)
		(connect_pads
			(clearance 0)
		)
		(min_thickness 0.25)
		(keepout
			(tracks not_allowed)
			(vias allowed)
			(pads allowed)
			(copperpour not_allowed)
			(footprints allowed)
		)
		(placement
			(enabled no)
			(sheetname "")
		)
		(fill yes
			(thermal_gap 0.5)
			(thermal_bridge_width 0.5)
			(island_removal_mode 0)
		)
		(polygon
			(pts
				(arc
					(start 41.665398 -272.321528)
					(mid 41.680277 -272.357449)
					(end 41.716198 -272.372328)
				)
				(arc
					(start 43.115738 -272.372328)
					(mid 43.151659 -272.357449)
					(end 43.166538 -272.321528)
				)
				(arc
					(start 43.166538 -271.912588)
					(mid 43.151659 -271.876667)
					(end 43.115738 -271.861788)
				)
				(arc
					(start 41.716198 -271.861788)
					(mid 41.680277 -271.876667)
					(end 41.665398 -271.912588)
				)
			)
		)
	)
	(zone
		(layers "In1.Cu" "In2.Cu")
		(hatch none 0.5)
		(connect_pads
			(clearance 0)
		)
		(min_thickness 0.25)
		(keepout
			(tracks not_allowed)
			(vias allowed)
			(pads allowed)
			(copperpour not_allowed)
			(footprints allowed)
		)
		(placement
			(enabled no)
			(sheetname "")
		)
		(fill yes
			(thermal_gap 0.5)
			(thermal_bridge_width 0.5)
			(island_removal_mode 0)
		)
		(polygon
			(pts
				(arc
					(start 210.86953 -305.471322)
					(mid 210.884409 -305.507243)
					(end 210.92033 -305.522122)
				)
				(arc
					(start 212.31987 -305.522122)
					(mid 212.355791 -305.507243)
					(end 212.37067 -305.471322)
				)
				(arc
					(start 212.37067 -305.062382)
					(mid 212.355791 -305.026461)
					(end 212.31987 -305.011582)
				)
				(arc
					(start 210.92033 -305.011582)
					(mid 210.884409 -305.026461)
					(end 210.86953 -305.062382)
				)
			)
		)
	)
	(zone
		(layers "In1.Cu" "In2.Cu")
		(hatch none 0.5)
		(connect_pads
			(clearance 0)
		)
		(min_thickness 0.25)
		(keepout
			(tracks not_allowed)
			(vias allowed)
			(pads allowed)
			(copperpour not_allowed)
			(footprints allowed)
		)
		(placement
			(enabled no)
			(sheetname "")
		)
		(fill yes
			(thermal_gap 0.5)
			(thermal_bridge_width 0.5)
			(island_removal_mode 0)
		)
		(polygon
			(pts
				(arc
					(start 410.103066 -206.871316)
					(mid 410.117945 -206.907237)
					(end 410.153866 -206.922116)
				)
				(arc
					(start 411.553406 -206.922116)
					(mid 411.589327 -206.907237)
					(end 411.604206 -206.871316)
				)
				(arc
					(start 411.604206 -206.462376)
					(mid 411.589327 -206.426455)
					(end 411.553406 -206.411576)
				)
				(arc
					(start 410.153866 -206.411576)
					(mid 410.117945 -206.426455)
					(end 410.103066 -206.462376)
				)
			)
		)
	)
	(zone
		(layers "In1.Cu" "In2.Cu")
		(hatch none 0.5)
		(connect_pads
			(clearance 0)
		)
		(min_thickness 0.25)
		(keepout
			(tracks not_allowed)
			(vias allowed)
			(pads allowed)
			(copperpour not_allowed)
			(footprints allowed)
		)
		(placement
			(enabled no)
			(sheetname "")
		)
		(fill yes
			(thermal_gap 0.5)
			(thermal_bridge_width 0.5)
			(island_removal_mode 0)
		)
		(polygon
			(pts
				(arc
					(start 19.033998 -260.421374)
					(mid 19.048877 -260.457295)
					(end 19.084798 -260.472174)
				)
				(arc
					(start 20.484338 -260.472174)
					(mid 20.520259 -260.457295)
					(end 20.535138 -260.421374)
				)
				(arc
					(start 20.535138 -260.012434)
					(mid 20.520259 -259.976513)
					(end 20.484338 -259.961634)
				)
				(arc
					(start 19.084798 -259.961634)
					(mid 19.048877 -259.976513)
					(end 19.033998 -260.012434)
				)
			)
		)
	)
	(zone
		(layers "In1.Cu" "In2.Cu")
		(hatch none 0.5)
		(connect_pads
			(clearance 0)
		)
		(min_thickness 0.25)
		(keepout
			(tracks not_allowed)
			(vias allowed)
			(pads allowed)
			(copperpour not_allowed)
			(footprints allowed)
		)
		(placement
			(enabled no)
			(sheetname "")
		)
		(fill yes
			(thermal_gap 0.5)
			(thermal_bridge_width 0.5)
			(island_removal_mode 0)
		)
		(polygon
			(pts
				(arc
					(start 410.103066 -227.271326)
					(mid 410.117945 -227.307247)
					(end 410.153866 -227.322126)
				)
				(arc
					(start 411.553406 -227.322126)
					(mid 411.589327 -227.307247)
					(end 411.604206 -227.271326)
				)
				(arc
					(start 411.604206 -226.862386)
					(mid 411.589327 -226.826465)
					(end 411.553406 -226.811586)
				)
				(arc
					(start 410.153866 -226.811586)
					(mid 410.117945 -226.826465)
					(end 410.103066 -226.862386)
				)
			)
		)
	)
	(zone
		(layers "In1.Cu" "In2.Cu")
		(hatch none 0.5)
		(connect_pads
			(clearance 0)
		)
		(min_thickness 0.25)
		(keepout
			(tracks not_allowed)
			(vias allowed)
			(pads allowed)
			(copperpour not_allowed)
			(footprints allowed)
		)
		(placement
			(enabled no)
			(sheetname "")
		)
		(fill yes
			(thermal_gap 0.5)
			(thermal_bridge_width 0.5)
			(island_removal_mode 0)
		)
		(polygon
			(pts
				(arc
					(start 41.665398 -278.271478)
					(mid 41.680277 -278.307399)
					(end 41.716198 -278.322278)
				)
				(arc
					(start 43.115738 -278.322278)
					(mid 43.151659 -278.307399)
					(end 43.166538 -278.271478)
				)
				(arc
					(start 43.166538 -277.862538)
					(mid 43.151659 -277.826617)
					(end 43.115738 -277.811738)
				)
				(arc
					(start 41.716198 -277.811738)
					(mid 41.680277 -277.826617)
					(end 41.665398 -277.862538)
				)
			)
		)
	)
	(zone
		(layers "In1.Cu" "In2.Cu")
		(hatch none 0.5)
		(connect_pads
			(clearance 0)
		)
		(min_thickness 0.25)
		(keepout
			(tracks not_allowed)
			(vias allowed)
			(pads allowed)
			(copperpour not_allowed)
			(footprints allowed)
		)
		(placement
			(enabled no)
			(sheetname "")
		)
		(fill yes
			(thermal_gap 0.5)
			(thermal_bridge_width 0.5)
			(island_removal_mode 0)
		)
		(polygon
			(pts
				(arc
					(start 308.136798 -249.371358)
					(mid 308.151677 -249.407279)
					(end 308.187598 -249.422158)
				)
				(arc
					(start 309.587138 -249.422158)
					(mid 309.623059 -249.407279)
					(end 309.637938 -249.371358)
				)
				(arc
					(start 309.637938 -248.962418)
					(mid 309.623059 -248.926497)
					(end 309.587138 -248.911618)
				)
				(arc
					(start 308.187598 -248.911618)
					(mid 308.151677 -248.926497)
					(end 308.136798 -248.962418)
				)
			)
		)
	)
	(zone
		(layers "In1.Cu" "In2.Cu")
		(hatch none 0.5)
		(connect_pads
			(clearance 0)
		)
		(min_thickness 0.25)
		(keepout
			(tracks not_allowed)
			(vias allowed)
			(pads allowed)
			(copperpour not_allowed)
			(footprints allowed)
		)
		(placement
			(enabled no)
			(sheetname "")
		)
		(fill yes
			(thermal_gap 0.5)
			(thermal_bridge_width 0.5)
			(island_removal_mode 0)
		)
		(polygon
			(pts
				(arc
					(start 270.417798 -273.171412)
					(mid 270.432677 -273.207333)
					(end 270.468598 -273.222212)
				)
				(arc
					(start 271.868138 -273.222212)
					(mid 271.904059 -273.207333)
					(end 271.918938 -273.171412)
				)
				(arc
					(start 271.918938 -272.762472)
					(mid 271.904059 -272.726551)
					(end 271.868138 -272.711672)
				)
				(arc
					(start 270.468598 -272.711672)
					(mid 270.432677 -272.726551)
					(end 270.417798 -272.762472)
				)
			)
		)
	)
	(zone
		(layers "In1.Cu" "In2.Cu")
		(hatch none 0.5)
		(connect_pads
			(clearance 0)
		)
		(min_thickness 0.25)
		(keepout
			(tracks not_allowed)
			(vias allowed)
			(pads allowed)
			(copperpour not_allowed)
			(footprints allowed)
		)
		(placement
			(enabled no)
			(sheetname "")
		)
		(fill yes
			(thermal_gap 0.5)
			(thermal_bridge_width 0.5)
			(island_removal_mode 0)
		)
		(polygon
			(pts
				(arc
					(start 188.23813 -215.371426)
					(mid 188.253009 -215.407347)
					(end 188.28893 -215.422226)
				)
				(arc
					(start 189.68847 -215.422226)
					(mid 189.724391 -215.407347)
					(end 189.73927 -215.371426)
				)
				(arc
					(start 189.73927 -214.962486)
					(mid 189.724391 -214.926565)
					(end 189.68847 -214.911686)
				)
				(arc
					(start 188.28893 -214.911686)
					(mid 188.253009 -214.926565)
					(end 188.23813 -214.962486)
				)
			)
		)
	)
	(zone
		(layers "In1.Cu" "In2.Cu")
		(hatch none 0.5)
		(connect_pads
			(clearance 0)
		)
		(min_thickness 0.25)
		(keepout
			(tracks not_allowed)
			(vias allowed)
			(pads allowed)
			(copperpour not_allowed)
			(footprints allowed)
		)
		(placement
			(enabled no)
			(sheetname "")
		)
		(fill yes
			(thermal_gap 0.5)
			(thermal_bridge_width 0.5)
			(island_removal_mode 0)
		)
		(polygon
			(pts
				(arc
					(start 22.47773 -221.321376)
					(mid 22.492609 -221.357297)
					(end 22.52853 -221.372176)
				)
				(arc
					(start 23.92807 -221.372176)
					(mid 23.963991 -221.357297)
					(end 23.97887 -221.321376)
				)
				(arc
					(start 23.97887 -220.912436)
					(mid 23.963991 -220.876515)
					(end 23.92807 -220.861636)
				)
				(arc
					(start 22.52853 -220.861636)
					(mid 22.492609 -220.876515)
					(end 22.47773 -220.912436)
				)
			)
		)
	)
	(zone
		(layers "In1.Cu" "In2.Cu")
		(hatch none 0.5)
		(connect_pads
			(clearance 0)
		)
		(min_thickness 0.25)
		(keepout
			(tracks not_allowed)
			(vias allowed)
			(pads allowed)
			(copperpour not_allowed)
			(footprints allowed)
		)
		(placement
			(enabled no)
			(sheetname "")
		)
		(fill yes
			(thermal_gap 0.5)
			(thermal_bridge_width 0.5)
			(island_removal_mode 0)
		)
		(polygon
			(pts
				(arc
					(start 214.969598 -212.82152)
					(mid 214.984477 -212.857441)
					(end 215.020398 -212.87232)
				)
				(arc
					(start 216.419938 -212.87232)
					(mid 216.455859 -212.857441)
					(end 216.470738 -212.82152)
				)
				(arc
					(start 216.470738 -212.41258)
					(mid 216.455859 -212.376659)
					(end 216.419938 -212.36178)
				)
				(arc
					(start 215.020398 -212.36178)
					(mid 214.984477 -212.376659)
					(end 214.969598 -212.41258)
				)
			)
		)
	)
	(zone
		(layers "In1.Cu" "In2.Cu")
		(hatch none 0.5)
		(connect_pads
			(clearance 0)
		)
		(min_thickness 0.25)
		(keepout
			(tracks not_allowed)
			(vias allowed)
			(pads allowed)
			(copperpour not_allowed)
			(footprints allowed)
		)
		(placement
			(enabled no)
			(sheetname "")
		)
		(fill yes
			(thermal_gap 0.5)
			(thermal_bridge_width 0.5)
			(island_removal_mode 0)
		)
		(polygon
			(pts
				(arc
					(start 308.136798 -279.121362)
					(mid 308.151677 -279.157283)
					(end 308.187598 -279.172162)
				)
				(arc
					(start 309.587138 -279.172162)
					(mid 309.623059 -279.157283)
					(end 309.637938 -279.121362)
				)
				(arc
					(start 309.637938 -278.712422)
					(mid 309.623059 -278.676501)
					(end 309.587138 -278.661622)
				)
				(arc
					(start 308.187598 -278.661622)
					(mid 308.151677 -278.676501)
					(end 308.136798 -278.712422)
				)
			)
		)
	)
	(zone
		(layers "In1.Cu" "In2.Cu")
		(hatch none 0.5)
		(connect_pads
			(clearance 0)
		)
		(min_thickness 0.25)
		(keepout
			(tracks not_allowed)
			(vias allowed)
			(pads allowed)
			(copperpour not_allowed)
			(footprints allowed)
		)
		(placement
			(enabled no)
			(sheetname "")
		)
		(fill yes
			(thermal_gap 0.5)
			(thermal_bridge_width 0.5)
			(island_removal_mode 0)
		)
		(polygon
			(pts
				(arc
					(start 169.706798 -292.721538)
					(mid 169.721677 -292.757459)
					(end 169.757598 -292.772338)
				)
				(arc
					(start 171.157138 -292.772338)
					(mid 171.193059 -292.757459)
					(end 171.207938 -292.721538)
				)
				(arc
					(start 171.207938 -292.312598)
					(mid 171.193059 -292.276677)
					(end 171.157138 -292.261798)
				)
				(arc
					(start 169.757598 -292.261798)
					(mid 169.721677 -292.276677)
					(end 169.706798 -292.312598)
				)
			)
		)
	)
	(zone
		(layers "In1.Cu" "In2.Cu")
		(hatch none 0.5)
		(connect_pads
			(clearance 0)
		)
		(min_thickness 0.25)
		(keepout
			(tracks not_allowed)
			(vias allowed)
			(pads allowed)
			(copperpour not_allowed)
			(footprints allowed)
		)
		(placement
			(enabled no)
			(sheetname "")
		)
		(fill yes
			(thermal_gap 0.5)
			(thermal_bridge_width 0.5)
			(island_removal_mode 0)
		)
		(polygon
			(pts
				(arc
					(start 451.265798 -271.47139)
					(mid 451.280677 -271.507311)
					(end 451.316598 -271.52219)
				)
				(arc
					(start 452.716138 -271.52219)
					(mid 452.752059 -271.507311)
					(end 452.766938 -271.47139)
				)
				(arc
					(start 452.766938 -271.06245)
					(mid 452.752059 -271.026529)
					(end 452.716138 -271.01165)
				)
				(arc
					(start 451.316598 -271.01165)
					(mid 451.280677 -271.026529)
					(end 451.265798 -271.06245)
				)
			)
		)
	)
	(zone
		(layers "In1.Cu" "In2.Cu")
		(hatch none 0.5)
		(connect_pads
			(clearance 0)
		)
		(min_thickness 0.25)
		(keepout
			(tracks not_allowed)
			(vias allowed)
			(pads allowed)
			(copperpour not_allowed)
			(footprints allowed)
		)
		(placement
			(enabled no)
			(sheetname "")
		)
		(fill yes
			(thermal_gap 0.5)
			(thermal_bridge_width 0.5)
			(island_removal_mode 0)
		)
		(polygon
			(pts
				(arc
					(start 443.721998 -273.171412)
					(mid 443.736877 -273.207333)
					(end 443.772798 -273.222212)
				)
				(arc
					(start 445.172338 -273.222212)
					(mid 445.208259 -273.207333)
					(end 445.223138 -273.171412)
				)
				(arc
					(start 445.223138 -272.762472)
					(mid 445.208259 -272.726551)
					(end 445.172338 -272.711672)
				)
				(arc
					(start 443.772798 -272.711672)
					(mid 443.736877 -272.726551)
					(end 443.721998 -272.762472)
				)
			)
		)
	)
	(zone
		(layers "In1.Cu" "In2.Cu")
		(hatch none 0.5)
		(connect_pads
			(clearance 0)
		)
		(min_thickness 0.25)
		(keepout
			(tracks not_allowed)
			(vias allowed)
			(pads allowed)
			(copperpour not_allowed)
			(footprints allowed)
		)
		(placement
			(enabled no)
			(sheetname "")
		)
		(fill yes
			(thermal_gap 0.5)
			(thermal_bridge_width 0.5)
			(island_removal_mode 0)
		)
		(polygon
			(pts
				(arc
					(start 7.39013 -297.82135)
					(mid 7.405009 -297.857271)
					(end 7.44093 -297.87215)
				)
				(arc
					(start 8.84047 -297.87215)
					(mid 8.876391 -297.857271)
					(end 8.89127 -297.82135)
				)
				(arc
					(start 8.89127 -297.41241)
					(mid 8.876391 -297.376489)
					(end 8.84047 -297.36161)
				)
				(arc
					(start 7.44093 -297.36161)
					(mid 7.405009 -297.376489)
					(end 7.39013 -297.41241)
				)
			)
		)
	)
	(zone
		(layers "In1.Cu" "In2.Cu")
		(hatch none 0.5)
		(connect_pads
			(clearance 0)
		)
		(min_thickness 0.25)
		(keepout
			(tracks not_allowed)
			(vias allowed)
			(pads allowed)
			(copperpour not_allowed)
			(footprints allowed)
		)
		(placement
			(enabled no)
			(sheetname "")
		)
		(fill yes
			(thermal_gap 0.5)
			(thermal_bridge_width 0.5)
			(island_removal_mode 0)
		)
		(polygon
			(pts
				(arc
					(start 11.490198 -304.621438)
					(mid 11.505077 -304.657359)
					(end 11.540998 -304.672238)
				)
				(arc
					(start 12.940538 -304.672238)
					(mid 12.976459 -304.657359)
					(end 12.991338 -304.621438)
				)
				(arc
					(start 12.991338 -304.212498)
					(mid 12.976459 -304.176577)
					(end 12.940538 -304.161698)
				)
				(arc
					(start 11.540998 -304.161698)
					(mid 11.505077 -304.176577)
					(end 11.490198 -304.212498)
				)
			)
		)
	)
	(zone
		(layers "In1.Cu" "In2.Cu")
		(hatch none 0.5)
		(connect_pads
			(clearance 0)
		)
		(min_thickness 0.25)
		(keepout
			(tracks not_allowed)
			(vias allowed)
			(pads allowed)
			(copperpour not_allowed)
			(footprints allowed)
		)
		(placement
			(enabled no)
			(sheetname "")
		)
		(fill yes
			(thermal_gap 0.5)
			(thermal_bridge_width 0.5)
			(island_removal_mode 0)
		)
		(polygon
			(pts
				(arc
					(start 413.546798 -291.8714)
					(mid 413.561677 -291.907321)
					(end 413.597598 -291.9222)
				)
				(arc
					(start 414.997138 -291.9222)
					(mid 415.033059 -291.907321)
					(end 415.047938 -291.8714)
				)
				(arc
					(start 415.047938 -291.46246)
					(mid 415.033059 -291.426539)
					(end 414.997138 -291.41166)
				)
				(arc
					(start 413.597598 -291.41166)
					(mid 413.561677 -291.426539)
					(end 413.546798 -291.46246)
				)
			)
		)
	)
	(zone
		(layers "In1.Cu" "In2.Cu")
		(hatch none 0.5)
		(connect_pads
			(clearance 0)
		)
		(min_thickness 0.25)
		(keepout
			(tracks not_allowed)
			(vias allowed)
			(pads allowed)
			(copperpour not_allowed)
			(footprints allowed)
		)
		(placement
			(enabled no)
			(sheetname "")
		)
		(fill yes
			(thermal_gap 0.5)
			(thermal_bridge_width 0.5)
			(island_removal_mode 0)
		)
		(polygon
			(pts
				(arc
					(start 304.693066 -287.621472)
					(mid 304.707945 -287.657393)
					(end 304.743866 -287.672272)
				)
				(arc
					(start 306.143406 -287.672272)
					(mid 306.179327 -287.657393)
					(end 306.194206 -287.621472)
				)
				(arc
					(start 306.194206 -287.212532)
					(mid 306.179327 -287.176611)
					(end 306.143406 -287.161732)
				)
				(arc
					(start 304.743866 -287.161732)
					(mid 304.707945 -287.176611)
					(end 304.693066 -287.212532)
				)
			)
		)
	)
	(zone
		(layers "In1.Cu" "In2.Cu")
		(hatch none 0.5)
		(connect_pads
			(clearance 0)
		)
		(min_thickness 0.25)
		(keepout
			(tracks not_allowed)
			(vias allowed)
			(pads allowed)
			(copperpour not_allowed)
			(footprints allowed)
		)
		(placement
			(enabled no)
			(sheetname "")
		)
		(fill yes
			(thermal_gap 0.5)
			(thermal_bridge_width 0.5)
			(island_removal_mode 0)
		)
		(polygon
			(pts
				(arc
					(start 462.909666 -283.371544)
					(mid 462.924545 -283.407465)
					(end 462.960466 -283.422344)
				)
				(arc
					(start 464.360006 -283.422344)
					(mid 464.395927 -283.407465)
					(end 464.410806 -283.371544)
				)
				(arc
					(start 464.410806 -282.962604)
					(mid 464.395927 -282.926683)
					(end 464.360006 -282.911804)
				)
				(arc
					(start 462.960466 -282.911804)
					(mid 462.924545 -282.926683)
					(end 462.909666 -282.962604)
				)
			)
		)
	)
	(zone
		(layers "In1.Cu" "In2.Cu")
		(hatch none 0.5)
		(connect_pads
			(clearance 0)
		)
		(min_thickness 0.25)
		(keepout
			(tracks not_allowed)
			(vias allowed)
			(pads allowed)
			(copperpour not_allowed)
			(footprints allowed)
		)
		(placement
			(enabled no)
			(sheetname "")
		)
		(fill yes
			(thermal_gap 0.5)
			(thermal_bridge_width 0.5)
			(island_removal_mode 0)
		)
		(polygon
			(pts
				(arc
					(start 41.665398 -211.121498)
					(mid 41.680277 -211.157419)
					(end 41.716198 -211.172298)
				)
				(arc
					(start 43.115738 -211.172298)
					(mid 43.151659 -211.157419)
					(end 43.166538 -211.121498)
				)
				(arc
					(start 43.166538 -210.712558)
					(mid 43.151659 -210.676637)
					(end 43.115738 -210.661758)
				)
				(arc
					(start 41.716198 -210.661758)
					(mid 41.680277 -210.676637)
					(end 41.665398 -210.712558)
				)
			)
		)
	)
	(zone
		(layers "In1.Cu" "In2.Cu")
		(hatch none 0.5)
		(connect_pads
			(clearance 0)
		)
		(min_thickness 0.25)
		(keepout
			(tracks not_allowed)
			(vias allowed)
			(pads allowed)
			(copperpour not_allowed)
			(footprints allowed)
		)
		(placement
			(enabled no)
			(sheetname "")
		)
		(fill yes
			(thermal_gap 0.5)
			(thermal_bridge_width 0.5)
			(island_removal_mode 0)
		)
		(polygon
			(pts
				(arc
					(start 22.47773 -264.671302)
					(mid 22.492609 -264.707223)
					(end 22.52853 -264.722102)
				)
				(arc
					(start 23.92807 -264.722102)
					(mid 23.963991 -264.707223)
					(end 23.97887 -264.671302)
				)
				(arc
					(start 23.97887 -264.262362)
					(mid 23.963991 -264.226441)
					(end 23.92807 -264.211562)
				)
				(arc
					(start 22.52853 -264.211562)
					(mid 22.492609 -264.226441)
					(end 22.47773 -264.262362)
				)
			)
		)
	)
	(zone
		(layers "In1.Cu" "In2.Cu")
		(hatch none 0.5)
		(connect_pads
			(clearance 0)
		)
		(min_thickness 0.25)
		(keepout
			(tracks not_allowed)
			(vias allowed)
			(pads allowed)
			(copperpour not_allowed)
			(footprints allowed)
		)
		(placement
			(enabled no)
			(sheetname "")
		)
		(fill yes
			(thermal_gap 0.5)
			(thermal_bridge_width 0.5)
			(island_removal_mode 0)
		)
		(polygon
			(pts
				(arc
					(start 255.330198 -240.021364)
					(mid 255.345077 -240.057285)
					(end 255.380998 -240.072164)
				)
				(arc
					(start 256.780538 -240.072164)
					(mid 256.816459 -240.057285)
					(end 256.831338 -240.021364)
				)
				(arc
					(start 256.831338 -239.612424)
					(mid 256.816459 -239.576503)
					(end 256.780538 -239.561624)
				)
				(arc
					(start 255.380998 -239.561624)
					(mid 255.345077 -239.576503)
					(end 255.330198 -239.612424)
				)
			)
		)
	)
	(zone
		(layers "In1.Cu" "In2.Cu")
		(hatch none 0.5)
		(connect_pads
			(clearance 0)
		)
		(min_thickness 0.25)
		(keepout
			(tracks not_allowed)
			(vias allowed)
			(pads allowed)
			(copperpour not_allowed)
			(footprints allowed)
		)
		(placement
			(enabled no)
			(sheetname "")
		)
		(fill yes
			(thermal_gap 0.5)
			(thermal_bridge_width 0.5)
			(island_removal_mode 0)
		)
		(polygon
			(pts
				(arc
					(start 304.693066 -283.371544)
					(mid 304.707945 -283.407465)
					(end 304.743866 -283.422344)
				)
				(arc
					(start 306.143406 -283.422344)
					(mid 306.179327 -283.407465)
					(end 306.194206 -283.371544)
				)
				(arc
					(start 306.194206 -282.962604)
					(mid 306.179327 -282.926683)
					(end 306.143406 -282.911804)
				)
				(arc
					(start 304.743866 -282.911804)
					(mid 304.707945 -282.926683)
					(end 304.693066 -282.962604)
				)
			)
		)
	)
	(zone
		(layers "In1.Cu" "In2.Cu")
		(hatch none 0.5)
		(connect_pads
			(clearance 0)
		)
		(min_thickness 0.25)
		(keepout
			(tracks not_allowed)
			(vias allowed)
			(pads allowed)
			(copperpour not_allowed)
			(footprints allowed)
		)
		(placement
			(enabled no)
			(sheetname "")
		)
		(fill yes
			(thermal_gap 0.5)
			(thermal_bridge_width 0.5)
			(island_removal_mode 0)
		)
		(polygon
			(pts
				(arc
					(start 410.103066 -291.021516)
					(mid 410.117945 -291.057437)
					(end 410.153866 -291.072316)
				)
				(arc
					(start 411.553406 -291.072316)
					(mid 411.589327 -291.057437)
					(end 411.604206 -291.021516)
				)
				(arc
					(start 411.604206 -290.612576)
					(mid 411.589327 -290.576655)
					(end 411.553406 -290.561776)
				)
				(arc
					(start 410.153866 -290.561776)
					(mid 410.117945 -290.576655)
					(end 410.103066 -290.612576)
				)
			)
		)
	)
	(zone
		(layers "In1.Cu" "In2.Cu")
		(hatch none 0.5)
		(connect_pads
			(clearance 0)
		)
		(min_thickness 0.25)
		(keepout
			(tracks not_allowed)
			(vias allowed)
			(pads allowed)
			(copperpour not_allowed)
			(footprints allowed)
		)
		(placement
			(enabled no)
			(sheetname "")
		)
		(fill yes
			(thermal_gap 0.5)
			(thermal_bridge_width 0.5)
			(island_removal_mode 0)
		)
		(polygon
			(pts
				(arc
					(start 289.605466 -217.921332)
					(mid 289.620345 -217.957253)
					(end 289.656266 -217.972132)
				)
				(arc
					(start 291.055806 -217.972132)
					(mid 291.091727 -217.957253)
					(end 291.106606 -217.921332)
				)
				(arc
					(start 291.106606 -217.512392)
					(mid 291.091727 -217.476471)
					(end 291.055806 -217.461592)
				)
				(arc
					(start 289.656266 -217.461592)
					(mid 289.620345 -217.476471)
					(end 289.605466 -217.512392)
				)
			)
		)
	)
	(zone
		(layers "In1.Cu" "In2.Cu")
		(hatch none 0.5)
		(connect_pads
			(clearance 0)
		)
		(min_thickness 0.25)
		(keepout
			(tracks not_allowed)
			(vias allowed)
			(pads allowed)
			(copperpour not_allowed)
			(footprints allowed)
		)
		(placement
			(enabled no)
			(sheetname "")
		)
		(fill yes
			(thermal_gap 0.5)
			(thermal_bridge_width 0.5)
			(island_removal_mode 0)
		)
		(polygon
			(pts
				(arc
					(start 214.969598 -309.721504)
					(mid 214.984477 -309.757425)
					(end 215.020398 -309.772304)
				)
				(arc
					(start 216.419938 -309.772304)
					(mid 216.455859 -309.757425)
					(end 216.470738 -309.721504)
				)
				(arc
					(start 216.470738 -309.312564)
					(mid 216.455859 -309.276643)
					(end 216.419938 -309.261764)
				)
				(arc
					(start 215.020398 -309.261764)
					(mid 214.984477 -309.276643)
					(end 214.969598 -309.312564)
				)
			)
		)
	)
	(zone
		(layers "In1.Cu" "In2.Cu")
		(hatch none 0.5)
		(connect_pads
			(clearance 0)
		)
		(min_thickness 0.25)
		(keepout
			(tracks not_allowed)
			(vias allowed)
			(pads allowed)
			(copperpour not_allowed)
			(footprints allowed)
		)
		(placement
			(enabled no)
			(sheetname "")
		)
		(fill yes
			(thermal_gap 0.5)
			(thermal_bridge_width 0.5)
			(island_removal_mode 0)
		)
		(polygon
			(pts
				(arc
					(start 406.002998 -196.671438)
					(mid 406.017877 -196.707359)
					(end 406.053798 -196.722238)
				)
				(arc
					(start 407.453338 -196.722238)
					(mid 407.489259 -196.707359)
					(end 407.504138 -196.671438)
				)
				(arc
					(start 407.504138 -196.262498)
					(mid 407.489259 -196.226577)
					(end 407.453338 -196.211698)
				)
				(arc
					(start 406.053798 -196.211698)
					(mid 406.017877 -196.226577)
					(end 406.002998 -196.262498)
				)
			)
		)
	)
	(zone
		(layers "In1.Cu" "In2.Cu")
		(hatch none 0.5)
		(connect_pads
			(clearance 0)
		)
		(min_thickness 0.25)
		(keepout
			(tracks not_allowed)
			(vias allowed)
			(pads allowed)
			(copperpour not_allowed)
			(footprints allowed)
		)
		(placement
			(enabled no)
			(sheetname "")
		)
		(fill yes
			(thermal_gap 0.5)
			(thermal_bridge_width 0.5)
			(island_removal_mode 0)
		)
		(polygon
			(pts
				(arc
					(start 19.033998 -272.321528)
					(mid 19.048877 -272.357449)
					(end 19.084798 -272.372328)
				)
				(arc
					(start 20.484338 -272.372328)
					(mid 20.520259 -272.357449)
					(end 20.535138 -272.321528)
				)
				(arc
					(start 20.535138 -271.912588)
					(mid 20.520259 -271.876667)
					(end 20.484338 -271.861788)
				)
				(arc
					(start 19.084798 -271.861788)
					(mid 19.048877 -271.876667)
					(end 19.033998 -271.912588)
				)
			)
		)
	)
	(zone
		(layers "In1.Cu" "In2.Cu")
		(hatch none 0.5)
		(connect_pads
			(clearance 0)
		)
		(min_thickness 0.25)
		(keepout
			(tracks not_allowed)
			(vias allowed)
			(pads allowed)
			(copperpour not_allowed)
			(footprints allowed)
		)
		(placement
			(enabled no)
			(sheetname "")
		)
		(fill yes
			(thermal_gap 0.5)
			(thermal_bridge_width 0.5)
			(island_removal_mode 0)
		)
		(polygon
			(pts
				(arc
					(start 312.236866 -295.271444)
					(mid 312.251745 -295.307365)
					(end 312.287666 -295.322244)
				)
				(arc
					(start 313.687206 -295.322244)
					(mid 313.723127 -295.307365)
					(end 313.738006 -295.271444)
				)
				(arc
					(start 313.738006 -294.862504)
					(mid 313.723127 -294.826583)
					(end 313.687206 -294.811704)
				)
				(arc
					(start 312.287666 -294.811704)
					(mid 312.251745 -294.826583)
					(end 312.236866 -294.862504)
				)
			)
		)
	)
	(zone
		(layers "In1.Cu" "In2.Cu")
		(hatch none 0.5)
		(connect_pads
			(clearance 0)
		)
		(min_thickness 0.25)
		(keepout
			(tracks not_allowed)
			(vias allowed)
			(pads allowed)
			(copperpour not_allowed)
			(footprints allowed)
		)
		(placement
			(enabled no)
			(sheetname "")
		)
		(fill yes
			(thermal_gap 0.5)
			(thermal_bridge_width 0.5)
			(island_removal_mode 0)
		)
		(polygon
			(pts
				(arc
					(start 214.969598 -267.221462)
					(mid 214.984477 -267.257383)
					(end 215.020398 -267.272262)
				)
				(arc
					(start 216.419938 -267.272262)
					(mid 216.455859 -267.257383)
					(end 216.470738 -267.221462)
				)
				(arc
					(start 216.470738 -266.812522)
					(mid 216.455859 -266.776601)
					(end 216.419938 -266.761722)
				)
				(arc
					(start 215.020398 -266.761722)
					(mid 214.984477 -266.776601)
					(end 214.969598 -266.812522)
				)
			)
		)
	)
	(zone
		(layers "In1.Cu" "In2.Cu")
		(hatch none 0.5)
		(connect_pads
			(clearance 0)
		)
		(min_thickness 0.25)
		(keepout
			(tracks not_allowed)
			(vias allowed)
			(pads allowed)
			(copperpour not_allowed)
			(footprints allowed)
		)
		(placement
			(enabled no)
			(sheetname "")
		)
		(fill yes
			(thermal_gap 0.5)
			(thermal_bridge_width 0.5)
			(island_removal_mode 0)
		)
		(polygon
			(pts
				(arc
					(start 428.634398 -285.071312)
					(mid 428.649277 -285.107233)
					(end 428.685198 -285.122112)
				)
				(arc
					(start 430.084738 -285.122112)
					(mid 430.120659 -285.107233)
					(end 430.135538 -285.071312)
				)
				(arc
					(start 430.135538 -284.662372)
					(mid 430.120659 -284.626451)
					(end 430.084738 -284.611572)
				)
				(arc
					(start 428.685198 -284.611572)
					(mid 428.649277 -284.626451)
					(end 428.634398 -284.662372)
				)
			)
		)
	)
	(zone
		(layers "In1.Cu" "In2.Cu")
		(hatch none 0.5)
		(connect_pads
			(clearance 0)
		)
		(min_thickness 0.25)
		(keepout
			(tracks not_allowed)
			(vias allowed)
			(pads allowed)
			(copperpour not_allowed)
			(footprints allowed)
		)
		(placement
			(enabled no)
			(sheetname "")
		)
		(fill yes
			(thermal_gap 0.5)
			(thermal_bridge_width 0.5)
			(island_removal_mode 0)
		)
		(polygon
			(pts
				(arc
					(start 177.250598 -292.721538)
					(mid 177.265477 -292.757459)
					(end 177.301398 -292.772338)
				)
				(arc
					(start 178.700938 -292.772338)
					(mid 178.736859 -292.757459)
					(end 178.751738 -292.721538)
				)
				(arc
					(start 178.751738 -292.312598)
					(mid 178.736859 -292.276677)
					(end 178.700938 -292.261798)
				)
				(arc
					(start 177.301398 -292.261798)
					(mid 177.265477 -292.276677)
					(end 177.250598 -292.312598)
				)
			)
		)
	)
	(zone
		(layers "In1.Cu" "In2.Cu")
		(hatch none 0.5)
		(connect_pads
			(clearance 0)
		)
		(min_thickness 0.25)
		(keepout
			(tracks not_allowed)
			(vias allowed)
			(pads allowed)
			(copperpour not_allowed)
			(footprints allowed)
		)
		(placement
			(enabled no)
			(sheetname "")
		)
		(fill yes
			(thermal_gap 0.5)
			(thermal_bridge_width 0.5)
			(island_removal_mode 0)
		)
		(polygon
			(pts
				(arc
					(start 255.330198 -286.771334)
					(mid 255.345077 -286.807255)
					(end 255.380998 -286.822134)
				)
				(arc
					(start 256.780538 -286.822134)
					(mid 256.816459 -286.807255)
					(end 256.831338 -286.771334)
				)
				(arc
					(start 256.831338 -286.362394)
					(mid 256.816459 -286.326473)
					(end 256.780538 -286.311594)
				)
				(arc
					(start 255.380998 -286.311594)
					(mid 255.345077 -286.326473)
					(end 255.330198 -286.362394)
				)
			)
		)
	)
	(zone
		(layers "In1.Cu" "In2.Cu")
		(hatch none 0.5)
		(connect_pads
			(clearance 0)
		)
		(min_thickness 0.25)
		(keepout
			(tracks not_allowed)
			(vias allowed)
			(pads allowed)
			(copperpour not_allowed)
			(footprints allowed)
		)
		(placement
			(enabled no)
			(sheetname "")
		)
		(fill yes
			(thermal_gap 0.5)
			(thermal_bridge_width 0.5)
			(island_removal_mode 0)
		)
		(polygon
			(pts
				(arc
					(start 203.32573 -280.821384)
					(mid 203.340609 -280.857305)
					(end 203.37653 -280.872184)
				)
				(arc
					(start 204.77607 -280.872184)
					(mid 204.811991 -280.857305)
					(end 204.82687 -280.821384)
				)
				(arc
					(start 204.82687 -280.412444)
					(mid 204.811991 -280.376523)
					(end 204.77607 -280.361644)
				)
				(arc
					(start 203.37653 -280.361644)
					(mid 203.340609 -280.376523)
					(end 203.32573 -280.412444)
				)
			)
		)
	)
	(zone
		(layers "In1.Cu" "In2.Cu")
		(hatch none 0.5)
		(connect_pads
			(clearance 0)
		)
		(min_thickness 0.25)
		(keepout
			(tracks not_allowed)
			(vias allowed)
			(pads allowed)
			(copperpour not_allowed)
			(footprints allowed)
		)
		(placement
			(enabled no)
			(sheetname "")
		)
		(fill yes
			(thermal_gap 0.5)
			(thermal_bridge_width 0.5)
			(island_removal_mode 0)
		)
		(polygon
			(pts
				(arc
					(start 19.033998 -291.021516)
					(mid 19.048877 -291.057437)
					(end 19.084798 -291.072316)
				)
				(arc
					(start 20.484338 -291.072316)
					(mid 20.520259 -291.057437)
					(end 20.535138 -291.021516)
				)
				(arc
					(start 20.535138 -290.612576)
					(mid 20.520259 -290.576655)
					(end 20.484338 -290.561776)
				)
				(arc
					(start 19.084798 -290.561776)
					(mid 19.048877 -290.576655)
					(end 19.033998 -290.612576)
				)
			)
		)
	)
	(zone
		(layers "In1.Cu" "In2.Cu")
		(hatch none 0.5)
		(connect_pads
			(clearance 0)
		)
		(min_thickness 0.25)
		(keepout
			(tracks not_allowed)
			(vias allowed)
			(pads allowed)
			(copperpour not_allowed)
			(footprints allowed)
		)
		(placement
			(enabled no)
			(sheetname "")
		)
		(fill yes
			(thermal_gap 0.5)
			(thermal_bridge_width 0.5)
			(island_removal_mode 0)
		)
		(polygon
			(pts
				(arc
					(start 173.15053 -312.27141)
					(mid 173.165409 -312.307331)
					(end 173.20133 -312.32221)
				)
				(arc
					(start 174.60087 -312.32221)
					(mid 174.636791 -312.307331)
					(end 174.65167 -312.27141)
				)
				(arc
					(start 174.65167 -311.86247)
					(mid 174.636791 -311.826549)
					(end 174.60087 -311.81167)
				)
				(arc
					(start 173.20133 -311.81167)
					(mid 173.165409 -311.826549)
					(end 173.15053 -311.86247)
				)
			)
		)
	)
	(zone
		(layers "In1.Cu" "In2.Cu")
		(hatch none 0.5)
		(connect_pads
			(clearance 0)
		)
		(min_thickness 0.25)
		(keepout
			(tracks not_allowed)
			(vias allowed)
			(pads allowed)
			(copperpour not_allowed)
			(footprints allowed)
		)
		(placement
			(enabled no)
			(sheetname "")
		)
		(fill yes
			(thermal_gap 0.5)
			(thermal_bridge_width 0.5)
			(island_removal_mode 0)
		)
		(polygon
			(pts
				(arc
					(start 451.265798 -305.471322)
					(mid 451.280677 -305.507243)
					(end 451.316598 -305.522122)
				)
				(arc
					(start 452.716138 -305.522122)
					(mid 452.752059 -305.507243)
					(end 452.766938 -305.471322)
				)
				(arc
					(start 452.766938 -305.062382)
					(mid 452.752059 -305.026461)
					(end 452.716138 -305.011582)
				)
				(arc
					(start 451.316598 -305.011582)
					(mid 451.280677 -305.026461)
					(end 451.265798 -305.062382)
				)
			)
		)
	)
	(zone
		(layers "In1.Cu" "In2.Cu")
		(hatch none 0.5)
		(connect_pads
			(clearance 0)
		)
		(min_thickness 0.25)
		(keepout
			(tracks not_allowed)
			(vias allowed)
			(pads allowed)
			(copperpour not_allowed)
			(footprints allowed)
		)
		(placement
			(enabled no)
			(sheetname "")
		)
		(fill yes
			(thermal_gap 0.5)
			(thermal_bridge_width 0.5)
			(island_removal_mode 0)
		)
		(polygon
			(pts
				(arc
					(start 455.365866 -205.171548)
					(mid 455.380745 -205.207469)
					(end 455.416666 -205.222348)
				)
				(arc
					(start 456.816206 -205.222348)
					(mid 456.852127 -205.207469)
					(end 456.867006 -205.171548)
				)
				(arc
					(start 456.867006 -204.762608)
					(mid 456.852127 -204.726687)
					(end 456.816206 -204.711808)
				)
				(arc
					(start 455.416666 -204.711808)
					(mid 455.380745 -204.726687)
					(end 455.365866 -204.762608)
				)
			)
		)
	)
	(zone
		(layers "In1.Cu" "In2.Cu")
		(hatch none 0.5)
		(connect_pads
			(clearance 0)
		)
		(min_thickness 0.25)
		(keepout
			(tracks not_allowed)
			(vias allowed)
			(pads allowed)
			(copperpour not_allowed)
			(footprints allowed)
		)
		(placement
			(enabled no)
			(sheetname "")
		)
		(fill yes
			(thermal_gap 0.5)
			(thermal_bridge_width 0.5)
			(island_removal_mode 0)
		)
		(polygon
			(pts
				(arc
					(start 177.250598 -274.02155)
					(mid 177.265477 -274.057471)
					(end 177.301398 -274.07235)
				)
				(arc
					(start 178.700938 -274.07235)
					(mid 178.736859 -274.057471)
					(end 178.751738 -274.02155)
				)
				(arc
					(start 178.751738 -273.61261)
					(mid 178.736859 -273.576689)
					(end 178.700938 -273.56181)
				)
				(arc
					(start 177.301398 -273.56181)
					(mid 177.265477 -273.576689)
					(end 177.250598 -273.61261)
				)
			)
		)
	)
	(zone
		(layers "In1.Cu" "In2.Cu")
		(hatch none 0.5)
		(connect_pads
			(clearance 0)
		)
		(min_thickness 0.25)
		(keepout
			(tracks not_allowed)
			(vias allowed)
			(pads allowed)
			(copperpour not_allowed)
			(footprints allowed)
		)
		(placement
			(enabled no)
			(sheetname "")
		)
		(fill yes
			(thermal_gap 0.5)
			(thermal_bridge_width 0.5)
			(island_removal_mode 0)
		)
		(polygon
			(pts
				(arc
					(start 266.974066 -287.621472)
					(mid 266.988945 -287.657393)
					(end 267.024866 -287.672272)
				)
				(arc
					(start 268.424406 -287.672272)
					(mid 268.460327 -287.657393)
					(end 268.475206 -287.621472)
				)
				(arc
					(start 268.475206 -287.212532)
					(mid 268.460327 -287.176611)
					(end 268.424406 -287.161732)
				)
				(arc
					(start 267.024866 -287.161732)
					(mid 266.988945 -287.176611)
					(end 266.974066 -287.212532)
				)
			)
		)
	)
	(zone
		(layers "In1.Cu" "In2.Cu")
		(hatch none 0.5)
		(connect_pads
			(clearance 0)
		)
		(min_thickness 0.25)
		(keepout
			(tracks not_allowed)
			(vias allowed)
			(pads allowed)
			(copperpour not_allowed)
			(footprints allowed)
		)
		(placement
			(enabled no)
			(sheetname "")
		)
		(fill yes
			(thermal_gap 0.5)
			(thermal_bridge_width 0.5)
			(island_removal_mode 0)
		)
		(polygon
			(pts
				(arc
					(start 300.592998 -219.621354)
					(mid 300.607877 -219.657275)
					(end 300.643798 -219.672154)
				)
				(arc
					(start 302.043338 -219.672154)
					(mid 302.079259 -219.657275)
					(end 302.094138 -219.621354)
				)
				(arc
					(start 302.094138 -219.212414)
					(mid 302.079259 -219.176493)
					(end 302.043338 -219.161614)
				)
				(arc
					(start 300.643798 -219.161614)
					(mid 300.607877 -219.176493)
					(end 300.592998 -219.212414)
				)
			)
		)
	)
	(zone
		(layers "In1.Cu" "In2.Cu")
		(hatch none 0.5)
		(connect_pads
			(clearance 0)
		)
		(min_thickness 0.25)
		(keepout
			(tracks not_allowed)
			(vias allowed)
			(pads allowed)
			(copperpour not_allowed)
			(footprints allowed)
		)
		(placement
			(enabled no)
			(sheetname "")
		)
		(fill yes
			(thermal_gap 0.5)
			(thermal_bridge_width 0.5)
			(island_removal_mode 0)
		)
		(polygon
			(pts
				(arc
					(start 177.250598 -315.671454)
					(mid 177.265477 -315.707375)
					(end 177.301398 -315.722254)
				)
				(arc
					(start 178.700938 -315.722254)
					(mid 178.736859 -315.707375)
					(end 178.751738 -315.671454)
				)
				(arc
					(start 178.751738 -315.262514)
					(mid 178.736859 -315.226593)
					(end 178.700938 -315.211714)
				)
				(arc
					(start 177.301398 -315.211714)
					(mid 177.265477 -315.226593)
					(end 177.250598 -315.262514)
				)
			)
		)
	)
	(zone
		(layers "In1.Cu" "In2.Cu")
		(hatch none 0.5)
		(connect_pads
			(clearance 0)
		)
		(min_thickness 0.25)
		(keepout
			(tracks not_allowed)
			(vias allowed)
			(pads allowed)
			(copperpour not_allowed)
			(footprints allowed)
		)
		(placement
			(enabled no)
			(sheetname "")
		)
		(fill yes
			(thermal_gap 0.5)
			(thermal_bridge_width 0.5)
			(island_removal_mode 0)
		)
		(polygon
			(pts
				(arc
					(start 37.56533 -312.27141)
					(mid 37.580209 -312.307331)
					(end 37.61613 -312.32221)
				)
				(arc
					(start 39.01567 -312.32221)
					(mid 39.051591 -312.307331)
					(end 39.06647 -312.27141)
				)
				(arc
					(start 39.06647 -311.86247)
					(mid 39.051591 -311.826549)
					(end 39.01567 -311.81167)
				)
				(arc
					(start 37.61613 -311.81167)
					(mid 37.580209 -311.826549)
					(end 37.56533 -311.86247)
				)
			)
		)
	)
	(zone
		(layers "In1.Cu" "In2.Cu")
		(hatch none 0.5)
		(connect_pads
			(clearance 0)
		)
		(min_thickness 0.25)
		(keepout
			(tracks not_allowed)
			(vias allowed)
			(pads allowed)
			(copperpour not_allowed)
			(footprints allowed)
		)
		(placement
			(enabled no)
			(sheetname "")
		)
		(fill yes
			(thermal_gap 0.5)
			(thermal_bridge_width 0.5)
			(island_removal_mode 0)
		)
		(polygon
			(pts
				(arc
					(start 304.693066 -220.471492)
					(mid 304.707945 -220.507413)
					(end 304.743866 -220.522292)
				)
				(arc
					(start 306.143406 -220.522292)
					(mid 306.179327 -220.507413)
					(end 306.194206 -220.471492)
				)
				(arc
					(start 306.194206 -220.062552)
					(mid 306.179327 -220.026631)
					(end 306.143406 -220.011752)
				)
				(arc
					(start 304.743866 -220.011752)
					(mid 304.707945 -220.026631)
					(end 304.693066 -220.062552)
				)
			)
		)
	)
	(zone
		(layers "In1.Cu" "In2.Cu")
		(hatch none 0.5)
		(connect_pads
			(clearance 0)
		)
		(min_thickness 0.25)
		(keepout
			(tracks not_allowed)
			(vias allowed)
			(pads allowed)
			(copperpour not_allowed)
			(footprints allowed)
		)
		(placement
			(enabled no)
			(sheetname "")
		)
		(fill yes
			(thermal_gap 0.5)
			(thermal_bridge_width 0.5)
			(island_removal_mode 0)
		)
		(polygon
			(pts
				(arc
					(start 177.250598 -263.821418)
					(mid 177.265477 -263.857339)
					(end 177.301398 -263.872218)
				)
				(arc
					(start 178.700938 -263.872218)
					(mid 178.736859 -263.857339)
					(end 178.751738 -263.821418)
				)
				(arc
					(start 178.751738 -263.412478)
					(mid 178.736859 -263.376557)
					(end 178.700938 -263.361678)
				)
				(arc
					(start 177.301398 -263.361678)
					(mid 177.265477 -263.376557)
					(end 177.250598 -263.412478)
				)
			)
		)
	)
	(zone
		(layers "In1.Cu" "In2.Cu")
		(hatch none 0.5)
		(connect_pads
			(clearance 0)
		)
		(min_thickness 0.25)
		(keepout
			(tracks not_allowed)
			(vias allowed)
			(pads allowed)
			(copperpour not_allowed)
			(footprints allowed)
		)
		(placement
			(enabled no)
			(sheetname "")
		)
		(fill yes
			(thermal_gap 0.5)
			(thermal_bridge_width 0.5)
			(island_removal_mode 0)
		)
		(polygon
			(pts
				(arc
					(start 270.417798 -296.121328)
					(mid 270.432677 -296.157249)
					(end 270.468598 -296.172128)
				)
				(arc
					(start 271.868138 -296.172128)
					(mid 271.904059 -296.157249)
					(end 271.918938 -296.121328)
				)
				(arc
					(start 271.918938 -295.712388)
					(mid 271.904059 -295.676467)
					(end 271.868138 -295.661588)
				)
				(arc
					(start 270.468598 -295.661588)
					(mid 270.432677 -295.676467)
					(end 270.417798 -295.712388)
				)
			)
		)
	)
	(zone
		(layers "In1.Cu" "In2.Cu")
		(hatch none 0.5)
		(connect_pads
			(clearance 0)
		)
		(min_thickness 0.25)
		(keepout
			(tracks not_allowed)
			(vias allowed)
			(pads allowed)
			(copperpour not_allowed)
			(footprints allowed)
		)
		(placement
			(enabled no)
			(sheetname "")
		)
		(fill yes
			(thermal_gap 0.5)
			(thermal_bridge_width 0.5)
			(island_removal_mode 0)
		)
		(polygon
			(pts
				(arc
					(start 293.049198 -234.071414)
					(mid 293.064077 -234.107335)
					(end 293.099998 -234.122214)
				)
				(arc
					(start 294.499538 -234.122214)
					(mid 294.535459 -234.107335)
					(end 294.550338 -234.071414)
				)
				(arc
					(start 294.550338 -233.662474)
					(mid 294.535459 -233.626553)
					(end 294.499538 -233.611674)
				)
				(arc
					(start 293.099998 -233.611674)
					(mid 293.064077 -233.626553)
					(end 293.049198 -233.662474)
				)
			)
		)
	)
	(zone
		(layers "In1.Cu" "In2.Cu")
		(hatch none 0.5)
		(connect_pads
			(clearance 0)
		)
		(min_thickness 0.25)
		(keepout
			(tracks not_allowed)
			(vias allowed)
			(pads allowed)
			(copperpour not_allowed)
			(footprints allowed)
		)
		(placement
			(enabled no)
			(sheetname "")
		)
		(fill yes
			(thermal_gap 0.5)
			(thermal_bridge_width 0.5)
			(island_removal_mode 0)
		)
		(polygon
			(pts
				(arc
					(start 188.23813 -245.971314)
					(mid 188.253009 -246.007235)
					(end 188.28893 -246.022114)
				)
				(arc
					(start 189.68847 -246.022114)
					(mid 189.724391 -246.007235)
					(end 189.73927 -245.971314)
				)
				(arc
					(start 189.73927 -245.562374)
					(mid 189.724391 -245.526453)
					(end 189.68847 -245.511574)
				)
				(arc
					(start 188.28893 -245.511574)
					(mid 188.253009 -245.526453)
					(end 188.23813 -245.562374)
				)
			)
		)
	)
	(zone
		(layers "In1.Cu" "In2.Cu")
		(hatch none 0.5)
		(connect_pads
			(clearance 0)
		)
		(min_thickness 0.25)
		(keepout
			(tracks not_allowed)
			(vias allowed)
			(pads allowed)
			(copperpour not_allowed)
			(footprints allowed)
		)
		(placement
			(enabled no)
			(sheetname "")
		)
		(fill yes
			(thermal_gap 0.5)
			(thermal_bridge_width 0.5)
			(island_removal_mode 0)
		)
		(polygon
			(pts
				(arc
					(start 22.47773 -237.471458)
					(mid 22.492609 -237.507379)
					(end 22.52853 -237.522258)
				)
				(arc
					(start 23.92807 -237.522258)
					(mid 23.963991 -237.507379)
					(end 23.97887 -237.471458)
				)
				(arc
					(start 23.97887 -237.062518)
					(mid 23.963991 -237.026597)
					(end 23.92807 -237.011718)
				)
				(arc
					(start 22.52853 -237.011718)
					(mid 22.492609 -237.026597)
					(end 22.47773 -237.062518)
				)
			)
		)
	)
	(zone
		(layers "In1.Cu" "In2.Cu")
		(hatch none 0.5)
		(connect_pads
			(clearance 0)
		)
		(min_thickness 0.25)
		(keepout
			(tracks not_allowed)
			(vias allowed)
			(pads allowed)
			(copperpour not_allowed)
			(footprints allowed)
		)
		(placement
			(enabled no)
			(sheetname "")
		)
		(fill yes
			(thermal_gap 0.5)
			(thermal_bridge_width 0.5)
			(island_removal_mode 0)
		)
		(polygon
			(pts
				(arc
					(start 30.02153 -302.921416)
					(mid 30.036409 -302.957337)
					(end 30.07233 -302.972216)
				)
				(arc
					(start 31.47187 -302.972216)
					(mid 31.507791 -302.957337)
					(end 31.52267 -302.921416)
				)
				(arc
					(start 31.52267 -302.512476)
					(mid 31.507791 -302.476555)
					(end 31.47187 -302.461676)
				)
				(arc
					(start 30.07233 -302.461676)
					(mid 30.036409 -302.476555)
					(end 30.02153 -302.512476)
				)
			)
		)
	)
	(zone
		(layers "In1.Cu" "In2.Cu")
		(hatch none 0.5)
		(connect_pads
			(clearance 0)
		)
		(min_thickness 0.25)
		(keepout
			(tracks not_allowed)
			(vias allowed)
			(pads allowed)
			(copperpour not_allowed)
			(footprints allowed)
		)
		(placement
			(enabled no)
			(sheetname "")
		)
		(fill yes
			(thermal_gap 0.5)
			(thermal_bridge_width 0.5)
			(island_removal_mode 0)
		)
		(polygon
			(pts
				(arc
					(start 462.909666 -278.271478)
					(mid 462.924545 -278.307399)
					(end 462.960466 -278.322278)
				)
				(arc
					(start 464.360006 -278.322278)
					(mid 464.395927 -278.307399)
					(end 464.410806 -278.271478)
				)
				(arc
					(start 464.410806 -277.862538)
					(mid 464.395927 -277.826617)
					(end 464.360006 -277.811738)
				)
				(arc
					(start 462.960466 -277.811738)
					(mid 462.924545 -277.826617)
					(end 462.909666 -277.862538)
				)
			)
		)
	)
	(zone
		(layers "In1.Cu" "In2.Cu")
		(hatch none 0.5)
		(connect_pads
			(clearance 0)
		)
		(min_thickness 0.25)
		(keepout
			(tracks not_allowed)
			(vias allowed)
			(pads allowed)
			(copperpour not_allowed)
			(footprints allowed)
		)
		(placement
			(enabled no)
			(sheetname "")
		)
		(fill yes
			(thermal_gap 0.5)
			(thermal_bridge_width 0.5)
			(island_removal_mode 0)
		)
		(polygon
			(pts
				(arc
					(start 436.178198 -297.82135)
					(mid 436.193077 -297.857271)
					(end 436.228998 -297.87215)
				)
				(arc
					(start 437.628538 -297.87215)
					(mid 437.664459 -297.857271)
					(end 437.679338 -297.82135)
				)
				(arc
					(start 437.679338 -297.41241)
					(mid 437.664459 -297.376489)
					(end 437.628538 -297.36161)
				)
				(arc
					(start 436.228998 -297.36161)
					(mid 436.193077 -297.376489)
					(end 436.178198 -297.41241)
				)
			)
		)
	)
	(zone
		(layers "In1.Cu" "In2.Cu")
		(hatch none 0.5)
		(connect_pads
			(clearance 0)
		)
		(min_thickness 0.25)
		(keepout
			(tracks not_allowed)
			(vias allowed)
			(pads allowed)
			(copperpour not_allowed)
			(footprints allowed)
		)
		(placement
			(enabled no)
			(sheetname "")
		)
		(fill yes
			(thermal_gap 0.5)
			(thermal_bridge_width 0.5)
			(island_removal_mode 0)
		)
		(polygon
			(pts
				(arc
					(start 34.121598 -283.371544)
					(mid 34.136477 -283.407465)
					(end 34.172398 -283.422344)
				)
				(arc
					(start 35.571938 -283.422344)
					(mid 35.607859 -283.407465)
					(end 35.622738 -283.371544)
				)
				(arc
					(start 35.622738 -282.962604)
					(mid 35.607859 -282.926683)
					(end 35.571938 -282.911804)
				)
				(arc
					(start 34.172398 -282.911804)
					(mid 34.136477 -282.926683)
					(end 34.121598 -282.962604)
				)
			)
		)
	)
	(zone
		(layers "In1.Cu" "In2.Cu")
		(hatch none 0.5)
		(connect_pads
			(clearance 0)
		)
		(min_thickness 0.25)
		(keepout
			(tracks not_allowed)
			(vias allowed)
			(pads allowed)
			(copperpour not_allowed)
			(footprints allowed)
		)
		(placement
			(enabled no)
			(sheetname "")
		)
		(fill yes
			(thermal_gap 0.5)
			(thermal_bridge_width 0.5)
			(island_removal_mode 0)
		)
		(polygon
			(pts
				(arc
					(start 177.250598 -245.12143)
					(mid 177.265477 -245.157351)
					(end 177.301398 -245.17223)
				)
				(arc
					(start 178.700938 -245.17223)
					(mid 178.736859 -245.157351)
					(end 178.751738 -245.12143)
				)
				(arc
					(start 178.751738 -244.71249)
					(mid 178.736859 -244.676569)
					(end 178.700938 -244.66169)
				)
				(arc
					(start 177.301398 -244.66169)
					(mid 177.265477 -244.676569)
					(end 177.250598 -244.71249)
				)
			)
		)
	)
	(zone
		(layers "In1.Cu" "In2.Cu")
		(hatch none 0.5)
		(connect_pads
			(clearance 0)
		)
		(min_thickness 0.25)
		(keepout
			(tracks not_allowed)
			(vias allowed)
			(pads allowed)
			(copperpour not_allowed)
			(footprints allowed)
		)
		(placement
			(enabled no)
			(sheetname "")
		)
		(fill yes
			(thermal_gap 0.5)
			(thermal_bridge_width 0.5)
			(island_removal_mode 0)
		)
		(polygon
			(pts
				(arc
					(start 34.121598 -227.271326)
					(mid 34.136477 -227.307247)
					(end 34.172398 -227.322126)
				)
				(arc
					(start 35.571938 -227.322126)
					(mid 35.607859 -227.307247)
					(end 35.622738 -227.271326)
				)
				(arc
					(start 35.622738 -226.862386)
					(mid 35.607859 -226.826465)
					(end 35.571938 -226.811586)
				)
				(arc
					(start 34.172398 -226.811586)
					(mid 34.136477 -226.826465)
					(end 34.121598 -226.862386)
				)
			)
		)
	)
	(zone
		(layers "In1.Cu" "In2.Cu")
		(hatch none 0.5)
		(connect_pads
			(clearance 0)
		)
		(min_thickness 0.25)
		(keepout
			(tracks not_allowed)
			(vias allowed)
			(pads allowed)
			(copperpour not_allowed)
			(footprints allowed)
		)
		(placement
			(enabled no)
			(sheetname "")
		)
		(fill yes
			(thermal_gap 0.5)
			(thermal_bridge_width 0.5)
			(island_removal_mode 0)
		)
		(polygon
			(pts
				(arc
					(start 188.23813 -252.771402)
					(mid 188.253009 -252.807323)
					(end 188.28893 -252.822202)
				)
				(arc
					(start 189.68847 -252.822202)
					(mid 189.724391 -252.807323)
					(end 189.73927 -252.771402)
				)
				(arc
					(start 189.73927 -252.362462)
					(mid 189.724391 -252.326541)
					(end 189.68847 -252.311662)
				)
				(arc
					(start 188.28893 -252.311662)
					(mid 188.253009 -252.326541)
					(end 188.23813 -252.362462)
				)
			)
		)
	)
	(zone
		(layers "In1.Cu" "In2.Cu")
		(hatch none 0.5)
		(connect_pads
			(clearance 0)
		)
		(min_thickness 0.25)
		(keepout
			(tracks not_allowed)
			(vias allowed)
			(pads allowed)
			(copperpour not_allowed)
			(footprints allowed)
		)
		(placement
			(enabled no)
			(sheetname "")
		)
		(fill yes
			(thermal_gap 0.5)
			(thermal_bridge_width 0.5)
			(island_removal_mode 0)
		)
		(polygon
			(pts
				(arc
					(start 214.969598 -229.821486)
					(mid 214.984477 -229.857407)
					(end 215.020398 -229.872286)
				)
				(arc
					(start 216.419938 -229.872286)
					(mid 216.455859 -229.857407)
					(end 216.470738 -229.821486)
				)
				(arc
					(start 216.470738 -229.412546)
					(mid 216.455859 -229.376625)
					(end 216.419938 -229.361746)
				)
				(arc
					(start 215.020398 -229.361746)
					(mid 214.984477 -229.376625)
					(end 214.969598 -229.412546)
				)
			)
		)
	)
	(zone
		(layers "In1.Cu" "In2.Cu")
		(hatch none 0.5)
		(connect_pads
			(clearance 0)
		)
		(min_thickness 0.25)
		(keepout
			(tracks not_allowed)
			(vias allowed)
			(pads allowed)
			(copperpour not_allowed)
			(footprints allowed)
		)
		(placement
			(enabled no)
			(sheetname "")
		)
		(fill yes
			(thermal_gap 0.5)
			(thermal_bridge_width 0.5)
			(island_removal_mode 0)
		)
		(polygon
			(pts
				(arc
					(start 180.69433 -279.121362)
					(mid 180.709209 -279.157283)
					(end 180.74513 -279.172162)
				)
				(arc
					(start 182.14467 -279.172162)
					(mid 182.180591 -279.157283)
					(end 182.19547 -279.121362)
				)
				(arc
					(start 182.19547 -278.712422)
					(mid 182.180591 -278.676501)
					(end 182.14467 -278.661622)
				)
				(arc
					(start 180.74513 -278.661622)
					(mid 180.709209 -278.676501)
					(end 180.69433 -278.712422)
				)
			)
		)
	)
	(zone
		(layers "In1.Cu" "In2.Cu")
		(hatch none 0.5)
		(connect_pads
			(clearance 0)
		)
		(min_thickness 0.25)
		(keepout
			(tracks not_allowed)
			(vias allowed)
			(pads allowed)
			(copperpour not_allowed)
			(footprints allowed)
		)
		(placement
			(enabled no)
			(sheetname "")
		)
		(fill yes
			(thermal_gap 0.5)
			(thermal_bridge_width 0.5)
			(island_removal_mode 0)
		)
		(polygon
			(pts
				(arc
					(start 447.822066 -263.821418)
					(mid 447.836945 -263.857339)
					(end 447.872866 -263.872218)
				)
				(arc
					(start 449.272406 -263.872218)
					(mid 449.308327 -263.857339)
					(end 449.323206 -263.821418)
				)
				(arc
					(start 449.323206 -263.412478)
					(mid 449.308327 -263.376557)
					(end 449.272406 -263.361678)
				)
				(arc
					(start 447.872866 -263.361678)
					(mid 447.836945 -263.376557)
					(end 447.822066 -263.412478)
				)
			)
		)
	)
	(zone
		(layers "In1.Cu" "In2.Cu")
		(hatch none 0.5)
		(connect_pads
			(clearance 0)
		)
		(min_thickness 0.25)
		(keepout
			(tracks not_allowed)
			(vias allowed)
			(pads allowed)
			(copperpour not_allowed)
			(footprints allowed)
		)
		(placement
			(enabled no)
			(sheetname "")
		)
		(fill yes
			(thermal_gap 0.5)
			(thermal_bridge_width 0.5)
			(island_removal_mode 0)
		)
		(polygon
			(pts
				(arc
					(start 52.65293 -291.8714)
					(mid 52.667809 -291.907321)
					(end 52.70373 -291.9222)
				)
				(arc
					(start 54.10327 -291.9222)
					(mid 54.139191 -291.907321)
					(end 54.15407 -291.8714)
				)
				(arc
					(start 54.15407 -291.46246)
					(mid 54.139191 -291.426539)
					(end 54.10327 -291.41166)
				)
				(arc
					(start 52.70373 -291.41166)
					(mid 52.667809 -291.426539)
					(end 52.65293 -291.46246)
				)
			)
		)
	)
	(zone
		(layers "In1.Cu" "In2.Cu")
		(hatch none 0.5)
		(connect_pads
			(clearance 0)
		)
		(min_thickness 0.25)
		(keepout
			(tracks not_allowed)
			(vias allowed)
			(pads allowed)
			(copperpour not_allowed)
			(footprints allowed)
		)
		(placement
			(enabled no)
			(sheetname "")
		)
		(fill yes
			(thermal_gap 0.5)
			(thermal_bridge_width 0.5)
			(island_removal_mode 0)
		)
		(polygon
			(pts
				(arc
					(start 177.250598 -206.871316)
					(mid 177.265477 -206.907237)
					(end 177.301398 -206.922116)
				)
				(arc
					(start 178.700938 -206.922116)
					(mid 178.736859 -206.907237)
					(end 178.751738 -206.871316)
				)
				(arc
					(start 178.751738 -206.462376)
					(mid 178.736859 -206.426455)
					(end 178.700938 -206.411576)
				)
				(arc
					(start 177.301398 -206.411576)
					(mid 177.265477 -206.426455)
					(end 177.250598 -206.462376)
				)
			)
		)
	)
	(zone
		(layers "In1.Cu" "In2.Cu")
		(hatch none 0.5)
		(connect_pads
			(clearance 0)
		)
		(min_thickness 0.25)
		(keepout
			(tracks not_allowed)
			(vias allowed)
			(pads allowed)
			(copperpour not_allowed)
			(footprints allowed)
		)
		(placement
			(enabled no)
			(sheetname "")
		)
		(fill yes
			(thermal_gap 0.5)
			(thermal_bridge_width 0.5)
			(island_removal_mode 0)
		)
		(polygon
			(pts
				(arc
					(start 266.974066 -293.571422)
					(mid 266.988945 -293.607343)
					(end 267.024866 -293.622222)
				)
				(arc
					(start 268.424406 -293.622222)
					(mid 268.460327 -293.607343)
					(end 268.475206 -293.571422)
				)
				(arc
					(start 268.475206 -293.162482)
					(mid 268.460327 -293.126561)
					(end 268.424406 -293.111682)
				)
				(arc
					(start 267.024866 -293.111682)
					(mid 266.988945 -293.126561)
					(end 266.974066 -293.162482)
				)
			)
		)
	)
	(zone
		(layers "In1.Cu" "In2.Cu")
		(hatch none 0.5)
		(connect_pads
			(clearance 0)
		)
		(min_thickness 0.25)
		(keepout
			(tracks not_allowed)
			(vias allowed)
			(pads allowed)
			(copperpour not_allowed)
			(footprints allowed)
		)
		(placement
			(enabled no)
			(sheetname "")
		)
		(fill yes
			(thermal_gap 0.5)
			(thermal_bridge_width 0.5)
			(island_removal_mode 0)
		)
		(polygon
			(pts
				(arc
					(start 56.752998 -274.871434)
					(mid 56.767877 -274.907355)
					(end 56.803798 -274.922234)
				)
				(arc
					(start 58.203338 -274.922234)
					(mid 58.239259 -274.907355)
					(end 58.254138 -274.871434)
				)
				(arc
					(start 58.254138 -274.462494)
					(mid 58.239259 -274.426573)
					(end 58.203338 -274.411694)
				)
				(arc
					(start 56.803798 -274.411694)
					(mid 56.767877 -274.426573)
					(end 56.752998 -274.462494)
				)
			)
		)
	)
	(zone
		(layers "In1.Cu" "In2.Cu")
		(hatch none 0.5)
		(connect_pads
			(clearance 0)
		)
		(min_thickness 0.25)
		(keepout
			(tracks not_allowed)
			(vias allowed)
			(pads allowed)
			(copperpour not_allowed)
			(footprints allowed)
		)
		(placement
			(enabled no)
			(sheetname "")
		)
		(fill yes
			(thermal_gap 0.5)
			(thermal_bridge_width 0.5)
			(island_removal_mode 0)
		)
		(polygon
			(pts
				(arc
					(start 173.15053 -223.021398)
					(mid 173.165409 -223.057319)
					(end 173.20133 -223.072198)
				)
				(arc
					(start 174.60087 -223.072198)
					(mid 174.636791 -223.057319)
					(end 174.65167 -223.021398)
				)
				(arc
					(start 174.65167 -222.612458)
					(mid 174.636791 -222.576537)
					(end 174.60087 -222.561658)
				)
				(arc
					(start 173.20133 -222.561658)
					(mid 173.165409 -222.576537)
					(end 173.15053 -222.612458)
				)
			)
		)
	)
	(zone
		(layers "In1.Cu" "In2.Cu")
		(hatch none 0.5)
		(connect_pads
			(clearance 0)
		)
		(min_thickness 0.25)
		(keepout
			(tracks not_allowed)
			(vias allowed)
			(pads allowed)
			(copperpour not_allowed)
			(footprints allowed)
		)
		(placement
			(enabled no)
			(sheetname "")
		)
		(fill yes
			(thermal_gap 0.5)
			(thermal_bridge_width 0.5)
			(island_removal_mode 0)
		)
		(polygon
			(pts
				(arc
					(start 19.033998 -240.871502)
					(mid 19.048877 -240.907423)
					(end 19.084798 -240.922302)
				)
				(arc
					(start 20.484338 -240.922302)
					(mid 20.520259 -240.907423)
					(end 20.535138 -240.871502)
				)
				(arc
					(start 20.535138 -240.462562)
					(mid 20.520259 -240.426641)
					(end 20.484338 -240.411762)
				)
				(arc
					(start 19.084798 -240.411762)
					(mid 19.048877 -240.426641)
					(end 19.033998 -240.462562)
				)
			)
		)
	)
	(zone
		(layers "In1.Cu" "In2.Cu")
		(hatch none 0.5)
		(connect_pads
			(clearance 0)
		)
		(min_thickness 0.25)
		(keepout
			(tracks not_allowed)
			(vias allowed)
			(pads allowed)
			(copperpour not_allowed)
			(footprints allowed)
		)
		(placement
			(enabled no)
			(sheetname "")
		)
		(fill yes
			(thermal_gap 0.5)
			(thermal_bridge_width 0.5)
			(island_removal_mode 0)
		)
		(polygon
			(pts
				(arc
					(start 458.809598 -307.171344)
					(mid 458.824477 -307.207265)
					(end 458.860398 -307.222144)
				)
				(arc
					(start 460.259938 -307.222144)
					(mid 460.295859 -307.207265)
					(end 460.310738 -307.171344)
				)
				(arc
					(start 460.310738 -306.762404)
					(mid 460.295859 -306.726483)
					(end 460.259938 -306.711604)
				)
				(arc
					(start 458.860398 -306.711604)
					(mid 458.824477 -306.726483)
					(end 458.809598 -306.762404)
				)
			)
		)
	)
	(zone
		(layers "In1.Cu" "In2.Cu")
		(hatch none 0.5)
		(connect_pads
			(clearance 0)
		)
		(min_thickness 0.25)
		(keepout
			(tracks not_allowed)
			(vias allowed)
			(pads allowed)
			(copperpour not_allowed)
			(footprints allowed)
		)
		(placement
			(enabled no)
			(sheetname "")
		)
		(fill yes
			(thermal_gap 0.5)
			(thermal_bridge_width 0.5)
			(island_removal_mode 0)
		)
		(polygon
			(pts
				(arc
					(start 428.634398 -290.171378)
					(mid 428.649277 -290.207299)
					(end 428.685198 -290.222178)
				)
				(arc
					(start 430.084738 -290.222178)
					(mid 430.120659 -290.207299)
					(end 430.135538 -290.171378)
				)
				(arc
					(start 430.135538 -289.762438)
					(mid 430.120659 -289.726517)
					(end 430.084738 -289.711638)
				)
				(arc
					(start 428.685198 -289.711638)
					(mid 428.649277 -289.726517)
					(end 428.634398 -289.762438)
				)
			)
		)
	)
	(zone
		(layers "In1.Cu" "In2.Cu")
		(hatch none 0.5)
		(connect_pads
			(clearance 0)
		)
		(min_thickness 0.25)
		(keepout
			(tracks not_allowed)
			(vias allowed)
			(pads allowed)
			(copperpour not_allowed)
			(footprints allowed)
		)
		(placement
			(enabled no)
			(sheetname "")
		)
		(fill yes
			(thermal_gap 0.5)
			(thermal_bridge_width 0.5)
			(island_removal_mode 0)
		)
		(polygon
			(pts
				(arc
					(start 425.190666 -197.521322)
					(mid 425.205545 -197.557243)
					(end 425.241466 -197.572122)
				)
				(arc
					(start 426.641006 -197.572122)
					(mid 426.676927 -197.557243)
					(end 426.691806 -197.521322)
				)
				(arc
					(start 426.691806 -197.112382)
					(mid 426.676927 -197.076461)
					(end 426.641006 -197.061582)
				)
				(arc
					(start 425.241466 -197.061582)
					(mid 425.205545 -197.076461)
					(end 425.190666 -197.112382)
				)
			)
		)
	)
	(zone
		(layers "In1.Cu" "In2.Cu")
		(hatch none 0.5)
		(connect_pads
			(clearance 0)
		)
		(min_thickness 0.25)
		(keepout
			(tracks not_allowed)
			(vias allowed)
			(pads allowed)
			(copperpour not_allowed)
			(footprints allowed)
		)
		(placement
			(enabled no)
			(sheetname "")
		)
		(fill yes
			(thermal_gap 0.5)
			(thermal_bridge_width 0.5)
			(island_removal_mode 0)
		)
		(polygon
			(pts
				(arc
					(start 30.02153 -269.771368)
					(mid 30.036409 -269.807289)
					(end 30.07233 -269.822168)
				)
				(arc
					(start 31.47187 -269.822168)
					(mid 31.507791 -269.807289)
					(end 31.52267 -269.771368)
				)
				(arc
					(start 31.52267 -269.362428)
					(mid 31.507791 -269.326507)
					(end 31.47187 -269.311628)
				)
				(arc
					(start 30.07233 -269.311628)
					(mid 30.036409 -269.326507)
					(end 30.02153 -269.362428)
				)
			)
		)
	)
	(zone
		(layers "In1.Cu" "In2.Cu")
		(hatch none 0.5)
		(connect_pads
			(clearance 0)
		)
		(min_thickness 0.25)
		(keepout
			(tracks not_allowed)
			(vias allowed)
			(pads allowed)
			(copperpour not_allowed)
			(footprints allowed)
		)
		(placement
			(enabled no)
			(sheetname "")
		)
		(fill yes
			(thermal_gap 0.5)
			(thermal_bridge_width 0.5)
			(island_removal_mode 0)
		)
		(polygon
			(pts
				(arc
					(start 255.330198 -303.7713)
					(mid 255.345077 -303.807221)
					(end 255.380998 -303.8221)
				)
				(arc
					(start 256.780538 -303.8221)
					(mid 256.816459 -303.807221)
					(end 256.831338 -303.7713)
				)
				(arc
					(start 256.831338 -303.36236)
					(mid 256.816459 -303.326439)
					(end 256.780538 -303.31156)
				)
				(arc
					(start 255.380998 -303.31156)
					(mid 255.345077 -303.326439)
					(end 255.330198 -303.36236)
				)
			)
		)
	)
	(zone
		(layers "In1.Cu" "In2.Cu")
		(hatch none 0.5)
		(connect_pads
			(clearance 0)
		)
		(min_thickness 0.25)
		(keepout
			(tracks not_allowed)
			(vias allowed)
			(pads allowed)
			(copperpour not_allowed)
			(footprints allowed)
		)
		(placement
			(enabled no)
			(sheetname "")
		)
		(fill yes
			(thermal_gap 0.5)
			(thermal_bridge_width 0.5)
			(island_removal_mode 0)
		)
		(polygon
			(pts
				(arc
					(start 300.592998 -286.771334)
					(mid 300.607877 -286.807255)
					(end 300.643798 -286.822134)
				)
				(arc
					(start 302.043338 -286.822134)
					(mid 302.079259 -286.807255)
					(end 302.094138 -286.771334)
				)
				(arc
					(start 302.094138 -286.362394)
					(mid 302.079259 -286.326473)
					(end 302.043338 -286.311594)
				)
				(arc
					(start 300.643798 -286.311594)
					(mid 300.607877 -286.326473)
					(end 300.592998 -286.362394)
				)
			)
		)
	)
	(zone
		(layers "In1.Cu" "In2.Cu")
		(hatch none 0.5)
		(connect_pads
			(clearance 0)
		)
		(min_thickness 0.25)
		(keepout
			(tracks not_allowed)
			(vias allowed)
			(pads allowed)
			(copperpour not_allowed)
			(footprints allowed)
		)
		(placement
			(enabled no)
			(sheetname "")
		)
		(fill yes
			(thermal_gap 0.5)
			(thermal_bridge_width 0.5)
			(island_removal_mode 0)
		)
		(polygon
			(pts
				(arc
					(start 285.505398 -247.671336)
					(mid 285.520277 -247.707257)
					(end 285.556198 -247.722136)
				)
				(arc
					(start 286.955738 -247.722136)
					(mid 286.991659 -247.707257)
					(end 287.006538 -247.671336)
				)
				(arc
					(start 287.006538 -247.262396)
					(mid 286.991659 -247.226475)
					(end 286.955738 -247.211596)
				)
				(arc
					(start 285.556198 -247.211596)
					(mid 285.520277 -247.226475)
					(end 285.505398 -247.262396)
				)
			)
		)
	)
	(zone
		(layers "In1.Cu" "In2.Cu")
		(hatch none 0.5)
		(connect_pads
			(clearance 0)
		)
		(min_thickness 0.25)
		(keepout
			(tracks not_allowed)
			(vias allowed)
			(pads allowed)
			(copperpour not_allowed)
			(footprints allowed)
		)
		(placement
			(enabled no)
			(sheetname "")
		)
		(fill yes
			(thermal_gap 0.5)
			(thermal_bridge_width 0.5)
			(island_removal_mode 0)
		)
		(polygon
			(pts
				(arc
					(start 184.794398 -199.221344)
					(mid 184.809277 -199.257265)
					(end 184.845198 -199.272144)
				)
				(arc
					(start 186.244738 -199.272144)
					(mid 186.280659 -199.257265)
					(end 186.295538 -199.221344)
				)
				(arc
					(start 186.295538 -198.812404)
					(mid 186.280659 -198.776483)
					(end 186.244738 -198.761604)
				)
				(arc
					(start 184.845198 -198.761604)
					(mid 184.809277 -198.776483)
					(end 184.794398 -198.812404)
				)
			)
		)
	)
	(zone
		(layers "In1.Cu" "In2.Cu")
		(hatch none 0.5)
		(connect_pads
			(clearance 0)
		)
		(min_thickness 0.25)
		(keepout
			(tracks not_allowed)
			(vias allowed)
			(pads allowed)
			(copperpour not_allowed)
			(footprints allowed)
		)
		(placement
			(enabled no)
			(sheetname "")
		)
		(fill yes
			(thermal_gap 0.5)
			(thermal_bridge_width 0.5)
			(island_removal_mode 0)
		)
		(polygon
			(pts
				(arc
					(start 41.665398 -217.921332)
					(mid 41.680277 -217.957253)
					(end 41.716198 -217.972132)
				)
				(arc
					(start 43.115738 -217.972132)
					(mid 43.151659 -217.957253)
					(end 43.166538 -217.921332)
				)
				(arc
					(start 43.166538 -217.512392)
					(mid 43.151659 -217.476471)
					(end 43.115738 -217.461592)
				)
				(arc
					(start 41.716198 -217.461592)
					(mid 41.680277 -217.476471)
					(end 41.665398 -217.512392)
				)
			)
		)
	)
	(zone
		(layers "In1.Cu" "In2.Cu")
		(hatch none 0.5)
		(connect_pads
			(clearance 0)
		)
		(min_thickness 0.25)
		(keepout
			(tracks not_allowed)
			(vias allowed)
			(pads allowed)
			(copperpour not_allowed)
			(footprints allowed)
		)
		(placement
			(enabled no)
			(sheetname "")
		)
		(fill yes
			(thermal_gap 0.5)
			(thermal_bridge_width 0.5)
			(island_removal_mode 0)
		)
		(polygon
			(pts
				(arc
					(start 192.338198 -231.521508)
					(mid 192.353077 -231.557429)
					(end 192.388998 -231.572308)
				)
				(arc
					(start 193.788538 -231.572308)
					(mid 193.824459 -231.557429)
					(end 193.839338 -231.521508)
				)
				(arc
					(start 193.839338 -231.112568)
					(mid 193.824459 -231.076647)
					(end 193.788538 -231.061768)
				)
				(arc
					(start 192.388998 -231.061768)
					(mid 192.353077 -231.076647)
					(end 192.338198 -231.112568)
				)
			)
		)
	)
	(zone
		(layers "In1.Cu" "In2.Cu")
		(hatch none 0.5)
		(connect_pads
			(clearance 0)
		)
		(min_thickness 0.25)
		(keepout
			(tracks not_allowed)
			(vias allowed)
			(pads allowed)
			(copperpour not_allowed)
			(footprints allowed)
		)
		(placement
			(enabled no)
			(sheetname "")
		)
		(fill yes
			(thermal_gap 0.5)
			(thermal_bridge_width 0.5)
			(island_removal_mode 0)
		)
		(polygon
			(pts
				(arc
					(start 177.250598 -285.92145)
					(mid 177.265477 -285.957371)
					(end 177.301398 -285.97225)
				)
				(arc
					(start 178.700938 -285.97225)
					(mid 178.736859 -285.957371)
					(end 178.751738 -285.92145)
				)
				(arc
					(start 178.751738 -285.51251)
					(mid 178.736859 -285.476589)
					(end 178.700938 -285.46171)
				)
				(arc
					(start 177.301398 -285.46171)
					(mid 177.265477 -285.476589)
					(end 177.250598 -285.51251)
				)
			)
		)
	)
	(zone
		(layers "In1.Cu" "In2.Cu")
		(hatch none 0.5)
		(connect_pads
			(clearance 0)
		)
		(min_thickness 0.25)
		(keepout
			(tracks not_allowed)
			(vias allowed)
			(pads allowed)
			(copperpour not_allowed)
			(footprints allowed)
		)
		(placement
			(enabled no)
			(sheetname "")
		)
		(fill yes
			(thermal_gap 0.5)
			(thermal_bridge_width 0.5)
			(island_removal_mode 0)
		)
		(polygon
			(pts
				(arc
					(start 180.69433 -221.321376)
					(mid 180.709209 -221.357297)
					(end 180.74513 -221.372176)
				)
				(arc
					(start 182.14467 -221.372176)
					(mid 182.180591 -221.357297)
					(end 182.19547 -221.321376)
				)
				(arc
					(start 182.19547 -220.912436)
					(mid 182.180591 -220.876515)
					(end 182.14467 -220.861636)
				)
				(arc
					(start 180.74513 -220.861636)
					(mid 180.709209 -220.876515)
					(end 180.69433 -220.912436)
				)
			)
		)
	)
	(zone
		(layers "In1.Cu" "In2.Cu")
		(hatch none 0.5)
		(connect_pads
			(clearance 0)
		)
		(min_thickness 0.25)
		(keepout
			(tracks not_allowed)
			(vias allowed)
			(pads allowed)
			(copperpour not_allowed)
			(footprints allowed)
		)
		(placement
			(enabled no)
			(sheetname "")
		)
		(fill yes
			(thermal_gap 0.5)
			(thermal_bridge_width 0.5)
			(island_removal_mode 0)
		)
		(polygon
			(pts
				(arc
					(start 282.061666 -201.771504)
					(mid 282.076545 -201.807425)
					(end 282.112466 -201.822304)
				)
				(arc
					(start 283.512006 -201.822304)
					(mid 283.547927 -201.807425)
					(end 283.562806 -201.771504)
				)
				(arc
					(start 283.562806 -201.362564)
					(mid 283.547927 -201.326643)
					(end 283.512006 -201.311764)
				)
				(arc
					(start 282.112466 -201.311764)
					(mid 282.076545 -201.326643)
					(end 282.061666 -201.362564)
				)
			)
		)
	)
	(zone
		(layers "In1.Cu" "In2.Cu")
		(hatch none 0.5)
		(connect_pads
			(clearance 0)
		)
		(min_thickness 0.25)
		(keepout
			(tracks not_allowed)
			(vias allowed)
			(pads allowed)
			(copperpour not_allowed)
			(footprints allowed)
		)
		(placement
			(enabled no)
			(sheetname "")
		)
		(fill yes
			(thermal_gap 0.5)
			(thermal_bridge_width 0.5)
			(island_removal_mode 0)
		)
		(polygon
			(pts
				(arc
					(start 195.78193 -221.321376)
					(mid 195.796809 -221.357297)
					(end 195.83273 -221.372176)
				)
				(arc
					(start 197.23227 -221.372176)
					(mid 197.268191 -221.357297)
					(end 197.28307 -221.321376)
				)
				(arc
					(start 197.28307 -220.912436)
					(mid 197.268191 -220.876515)
					(end 197.23227 -220.861636)
				)
				(arc
					(start 195.83273 -220.861636)
					(mid 195.796809 -220.876515)
					(end 195.78193 -220.912436)
				)
			)
		)
	)
	(zone
		(layers "In1.Cu" "In2.Cu")
		(hatch none 0.5)
		(connect_pads
			(clearance 0)
		)
		(min_thickness 0.25)
		(keepout
			(tracks not_allowed)
			(vias allowed)
			(pads allowed)
			(copperpour not_allowed)
			(footprints allowed)
		)
		(placement
			(enabled no)
			(sheetname "")
		)
		(fill yes
			(thermal_gap 0.5)
			(thermal_bridge_width 0.5)
			(island_removal_mode 0)
		)
		(polygon
			(pts
				(arc
					(start 432.734466 -199.221344)
					(mid 432.749345 -199.257265)
					(end 432.785266 -199.272144)
				)
				(arc
					(start 434.184806 -199.272144)
					(mid 434.220727 -199.257265)
					(end 434.235606 -199.221344)
				)
				(arc
					(start 434.235606 -198.812404)
					(mid 434.220727 -198.776483)
					(end 434.184806 -198.761604)
				)
				(arc
					(start 432.785266 -198.761604)
					(mid 432.749345 -198.776483)
					(end 432.734466 -198.812404)
				)
			)
		)
	)
	(zone
		(layers "In1.Cu" "In2.Cu")
		(hatch none 0.5)
		(connect_pads
			(clearance 0)
		)
		(min_thickness 0.25)
		(keepout
			(tracks not_allowed)
			(vias allowed)
			(pads allowed)
			(copperpour not_allowed)
			(footprints allowed)
		)
		(placement
			(enabled no)
			(sheetname "")
		)
		(fill yes
			(thermal_gap 0.5)
			(thermal_bridge_width 0.5)
			(island_removal_mode 0)
		)
		(polygon
			(pts
				(arc
					(start 26.577798 -209.421476)
					(mid 26.592677 -209.457397)
					(end 26.628598 -209.472276)
				)
				(arc
					(start 28.028138 -209.472276)
					(mid 28.064059 -209.457397)
					(end 28.078938 -209.421476)
				)
				(arc
					(start 28.078938 -209.012536)
					(mid 28.064059 -208.976615)
					(end 28.028138 -208.961736)
				)
				(arc
					(start 26.628598 -208.961736)
					(mid 26.592677 -208.976615)
					(end 26.577798 -209.012536)
				)
			)
		)
	)
	(zone
		(layers "In1.Cu" "In2.Cu")
		(hatch none 0.5)
		(connect_pads
			(clearance 0)
		)
		(min_thickness 0.25)
		(keepout
			(tracks not_allowed)
			(vias allowed)
			(pads allowed)
			(copperpour not_allowed)
			(footprints allowed)
		)
		(placement
			(enabled no)
			(sheetname "")
		)
		(fill yes
			(thermal_gap 0.5)
			(thermal_bridge_width 0.5)
			(island_removal_mode 0)
		)
		(polygon
			(pts
				(arc
					(start 195.78193 -209.421476)
					(mid 195.796809 -209.457397)
					(end 195.83273 -209.472276)
				)
				(arc
					(start 197.23227 -209.472276)
					(mid 197.268191 -209.457397)
					(end 197.28307 -209.421476)
				)
				(arc
					(start 197.28307 -209.012536)
					(mid 197.268191 -208.976615)
					(end 197.23227 -208.961736)
				)
				(arc
					(start 195.83273 -208.961736)
					(mid 195.796809 -208.976615)
					(end 195.78193 -209.012536)
				)
			)
		)
	)
	(zone
		(layers "In1.Cu" "In2.Cu")
		(hatch none 0.5)
		(connect_pads
			(clearance 0)
		)
		(min_thickness 0.25)
		(keepout
			(tracks not_allowed)
			(vias allowed)
			(pads allowed)
			(copperpour not_allowed)
			(footprints allowed)
		)
		(placement
			(enabled no)
			(sheetname "")
		)
		(fill yes
			(thermal_gap 0.5)
			(thermal_bridge_width 0.5)
			(island_removal_mode 0)
		)
		(polygon
			(pts
				(arc
					(start 282.061666 -295.271444)
					(mid 282.076545 -295.307365)
					(end 282.112466 -295.322244)
				)
				(arc
					(start 283.512006 -295.322244)
					(mid 283.547927 -295.307365)
					(end 283.562806 -295.271444)
				)
				(arc
					(start 283.562806 -294.862504)
					(mid 283.547927 -294.826583)
					(end 283.512006 -294.811704)
				)
				(arc
					(start 282.112466 -294.811704)
					(mid 282.076545 -294.826583)
					(end 282.061666 -294.862504)
				)
			)
		)
	)
	(zone
		(layers "In1.Cu" "In2.Cu")
		(hatch none 0.5)
		(connect_pads
			(clearance 0)
		)
		(min_thickness 0.25)
		(keepout
			(tracks not_allowed)
			(vias allowed)
			(pads allowed)
			(copperpour not_allowed)
			(footprints allowed)
		)
		(placement
			(enabled no)
			(sheetname "")
		)
		(fill yes
			(thermal_gap 0.5)
			(thermal_bridge_width 0.5)
			(island_removal_mode 0)
		)
		(polygon
			(pts
				(arc
					(start 207.425798 -302.071532)
					(mid 207.440677 -302.107453)
					(end 207.476598 -302.122332)
				)
				(arc
					(start 208.876138 -302.122332)
					(mid 208.912059 -302.107453)
					(end 208.926938 -302.071532)
				)
				(arc
					(start 208.926938 -301.662592)
					(mid 208.912059 -301.626671)
					(end 208.876138 -301.611792)
				)
				(arc
					(start 207.476598 -301.611792)
					(mid 207.440677 -301.626671)
					(end 207.425798 -301.662592)
				)
			)
		)
	)
	(zone
		(layers "In1.Cu" "In2.Cu")
		(hatch none 0.5)
		(connect_pads
			(clearance 0)
		)
		(min_thickness 0.25)
		(keepout
			(tracks not_allowed)
			(vias allowed)
			(pads allowed)
			(copperpour not_allowed)
			(footprints allowed)
		)
		(placement
			(enabled no)
			(sheetname "")
		)
		(fill yes
			(thermal_gap 0.5)
			(thermal_bridge_width 0.5)
			(island_removal_mode 0)
		)
		(polygon
			(pts
				(arc
					(start 49.209198 -276.571456)
					(mid 49.224077 -276.607377)
					(end 49.259998 -276.622256)
				)
				(arc
					(start 50.659538 -276.622256)
					(mid 50.695459 -276.607377)
					(end 50.710338 -276.571456)
				)
				(arc
					(start 50.710338 -276.162516)
					(mid 50.695459 -276.126595)
					(end 50.659538 -276.111716)
				)
				(arc
					(start 49.259998 -276.111716)
					(mid 49.224077 -276.126595)
					(end 49.209198 -276.162516)
				)
			)
		)
	)
	(zone
		(layers "In1.Cu" "In2.Cu")
		(hatch none 0.5)
		(connect_pads
			(clearance 0)
		)
		(min_thickness 0.25)
		(keepout
			(tracks not_allowed)
			(vias allowed)
			(pads allowed)
			(copperpour not_allowed)
			(footprints allowed)
		)
		(placement
			(enabled no)
			(sheetname "")
		)
		(fill yes
			(thermal_gap 0.5)
			(thermal_bridge_width 0.5)
			(island_removal_mode 0)
		)
		(polygon
			(pts
				(arc
					(start 49.209198 -227.271326)
					(mid 49.224077 -227.307247)
					(end 49.259998 -227.322126)
				)
				(arc
					(start 50.659538 -227.322126)
					(mid 50.695459 -227.307247)
					(end 50.710338 -227.271326)
				)
				(arc
					(start 50.710338 -226.862386)
					(mid 50.695459 -226.826465)
					(end 50.659538 -226.811586)
				)
				(arc
					(start 49.259998 -226.811586)
					(mid 49.224077 -226.826465)
					(end 49.209198 -226.862386)
				)
			)
		)
	)
	(zone
		(layers "In1.Cu" "In2.Cu")
		(hatch none 0.5)
		(connect_pads
			(clearance 0)
		)
		(min_thickness 0.25)
		(keepout
			(tracks not_allowed)
			(vias allowed)
			(pads allowed)
			(copperpour not_allowed)
			(footprints allowed)
		)
		(placement
			(enabled no)
			(sheetname "")
		)
		(fill yes
			(thermal_gap 0.5)
			(thermal_bridge_width 0.5)
			(island_removal_mode 0)
		)
		(polygon
			(pts
				(arc
					(start 169.706798 -227.271326)
					(mid 169.721677 -227.307247)
					(end 169.757598 -227.322126)
				)
				(arc
					(start 171.157138 -227.322126)
					(mid 171.193059 -227.307247)
					(end 171.207938 -227.271326)
				)
				(arc
					(start 171.207938 -226.862386)
					(mid 171.193059 -226.826465)
					(end 171.157138 -226.811586)
				)
				(arc
					(start 169.757598 -226.811586)
					(mid 169.721677 -226.826465)
					(end 169.706798 -226.862386)
				)
			)
		)
	)
	(zone
		(layers "In1.Cu" "In2.Cu")
		(hatch none 0.5)
		(connect_pads
			(clearance 0)
		)
		(min_thickness 0.25)
		(keepout
			(tracks not_allowed)
			(vias allowed)
			(pads allowed)
			(copperpour not_allowed)
			(footprints allowed)
		)
		(placement
			(enabled no)
			(sheetname "")
		)
		(fill yes
			(thermal_gap 0.5)
			(thermal_bridge_width 0.5)
			(island_removal_mode 0)
		)
		(polygon
			(pts
				(arc
					(start 162.162998 -201.771504)
					(mid 162.177877 -201.807425)
					(end 162.213798 -201.822304)
				)
				(arc
					(start 163.613338 -201.822304)
					(mid 163.649259 -201.807425)
					(end 163.664138 -201.771504)
				)
				(arc
					(start 163.664138 -201.362564)
					(mid 163.649259 -201.326643)
					(end 163.613338 -201.311764)
				)
				(arc
					(start 162.213798 -201.311764)
					(mid 162.177877 -201.326643)
					(end 162.162998 -201.362564)
				)
			)
		)
	)
	(zone
		(layers "In1.Cu" "In2.Cu")
		(hatch none 0.5)
		(connect_pads
			(clearance 0)
		)
		(min_thickness 0.25)
		(keepout
			(tracks not_allowed)
			(vias allowed)
			(pads allowed)
			(copperpour not_allowed)
			(footprints allowed)
		)
		(placement
			(enabled no)
			(sheetname "")
		)
		(fill yes
			(thermal_gap 0.5)
			(thermal_bridge_width 0.5)
			(island_removal_mode 0)
		)
		(polygon
			(pts
				(arc
					(start 270.417798 -293.571422)
					(mid 270.432677 -293.607343)
					(end 270.468598 -293.622222)
				)
				(arc
					(start 271.868138 -293.622222)
					(mid 271.904059 -293.607343)
					(end 271.918938 -293.571422)
				)
				(arc
					(start 271.918938 -293.162482)
					(mid 271.904059 -293.126561)
					(end 271.868138 -293.111682)
				)
				(arc
					(start 270.468598 -293.111682)
					(mid 270.432677 -293.126561)
					(end 270.417798 -293.162482)
				)
			)
		)
	)
	(zone
		(layers "In1.Cu" "In2.Cu")
		(hatch none 0.5)
		(connect_pads
			(clearance 0)
		)
		(min_thickness 0.25)
		(keepout
			(tracks not_allowed)
			(vias allowed)
			(pads allowed)
			(copperpour not_allowed)
			(footprints allowed)
		)
		(placement
			(enabled no)
			(sheetname "")
		)
		(fill yes
			(thermal_gap 0.5)
			(thermal_bridge_width 0.5)
			(island_removal_mode 0)
		)
		(polygon
			(pts
				(arc
					(start 289.605466 -231.521508)
					(mid 289.620345 -231.557429)
					(end 289.656266 -231.572308)
				)
				(arc
					(start 291.055806 -231.572308)
					(mid 291.091727 -231.557429)
					(end 291.106606 -231.521508)
				)
				(arc
					(start 291.106606 -231.112568)
					(mid 291.091727 -231.076647)
					(end 291.055806 -231.061768)
				)
				(arc
					(start 289.656266 -231.061768)
					(mid 289.620345 -231.076647)
					(end 289.605466 -231.112568)
				)
			)
		)
	)
	(zone
		(layers "In1.Cu" "In2.Cu")
		(hatch none 0.5)
		(connect_pads
			(clearance 0)
		)
		(min_thickness 0.25)
		(keepout
			(tracks not_allowed)
			(vias allowed)
			(pads allowed)
			(copperpour not_allowed)
			(footprints allowed)
		)
		(placement
			(enabled no)
			(sheetname "")
		)
		(fill yes
			(thermal_gap 0.5)
			(thermal_bridge_width 0.5)
			(island_removal_mode 0)
		)
		(polygon
			(pts
				(arc
					(start 199.881998 -222.171514)
					(mid 199.896877 -222.207435)
					(end 199.932798 -222.222314)
				)
				(arc
					(start 201.332338 -222.222314)
					(mid 201.368259 -222.207435)
					(end 201.383138 -222.171514)
				)
				(arc
					(start 201.383138 -221.762574)
					(mid 201.368259 -221.726653)
					(end 201.332338 -221.711774)
				)
				(arc
					(start 199.932798 -221.711774)
					(mid 199.896877 -221.726653)
					(end 199.881998 -221.762574)
				)
			)
		)
	)
	(zone
		(layers "In1.Cu" "In2.Cu")
		(hatch none 0.5)
		(connect_pads
			(clearance 0)
		)
		(min_thickness 0.25)
		(keepout
			(tracks not_allowed)
			(vias allowed)
			(pads allowed)
			(copperpour not_allowed)
			(footprints allowed)
		)
		(placement
			(enabled no)
			(sheetname "")
		)
		(fill yes
			(thermal_gap 0.5)
			(thermal_bridge_width 0.5)
			(island_removal_mode 0)
		)
		(polygon
			(pts
				(arc
					(start 41.665398 -287.621472)
					(mid 41.680277 -287.657393)
					(end 41.716198 -287.672272)
				)
				(arc
					(start 43.115738 -287.672272)
					(mid 43.151659 -287.657393)
					(end 43.166538 -287.621472)
				)
				(arc
					(start 43.166538 -287.212532)
					(mid 43.151659 -287.176611)
					(end 43.115738 -287.161732)
				)
				(arc
					(start 41.716198 -287.161732)
					(mid 41.680277 -287.176611)
					(end 41.665398 -287.212532)
				)
			)
		)
	)
	(zone
		(layers "In1.Cu" "In2.Cu")
		(hatch none 0.5)
		(connect_pads
			(clearance 0)
		)
		(min_thickness 0.25)
		(keepout
			(tracks not_allowed)
			(vias allowed)
			(pads allowed)
			(copperpour not_allowed)
			(footprints allowed)
		)
		(placement
			(enabled no)
			(sheetname "")
		)
		(fill yes
			(thermal_gap 0.5)
			(thermal_bridge_width 0.5)
			(island_removal_mode 0)
		)
		(polygon
			(pts
				(arc
					(start 41.665398 -237.471458)
					(mid 41.680277 -237.507379)
					(end 41.716198 -237.522258)
				)
				(arc
					(start 43.115738 -237.522258)
					(mid 43.151659 -237.507379)
					(end 43.166538 -237.471458)
				)
				(arc
					(start 43.166538 -237.062518)
					(mid 43.151659 -237.026597)
					(end 43.115738 -237.011718)
				)
				(arc
					(start 41.716198 -237.011718)
					(mid 41.680277 -237.026597)
					(end 41.665398 -237.062518)
				)
			)
		)
	)
	(zone
		(layers "In1.Cu" "In2.Cu")
		(hatch none 0.5)
		(connect_pads
			(clearance 0)
		)
		(min_thickness 0.25)
		(keepout
			(tracks not_allowed)
			(vias allowed)
			(pads allowed)
			(copperpour not_allowed)
			(footprints allowed)
		)
		(placement
			(enabled no)
			(sheetname "")
		)
		(fill yes
			(thermal_gap 0.5)
			(thermal_bridge_width 0.5)
			(island_removal_mode 0)
		)
		(polygon
			(pts
				(arc
					(start 443.721998 -307.171344)
					(mid 443.736877 -307.207265)
					(end 443.772798 -307.222144)
				)
				(arc
					(start 445.172338 -307.222144)
					(mid 445.208259 -307.207265)
					(end 445.223138 -307.171344)
				)
				(arc
					(start 445.223138 -306.762404)
					(mid 445.208259 -306.726483)
					(end 445.172338 -306.711604)
				)
				(arc
					(start 443.772798 -306.711604)
					(mid 443.736877 -306.726483)
					(end 443.721998 -306.762404)
				)
			)
		)
	)
	(zone
		(layers "In1.Cu" "In2.Cu")
		(hatch none 0.5)
		(connect_pads
			(clearance 0)
		)
		(min_thickness 0.25)
		(keepout
			(tracks not_allowed)
			(vias allowed)
			(pads allowed)
			(copperpour not_allowed)
			(footprints allowed)
		)
		(placement
			(enabled no)
			(sheetname "")
		)
		(fill yes
			(thermal_gap 0.5)
			(thermal_bridge_width 0.5)
			(island_removal_mode 0)
		)
		(polygon
			(pts
				(arc
					(start 297.149266 -284.221428)
					(mid 297.164145 -284.257349)
					(end 297.200066 -284.272228)
				)
				(arc
					(start 298.599606 -284.272228)
					(mid 298.635527 -284.257349)
					(end 298.650406 -284.221428)
				)
				(arc
					(start 298.650406 -283.812488)
					(mid 298.635527 -283.776567)
					(end 298.599606 -283.761688)
				)
				(arc
					(start 297.200066 -283.761688)
					(mid 297.164145 -283.776567)
					(end 297.149266 -283.812488)
				)
			)
		)
	)
	(zone
		(layers "In1.Cu" "In2.Cu")
		(hatch none 0.5)
		(connect_pads
			(clearance 0)
		)
		(min_thickness 0.25)
		(keepout
			(tracks not_allowed)
			(vias allowed)
			(pads allowed)
			(copperpour not_allowed)
			(footprints allowed)
		)
		(placement
			(enabled no)
			(sheetname "")
		)
		(fill yes
			(thermal_gap 0.5)
			(thermal_bridge_width 0.5)
			(island_removal_mode 0)
		)
		(polygon
			(pts
				(arc
					(start 26.577798 -304.621438)
					(mid 26.592677 -304.657359)
					(end 26.628598 -304.672238)
				)
				(arc
					(start 28.028138 -304.672238)
					(mid 28.064059 -304.657359)
					(end 28.078938 -304.621438)
				)
				(arc
					(start 28.078938 -304.212498)
					(mid 28.064059 -304.176577)
					(end 28.028138 -304.161698)
				)
				(arc
					(start 26.628598 -304.161698)
					(mid 26.592677 -304.176577)
					(end 26.577798 -304.212498)
				)
			)
		)
	)
	(zone
		(layers "In1.Cu" "In2.Cu")
		(hatch none 0.5)
		(connect_pads
			(clearance 0)
		)
		(min_thickness 0.25)
		(keepout
			(tracks not_allowed)
			(vias allowed)
			(pads allowed)
			(copperpour not_allowed)
			(footprints allowed)
		)
		(placement
			(enabled no)
			(sheetname "")
		)
		(fill yes
			(thermal_gap 0.5)
			(thermal_bridge_width 0.5)
			(island_removal_mode 0)
		)
		(polygon
			(pts
				(arc
					(start 180.69433 -262.971534)
					(mid 180.709209 -263.007455)
					(end 180.74513 -263.022334)
				)
				(arc
					(start 182.14467 -263.022334)
					(mid 182.180591 -263.007455)
					(end 182.19547 -262.971534)
				)
				(arc
					(start 182.19547 -262.562594)
					(mid 182.180591 -262.526673)
					(end 182.14467 -262.511794)
				)
				(arc
					(start 180.74513 -262.511794)
					(mid 180.709209 -262.526673)
					(end 180.69433 -262.562594)
				)
			)
		)
	)
	(zone
		(layers "In1.Cu" "In2.Cu")
		(hatch none 0.5)
		(connect_pads
			(clearance 0)
		)
		(min_thickness 0.25)
		(keepout
			(tracks not_allowed)
			(vias allowed)
			(pads allowed)
			(copperpour not_allowed)
			(footprints allowed)
		)
		(placement
			(enabled no)
			(sheetname "")
		)
		(fill yes
			(thermal_gap 0.5)
			(thermal_bridge_width 0.5)
			(island_removal_mode 0)
		)
		(polygon
			(pts
				(arc
					(start 282.061666 -251.921518)
					(mid 282.076545 -251.957439)
					(end 282.112466 -251.972318)
				)
				(arc
					(start 283.512006 -251.972318)
					(mid 283.547927 -251.957439)
					(end 283.562806 -251.921518)
				)
				(arc
					(start 283.562806 -251.512578)
					(mid 283.547927 -251.476657)
					(end 283.512006 -251.461778)
				)
				(arc
					(start 282.112466 -251.461778)
					(mid 282.076545 -251.476657)
					(end 282.061666 -251.512578)
				)
			)
		)
	)
	(zone
		(layers "In1.Cu" "In2.Cu")
		(hatch none 0.5)
		(connect_pads
			(clearance 0)
		)
		(min_thickness 0.25)
		(keepout
			(tracks not_allowed)
			(vias allowed)
			(pads allowed)
			(copperpour not_allowed)
			(footprints allowed)
		)
		(placement
			(enabled no)
			(sheetname "")
		)
		(fill yes
			(thermal_gap 0.5)
			(thermal_bridge_width 0.5)
			(island_removal_mode 0)
		)
		(polygon
			(pts
				(arc
					(start 436.178198 -204.32141)
					(mid 436.193077 -204.357331)
					(end 436.228998 -204.37221)
				)
				(arc
					(start 437.628538 -204.37221)
					(mid 437.664459 -204.357331)
					(end 437.679338 -204.32141)
				)
				(arc
					(start 437.679338 -203.91247)
					(mid 437.664459 -203.876549)
					(end 437.628538 -203.86167)
				)
				(arc
					(start 436.228998 -203.86167)
					(mid 436.193077 -203.876549)
					(end 436.178198 -203.91247)
				)
			)
		)
	)
	(zone
		(layers "In1.Cu" "In2.Cu")
		(hatch none 0.5)
		(connect_pads
			(clearance 0)
		)
		(min_thickness 0.25)
		(keepout
			(tracks not_allowed)
			(vias allowed)
			(pads allowed)
			(copperpour not_allowed)
			(footprints allowed)
		)
		(placement
			(enabled no)
			(sheetname "")
		)
		(fill yes
			(thermal_gap 0.5)
			(thermal_bridge_width 0.5)
			(island_removal_mode 0)
		)
		(polygon
			(pts
				(arc
					(start 7.39013 -224.72142)
					(mid 7.405009 -224.757341)
					(end 7.44093 -224.77222)
				)
				(arc
					(start 8.84047 -224.77222)
					(mid 8.876391 -224.757341)
					(end 8.89127 -224.72142)
				)
				(arc
					(start 8.89127 -224.31248)
					(mid 8.876391 -224.276559)
					(end 8.84047 -224.26168)
				)
				(arc
					(start 7.44093 -224.26168)
					(mid 7.405009 -224.276559)
					(end 7.39013 -224.31248)
				)
			)
		)
	)
	(zone
		(layers "In1.Cu" "In2.Cu")
		(hatch none 0.5)
		(connect_pads
			(clearance 0)
		)
		(min_thickness 0.25)
		(keepout
			(tracks not_allowed)
			(vias allowed)
			(pads allowed)
			(copperpour not_allowed)
			(footprints allowed)
		)
		(placement
			(enabled no)
			(sheetname "")
		)
		(fill yes
			(thermal_gap 0.5)
			(thermal_bridge_width 0.5)
			(island_removal_mode 0)
		)
		(polygon
			(pts
				(arc
					(start 282.061666 -309.721504)
					(mid 282.076545 -309.757425)
					(end 282.112466 -309.772304)
				)
				(arc
					(start 283.512006 -309.772304)
					(mid 283.547927 -309.757425)
					(end 283.562806 -309.721504)
				)
				(arc
					(start 283.562806 -309.312564)
					(mid 283.547927 -309.276643)
					(end 283.512006 -309.261764)
				)
				(arc
					(start 282.112466 -309.261764)
					(mid 282.076545 -309.276643)
					(end 282.061666 -309.312564)
				)
			)
		)
	)
	(zone
		(layers "In1.Cu" "In2.Cu")
		(hatch none 0.5)
		(connect_pads
			(clearance 0)
		)
		(min_thickness 0.25)
		(keepout
			(tracks not_allowed)
			(vias allowed)
			(pads allowed)
			(copperpour not_allowed)
			(footprints allowed)
		)
		(placement
			(enabled no)
			(sheetname "")
		)
		(fill yes
			(thermal_gap 0.5)
			(thermal_bridge_width 0.5)
			(island_removal_mode 0)
		)
		(polygon
			(pts
				(arc
					(start 266.974066 -263.821418)
					(mid 266.988945 -263.857339)
					(end 267.024866 -263.872218)
				)
				(arc
					(start 268.424406 -263.872218)
					(mid 268.460327 -263.857339)
					(end 268.475206 -263.821418)
				)
				(arc
					(start 268.475206 -263.412478)
					(mid 268.460327 -263.376557)
					(end 268.424406 -263.361678)
				)
				(arc
					(start 267.024866 -263.361678)
					(mid 266.988945 -263.376557)
					(end 266.974066 -263.412478)
				)
			)
		)
	)
	(zone
		(layers "In1.Cu" "In2.Cu")
		(hatch none 0.5)
		(connect_pads
			(clearance 0)
		)
		(min_thickness 0.25)
		(keepout
			(tracks not_allowed)
			(vias allowed)
			(pads allowed)
			(copperpour not_allowed)
			(footprints allowed)
		)
		(placement
			(enabled no)
			(sheetname "")
		)
		(fill yes
			(thermal_gap 0.5)
			(thermal_bridge_width 0.5)
			(island_removal_mode 0)
		)
		(polygon
			(pts
				(arc
					(start 173.15053 -290.171378)
					(mid 173.165409 -290.207299)
					(end 173.20133 -290.222178)
				)
				(arc
					(start 174.60087 -290.222178)
					(mid 174.636791 -290.207299)
					(end 174.65167 -290.171378)
				)
				(arc
					(start 174.65167 -289.762438)
					(mid 174.636791 -289.726517)
					(end 174.60087 -289.711638)
				)
				(arc
					(start 173.20133 -289.711638)
					(mid 173.165409 -289.726517)
					(end 173.15053 -289.762438)
				)
			)
		)
	)
	(zone
		(layers "In1.Cu" "In2.Cu")
		(hatch none 0.5)
		(connect_pads
			(clearance 0)
		)
		(min_thickness 0.25)
		(keepout
			(tracks not_allowed)
			(vias allowed)
			(pads allowed)
			(copperpour not_allowed)
			(footprints allowed)
		)
		(placement
			(enabled no)
			(sheetname "")
		)
		(fill yes
			(thermal_gap 0.5)
			(thermal_bridge_width 0.5)
			(island_removal_mode 0)
		)
		(polygon
			(pts
				(arc
					(start 49.209198 -281.671522)
					(mid 49.224077 -281.707443)
					(end 49.259998 -281.722322)
				)
				(arc
					(start 50.659538 -281.722322)
					(mid 50.695459 -281.707443)
					(end 50.710338 -281.671522)
				)
				(arc
					(start 50.710338 -281.262582)
					(mid 50.695459 -281.226661)
					(end 50.659538 -281.211782)
				)
				(arc
					(start 49.259998 -281.211782)
					(mid 49.224077 -281.226661)
					(end 49.209198 -281.262582)
				)
			)
		)
	)
	(zone
		(layers "In1.Cu" "In2.Cu")
		(hatch none 0.5)
		(connect_pads
			(clearance 0)
		)
		(min_thickness 0.25)
		(keepout
			(tracks not_allowed)
			(vias allowed)
			(pads allowed)
			(copperpour not_allowed)
			(footprints allowed)
		)
		(placement
			(enabled no)
			(sheetname "")
		)
		(fill yes
			(thermal_gap 0.5)
			(thermal_bridge_width 0.5)
			(island_removal_mode 0)
		)
		(polygon
			(pts
				(arc
					(start 11.490198 -292.721538)
					(mid 11.505077 -292.757459)
					(end 11.540998 -292.772338)
				)
				(arc
					(start 12.940538 -292.772338)
					(mid 12.976459 -292.757459)
					(end 12.991338 -292.721538)
				)
				(arc
					(start 12.991338 -292.312598)
					(mid 12.976459 -292.276677)
					(end 12.940538 -292.261798)
				)
				(arc
					(start 11.540998 -292.261798)
					(mid 11.505077 -292.276677)
					(end 11.490198 -292.312598)
				)
			)
		)
	)
	(zone
		(layers "In1.Cu" "In2.Cu")
		(hatch none 0.5)
		(connect_pads
			(clearance 0)
		)
		(min_thickness 0.25)
		(keepout
			(tracks not_allowed)
			(vias allowed)
			(pads allowed)
			(copperpour not_allowed)
			(footprints allowed)
		)
		(placement
			(enabled no)
			(sheetname "")
		)
		(fill yes
			(thermal_gap 0.5)
			(thermal_bridge_width 0.5)
			(island_removal_mode 0)
		)
		(polygon
			(pts
				(arc
					(start 462.909666 -315.671454)
					(mid 462.924545 -315.707375)
					(end 462.960466 -315.722254)
				)
				(arc
					(start 464.360006 -315.722254)
					(mid 464.395927 -315.707375)
					(end 464.410806 -315.671454)
				)
				(arc
					(start 464.410806 -315.262514)
					(mid 464.395927 -315.226593)
					(end 464.360006 -315.211714)
				)
				(arc
					(start 462.960466 -315.211714)
					(mid 462.924545 -315.226593)
					(end 462.909666 -315.262514)
				)
			)
		)
	)
	(zone
		(layers "In1.Cu" "In2.Cu")
		(hatch none 0.5)
		(connect_pads
			(clearance 0)
		)
		(min_thickness 0.25)
		(keepout
			(tracks not_allowed)
			(vias allowed)
			(pads allowed)
			(copperpour not_allowed)
			(footprints allowed)
		)
		(placement
			(enabled no)
			(sheetname "")
		)
		(fill yes
			(thermal_gap 0.5)
			(thermal_bridge_width 0.5)
			(island_removal_mode 0)
		)
		(polygon
			(pts
				(arc
					(start 14.93393 -279.121362)
					(mid 14.948809 -279.157283)
					(end 14.98473 -279.172162)
				)
				(arc
					(start 16.38427 -279.172162)
					(mid 16.420191 -279.157283)
					(end 16.43507 -279.121362)
				)
				(arc
					(start 16.43507 -278.712422)
					(mid 16.420191 -278.676501)
					(end 16.38427 -278.661622)
				)
				(arc
					(start 14.98473 -278.661622)
					(mid 14.948809 -278.676501)
					(end 14.93393 -278.712422)
				)
			)
		)
	)
	(zone
		(layers "In1.Cu" "In2.Cu")
		(hatch none 0.5)
		(connect_pads
			(clearance 0)
		)
		(min_thickness 0.25)
		(keepout
			(tracks not_allowed)
			(vias allowed)
			(pads allowed)
			(copperpour not_allowed)
			(footprints allowed)
		)
		(placement
			(enabled no)
			(sheetname "")
		)
		(fill yes
			(thermal_gap 0.5)
			(thermal_bridge_width 0.5)
			(island_removal_mode 0)
		)
		(polygon
			(pts
				(arc
					(start 49.209198 -296.971466)
					(mid 49.224077 -297.007387)
					(end 49.259998 -297.022266)
				)
				(arc
					(start 50.659538 -297.022266)
					(mid 50.695459 -297.007387)
					(end 50.710338 -296.971466)
				)
				(arc
					(start 50.710338 -296.562526)
					(mid 50.695459 -296.526605)
					(end 50.659538 -296.511726)
				)
				(arc
					(start 49.259998 -296.511726)
					(mid 49.224077 -296.526605)
					(end 49.209198 -296.562526)
				)
			)
		)
	)
	(zone
		(layers "In1.Cu" "In2.Cu")
		(hatch none 0.5)
		(connect_pads
			(clearance 0)
		)
		(min_thickness 0.25)
		(keepout
			(tracks not_allowed)
			(vias allowed)
			(pads allowed)
			(copperpour not_allowed)
			(footprints allowed)
		)
		(placement
			(enabled no)
			(sheetname "")
		)
		(fill yes
			(thermal_gap 0.5)
			(thermal_bridge_width 0.5)
			(island_removal_mode 0)
		)
		(polygon
			(pts
				(arc
					(start 443.721998 -198.37146)
					(mid 443.736877 -198.407381)
					(end 443.772798 -198.42226)
				)
				(arc
					(start 445.172338 -198.42226)
					(mid 445.208259 -198.407381)
					(end 445.223138 -198.37146)
				)
				(arc
					(start 445.223138 -197.96252)
					(mid 445.208259 -197.926599)
					(end 445.172338 -197.91172)
				)
				(arc
					(start 443.772798 -197.91172)
					(mid 443.736877 -197.926599)
					(end 443.721998 -197.96252)
				)
			)
		)
	)
	(zone
		(layers "In1.Cu" "In2.Cu")
		(hatch none 0.5)
		(connect_pads
			(clearance 0)
		)
		(min_thickness 0.25)
		(keepout
			(tracks not_allowed)
			(vias allowed)
			(pads allowed)
			(copperpour not_allowed)
			(footprints allowed)
		)
		(placement
			(enabled no)
			(sheetname "")
		)
		(fill yes
			(thermal_gap 0.5)
			(thermal_bridge_width 0.5)
			(island_removal_mode 0)
		)
		(polygon
			(pts
				(arc
					(start 30.02153 -284.221428)
					(mid 30.036409 -284.257349)
					(end 30.07233 -284.272228)
				)
				(arc
					(start 31.47187 -284.272228)
					(mid 31.507791 -284.257349)
					(end 31.52267 -284.221428)
				)
				(arc
					(start 31.52267 -283.812488)
					(mid 31.507791 -283.776567)
					(end 31.47187 -283.761688)
				)
				(arc
					(start 30.07233 -283.761688)
					(mid 30.036409 -283.776567)
					(end 30.02153 -283.812488)
				)
			)
		)
	)
	(zone
		(layers "In1.Cu" "In2.Cu")
		(hatch none 0.5)
		(connect_pads
			(clearance 0)
		)
		(min_thickness 0.25)
		(keepout
			(tracks not_allowed)
			(vias allowed)
			(pads allowed)
			(copperpour not_allowed)
			(footprints allowed)
		)
		(placement
			(enabled no)
			(sheetname "")
		)
		(fill yes
			(thermal_gap 0.5)
			(thermal_bridge_width 0.5)
			(island_removal_mode 0)
		)
		(polygon
			(pts
				(arc
					(start 304.693066 -296.971466)
					(mid 304.707945 -297.007387)
					(end 304.743866 -297.022266)
				)
				(arc
					(start 306.143406 -297.022266)
					(mid 306.179327 -297.007387)
					(end 306.194206 -296.971466)
				)
				(arc
					(start 306.194206 -296.562526)
					(mid 306.179327 -296.526605)
					(end 306.143406 -296.511726)
				)
				(arc
					(start 304.743866 -296.511726)
					(mid 304.707945 -296.526605)
					(end 304.693066 -296.562526)
				)
			)
		)
	)
	(zone
		(layers "In1.Cu" "In2.Cu")
		(hatch none 0.5)
		(connect_pads
			(clearance 0)
		)
		(min_thickness 0.25)
		(keepout
			(tracks not_allowed)
			(vias allowed)
			(pads allowed)
			(copperpour not_allowed)
			(footprints allowed)
		)
		(placement
			(enabled no)
			(sheetname "")
		)
		(fill yes
			(thermal_gap 0.5)
			(thermal_bridge_width 0.5)
			(island_removal_mode 0)
		)
		(polygon
			(pts
				(arc
					(start 436.178198 -279.121362)
					(mid 436.193077 -279.157283)
					(end 436.228998 -279.172162)
				)
				(arc
					(start 437.628538 -279.172162)
					(mid 437.664459 -279.157283)
					(end 437.679338 -279.121362)
				)
				(arc
					(start 437.679338 -278.712422)
					(mid 437.664459 -278.676501)
					(end 437.628538 -278.661622)
				)
				(arc
					(start 436.228998 -278.661622)
					(mid 436.193077 -278.676501)
					(end 436.178198 -278.712422)
				)
			)
		)
	)
	(zone
		(layers "In1.Cu" "In2.Cu")
		(hatch none 0.5)
		(connect_pads
			(clearance 0)
		)
		(min_thickness 0.25)
		(keepout
			(tracks not_allowed)
			(vias allowed)
			(pads allowed)
			(copperpour not_allowed)
			(footprints allowed)
		)
		(placement
			(enabled no)
			(sheetname "")
		)
		(fill yes
			(thermal_gap 0.5)
			(thermal_bridge_width 0.5)
			(island_removal_mode 0)
		)
		(polygon
			(pts
				(arc
					(start 270.417798 -217.071448)
					(mid 270.432677 -217.107369)
					(end 270.468598 -217.122248)
				)
				(arc
					(start 271.868138 -217.122248)
					(mid 271.904059 -217.107369)
					(end 271.918938 -217.071448)
				)
				(arc
					(start 271.918938 -216.662508)
					(mid 271.904059 -216.626587)
					(end 271.868138 -216.611708)
				)
				(arc
					(start 270.468598 -216.611708)
					(mid 270.432677 -216.626587)
					(end 270.417798 -216.662508)
				)
			)
		)
	)
	(zone
		(layers "In1.Cu" "In2.Cu")
		(hatch none 0.5)
		(connect_pads
			(clearance 0)
		)
		(min_thickness 0.25)
		(keepout
			(tracks not_allowed)
			(vias allowed)
			(pads allowed)
			(copperpour not_allowed)
			(footprints allowed)
		)
		(placement
			(enabled no)
			(sheetname "")
		)
		(fill yes
			(thermal_gap 0.5)
			(thermal_bridge_width 0.5)
			(island_removal_mode 0)
		)
		(polygon
			(pts
				(arc
					(start 447.822066 -260.421374)
					(mid 447.836945 -260.457295)
					(end 447.872866 -260.472174)
				)
				(arc
					(start 449.272406 -260.472174)
					(mid 449.308327 -260.457295)
					(end 449.323206 -260.421374)
				)
				(arc
					(start 449.323206 -260.012434)
					(mid 449.308327 -259.976513)
					(end 449.272406 -259.961634)
				)
				(arc
					(start 447.872866 -259.961634)
					(mid 447.836945 -259.976513)
					(end 447.822066 -260.012434)
				)
			)
		)
	)
	(zone
		(layers "In1.Cu" "In2.Cu")
		(hatch none 0.5)
		(connect_pads
			(clearance 0)
		)
		(min_thickness 0.25)
		(keepout
			(tracks not_allowed)
			(vias allowed)
			(pads allowed)
			(copperpour not_allowed)
			(footprints allowed)
		)
		(placement
			(enabled no)
			(sheetname "")
		)
		(fill yes
			(thermal_gap 0.5)
			(thermal_bridge_width 0.5)
			(island_removal_mode 0)
		)
		(polygon
			(pts
				(arc
					(start 19.033998 -295.271444)
					(mid 19.048877 -295.307365)
					(end 19.084798 -295.322244)
				)
				(arc
					(start 20.484338 -295.322244)
					(mid 20.520259 -295.307365)
					(end 20.535138 -295.271444)
				)
				(arc
					(start 20.535138 -294.862504)
					(mid 20.520259 -294.826583)
					(end 20.484338 -294.811704)
				)
				(arc
					(start 19.084798 -294.811704)
					(mid 19.048877 -294.826583)
					(end 19.033998 -294.862504)
				)
			)
		)
	)
	(zone
		(layers "In1.Cu" "In2.Cu")
		(hatch none 0.5)
		(connect_pads
			(clearance 0)
		)
		(min_thickness 0.25)
		(keepout
			(tracks not_allowed)
			(vias allowed)
			(pads allowed)
			(copperpour not_allowed)
			(footprints allowed)
		)
		(placement
			(enabled no)
			(sheetname "")
		)
		(fill yes
			(thermal_gap 0.5)
			(thermal_bridge_width 0.5)
			(island_removal_mode 0)
		)
		(polygon
			(pts
				(arc
					(start 7.39013 -277.42134)
					(mid 7.405009 -277.457261)
					(end 7.44093 -277.47214)
				)
				(arc
					(start 8.84047 -277.47214)
					(mid 8.876391 -277.457261)
					(end 8.89127 -277.42134)
				)
				(arc
					(start 8.89127 -277.0124)
					(mid 8.876391 -276.976479)
					(end 8.84047 -276.9616)
				)
				(arc
					(start 7.44093 -276.9616)
					(mid 7.405009 -276.976479)
					(end 7.39013 -277.0124)
				)
			)
		)
	)
	(zone
		(layers "In1.Cu" "In2.Cu")
		(hatch none 0.5)
		(connect_pads
			(clearance 0)
		)
		(min_thickness 0.25)
		(keepout
			(tracks not_allowed)
			(vias allowed)
			(pads allowed)
			(copperpour not_allowed)
			(footprints allowed)
		)
		(placement
			(enabled no)
			(sheetname "")
		)
		(fill yes
			(thermal_gap 0.5)
			(thermal_bridge_width 0.5)
			(island_removal_mode 0)
		)
		(polygon
			(pts
				(arc
					(start 451.265798 -251.07138)
					(mid 451.280677 -251.107301)
					(end 451.316598 -251.12218)
				)
				(arc
					(start 452.716138 -251.12218)
					(mid 452.752059 -251.107301)
					(end 452.766938 -251.07138)
				)
				(arc
					(start 452.766938 -250.66244)
					(mid 452.752059 -250.626519)
					(end 452.716138 -250.61164)
				)
				(arc
					(start 451.316598 -250.61164)
					(mid 451.280677 -250.626519)
					(end 451.265798 -250.66244)
				)
			)
		)
	)
	(zone
		(layers "In1.Cu" "In2.Cu")
		(hatch none 0.5)
		(connect_pads
			(clearance 0)
		)
		(min_thickness 0.25)
		(keepout
			(tracks not_allowed)
			(vias allowed)
			(pads allowed)
			(copperpour not_allowed)
			(footprints allowed)
		)
		(placement
			(enabled no)
			(sheetname "")
		)
		(fill yes
			(thermal_gap 0.5)
			(thermal_bridge_width 0.5)
			(island_removal_mode 0)
		)
		(polygon
			(pts
				(arc
					(start 432.734466 -203.471526)
					(mid 432.749345 -203.507447)
					(end 432.785266 -203.522326)
				)
				(arc
					(start 434.184806 -203.522326)
					(mid 434.220727 -203.507447)
					(end 434.235606 -203.471526)
				)
				(arc
					(start 434.235606 -203.062586)
					(mid 434.220727 -203.026665)
					(end 434.184806 -203.011786)
				)
				(arc
					(start 432.785266 -203.011786)
					(mid 432.749345 -203.026665)
					(end 432.734466 -203.062586)
				)
			)
		)
	)
	(zone
		(layers "In1.Cu" "In2.Cu")
		(hatch none 0.5)
		(connect_pads
			(clearance 0)
		)
		(min_thickness 0.25)
		(keepout
			(tracks not_allowed)
			(vias allowed)
			(pads allowed)
			(copperpour not_allowed)
			(footprints allowed)
		)
		(placement
			(enabled no)
			(sheetname "")
		)
		(fill yes
			(thermal_gap 0.5)
			(thermal_bridge_width 0.5)
			(island_removal_mode 0)
		)
		(polygon
			(pts
				(arc
					(start 22.47773 -279.121362)
					(mid 22.492609 -279.157283)
					(end 22.52853 -279.172162)
				)
				(arc
					(start 23.92807 -279.172162)
					(mid 23.963991 -279.157283)
					(end 23.97887 -279.121362)
				)
				(arc
					(start 23.97887 -278.712422)
					(mid 23.963991 -278.676501)
					(end 23.92807 -278.661622)
				)
				(arc
					(start 22.52853 -278.661622)
					(mid 22.492609 -278.676501)
					(end 22.47773 -278.712422)
				)
			)
		)
	)
	(zone
		(layers "In1.Cu" "In2.Cu")
		(hatch none 0.5)
		(connect_pads
			(clearance 0)
		)
		(min_thickness 0.25)
		(keepout
			(tracks not_allowed)
			(vias allowed)
			(pads allowed)
			(copperpour not_allowed)
			(footprints allowed)
		)
		(placement
			(enabled no)
			(sheetname "")
		)
		(fill yes
			(thermal_gap 0.5)
			(thermal_bridge_width 0.5)
			(island_removal_mode 0)
		)
		(polygon
			(pts
				(arc
					(start 410.103066 -300.37151)
					(mid 410.117945 -300.407431)
					(end 410.153866 -300.42231)
				)
				(arc
					(start 411.553406 -300.42231)
					(mid 411.589327 -300.407431)
					(end 411.604206 -300.37151)
				)
				(arc
					(start 411.604206 -299.96257)
					(mid 411.589327 -299.926649)
					(end 411.553406 -299.91177)
				)
				(arc
					(start 410.153866 -299.91177)
					(mid 410.117945 -299.926649)
					(end 410.103066 -299.96257)
				)
			)
		)
	)
	(zone
		(layers "In1.Cu" "In2.Cu")
		(hatch none 0.5)
		(connect_pads
			(clearance 0)
		)
		(min_thickness 0.25)
		(keepout
			(tracks not_allowed)
			(vias allowed)
			(pads allowed)
			(copperpour not_allowed)
			(footprints allowed)
		)
		(placement
			(enabled no)
			(sheetname "")
		)
		(fill yes
			(thermal_gap 0.5)
			(thermal_bridge_width 0.5)
			(island_removal_mode 0)
		)
		(polygon
			(pts
				(arc
					(start 214.969598 -208.571338)
					(mid 214.984477 -208.607259)
					(end 215.020398 -208.622138)
				)
				(arc
					(start 216.419938 -208.622138)
					(mid 216.455859 -208.607259)
					(end 216.470738 -208.571338)
				)
				(arc
					(start 216.470738 -208.162398)
					(mid 216.455859 -208.126477)
					(end 216.419938 -208.111598)
				)
				(arc
					(start 215.020398 -208.111598)
					(mid 214.984477 -208.126477)
					(end 214.969598 -208.162398)
				)
			)
		)
	)
	(zone
		(layers "In1.Cu" "In2.Cu")
		(hatch none 0.5)
		(connect_pads
			(clearance 0)
		)
		(min_thickness 0.25)
		(keepout
			(tracks not_allowed)
			(vias allowed)
			(pads allowed)
			(copperpour not_allowed)
			(footprints allowed)
		)
		(placement
			(enabled no)
			(sheetname "")
		)
		(fill yes
			(thermal_gap 0.5)
			(thermal_bridge_width 0.5)
			(island_removal_mode 0)
		)
		(polygon
			(pts
				(arc
					(start 210.86953 -282.521406)
					(mid 210.884409 -282.557327)
					(end 210.92033 -282.572206)
				)
				(arc
					(start 212.31987 -282.572206)
					(mid 212.355791 -282.557327)
					(end 212.37067 -282.521406)
				)
				(arc
					(start 212.37067 -282.112466)
					(mid 212.355791 -282.076545)
					(end 212.31987 -282.061666)
				)
				(arc
					(start 210.92033 -282.061666)
					(mid 210.884409 -282.076545)
					(end 210.86953 -282.112466)
				)
			)
		)
	)
	(zone
		(layers "In1.Cu" "In2.Cu")
		(hatch none 0.5)
		(connect_pads
			(clearance 0)
		)
		(min_thickness 0.25)
		(keepout
			(tracks not_allowed)
			(vias allowed)
			(pads allowed)
			(copperpour not_allowed)
			(footprints allowed)
		)
		(placement
			(enabled no)
			(sheetname "")
		)
		(fill yes
			(thermal_gap 0.5)
			(thermal_bridge_width 0.5)
			(island_removal_mode 0)
		)
		(polygon
			(pts
				(arc
					(start 49.209198 -300.37151)
					(mid 49.224077 -300.407431)
					(end 49.259998 -300.42231)
				)
				(arc
					(start 50.659538 -300.42231)
					(mid 50.695459 -300.407431)
					(end 50.710338 -300.37151)
				)
				(arc
					(start 50.710338 -299.96257)
					(mid 50.695459 -299.926649)
					(end 50.659538 -299.91177)
				)
				(arc
					(start 49.259998 -299.91177)
					(mid 49.224077 -299.926649)
					(end 49.209198 -299.96257)
				)
			)
		)
	)
	(zone
		(layers "In1.Cu" "In2.Cu")
		(hatch none 0.5)
		(connect_pads
			(clearance 0)
		)
		(min_thickness 0.25)
		(keepout
			(tracks not_allowed)
			(vias allowed)
			(pads allowed)
			(copperpour not_allowed)
			(footprints allowed)
		)
		(placement
			(enabled no)
			(sheetname "")
		)
		(fill yes
			(thermal_gap 0.5)
			(thermal_bridge_width 0.5)
			(island_removal_mode 0)
		)
		(polygon
			(pts
				(arc
					(start 214.969598 -195.821554)
					(mid 214.984477 -195.857475)
					(end 215.020398 -195.872354)
				)
				(arc
					(start 216.419938 -195.872354)
					(mid 216.455859 -195.857475)
					(end 216.470738 -195.821554)
				)
				(arc
					(start 216.470738 -195.412614)
					(mid 216.455859 -195.376693)
					(end 216.419938 -195.361814)
				)
				(arc
					(start 215.020398 -195.361814)
					(mid 214.984477 -195.376693)
					(end 214.969598 -195.412614)
				)
			)
		)
	)
	(zone
		(layers "In1.Cu" "In2.Cu")
		(hatch none 0.5)
		(connect_pads
			(clearance 0)
		)
		(min_thickness 0.25)
		(keepout
			(tracks not_allowed)
			(vias allowed)
			(pads allowed)
			(copperpour not_allowed)
			(footprints allowed)
		)
		(placement
			(enabled no)
			(sheetname "")
		)
		(fill yes
			(thermal_gap 0.5)
			(thermal_bridge_width 0.5)
			(island_removal_mode 0)
		)
		(polygon
			(pts
				(arc
					(start 312.236866 -195.821554)
					(mid 312.251745 -195.857475)
					(end 312.287666 -195.872354)
				)
				(arc
					(start 313.687206 -195.872354)
					(mid 313.723127 -195.857475)
					(end 313.738006 -195.821554)
				)
				(arc
					(start 313.738006 -195.412614)
					(mid 313.723127 -195.376693)
					(end 313.687206 -195.361814)
				)
				(arc
					(start 312.287666 -195.361814)
					(mid 312.251745 -195.376693)
					(end 312.236866 -195.412614)
				)
			)
		)
	)
	(zone
		(layers "In1.Cu" "In2.Cu")
		(hatch none 0.5)
		(connect_pads
			(clearance 0)
		)
		(min_thickness 0.25)
		(keepout
			(tracks not_allowed)
			(vias allowed)
			(pads allowed)
			(copperpour not_allowed)
			(footprints allowed)
		)
		(placement
			(enabled no)
			(sheetname "")
		)
		(fill yes
			(thermal_gap 0.5)
			(thermal_bridge_width 0.5)
			(island_removal_mode 0)
		)
		(polygon
			(pts
				(arc
					(start 462.909666 -228.121464)
					(mid 462.924545 -228.157385)
					(end 462.960466 -228.172264)
				)
				(arc
					(start 464.360006 -228.172264)
					(mid 464.395927 -228.157385)
					(end 464.410806 -228.121464)
				)
				(arc
					(start 464.410806 -227.712524)
					(mid 464.395927 -227.676603)
					(end 464.360006 -227.661724)
				)
				(arc
					(start 462.960466 -227.661724)
					(mid 462.924545 -227.676603)
					(end 462.909666 -227.712524)
				)
			)
		)
	)
	(zone
		(layers "In1.Cu" "In2.Cu")
		(hatch none 0.5)
		(connect_pads
			(clearance 0)
		)
		(min_thickness 0.25)
		(keepout
			(tracks not_allowed)
			(vias allowed)
			(pads allowed)
			(copperpour not_allowed)
			(footprints allowed)
		)
		(placement
			(enabled no)
			(sheetname "")
		)
		(fill yes
			(thermal_gap 0.5)
			(thermal_bridge_width 0.5)
			(island_removal_mode 0)
		)
		(polygon
			(pts
				(arc
					(start 447.822066 -201.771504)
					(mid 447.836945 -201.807425)
					(end 447.872866 -201.822304)
				)
				(arc
					(start 449.272406 -201.822304)
					(mid 449.308327 -201.807425)
					(end 449.323206 -201.771504)
				)
				(arc
					(start 449.323206 -201.362564)
					(mid 449.308327 -201.326643)
					(end 449.272406 -201.311764)
				)
				(arc
					(start 447.872866 -201.311764)
					(mid 447.836945 -201.326643)
					(end 447.822066 -201.362564)
				)
			)
		)
	)
	(zone
		(layers "In1.Cu" "In2.Cu")
		(hatch none 0.5)
		(connect_pads
			(clearance 0)
		)
		(min_thickness 0.25)
		(keepout
			(tracks not_allowed)
			(vias allowed)
			(pads allowed)
			(copperpour not_allowed)
			(footprints allowed)
		)
		(placement
			(enabled no)
			(sheetname "")
		)
		(fill yes
			(thermal_gap 0.5)
			(thermal_bridge_width 0.5)
			(island_removal_mode 0)
		)
		(polygon
			(pts
				(arc
					(start 282.061666 -217.921332)
					(mid 282.076545 -217.957253)
					(end 282.112466 -217.972132)
				)
				(arc
					(start 283.512006 -217.972132)
					(mid 283.547927 -217.957253)
					(end 283.562806 -217.921332)
				)
				(arc
					(start 283.562806 -217.512392)
					(mid 283.547927 -217.476471)
					(end 283.512006 -217.461592)
				)
				(arc
					(start 282.112466 -217.461592)
					(mid 282.076545 -217.476471)
					(end 282.061666 -217.512392)
				)
			)
		)
	)
	(zone
		(layers "In1.Cu" "In2.Cu")
		(hatch none 0.5)
		(connect_pads
			(clearance 0)
		)
		(min_thickness 0.25)
		(keepout
			(tracks not_allowed)
			(vias allowed)
			(pads allowed)
			(copperpour not_allowed)
			(footprints allowed)
		)
		(placement
			(enabled no)
			(sheetname "")
		)
		(fill yes
			(thermal_gap 0.5)
			(thermal_bridge_width 0.5)
			(island_removal_mode 0)
		)
		(polygon
			(pts
				(arc
					(start 195.78193 -302.921416)
					(mid 195.796809 -302.957337)
					(end 195.83273 -302.972216)
				)
				(arc
					(start 197.23227 -302.972216)
					(mid 197.268191 -302.957337)
					(end 197.28307 -302.921416)
				)
				(arc
					(start 197.28307 -302.512476)
					(mid 197.268191 -302.476555)
					(end 197.23227 -302.461676)
				)
				(arc
					(start 195.83273 -302.461676)
					(mid 195.796809 -302.476555)
					(end 195.78193 -302.512476)
				)
			)
		)
	)
	(zone
		(layers "In1.Cu" "In2.Cu")
		(hatch none 0.5)
		(connect_pads
			(clearance 0)
		)
		(min_thickness 0.25)
		(keepout
			(tracks not_allowed)
			(vias allowed)
			(pads allowed)
			(copperpour not_allowed)
			(footprints allowed)
		)
		(placement
			(enabled no)
			(sheetname "")
		)
		(fill yes
			(thermal_gap 0.5)
			(thermal_bridge_width 0.5)
			(island_removal_mode 0)
		)
		(polygon
			(pts
				(arc
					(start 462.909666 -201.771504)
					(mid 462.924545 -201.807425)
					(end 462.960466 -201.822304)
				)
				(arc
					(start 464.360006 -201.822304)
					(mid 464.395927 -201.807425)
					(end 464.410806 -201.771504)
				)
				(arc
					(start 464.410806 -201.362564)
					(mid 464.395927 -201.326643)
					(end 464.360006 -201.311764)
				)
				(arc
					(start 462.960466 -201.311764)
					(mid 462.924545 -201.326643)
					(end 462.909666 -201.362564)
				)
			)
		)
	)
	(zone
		(layers "In1.Cu" "In2.Cu")
		(hatch none 0.5)
		(connect_pads
			(clearance 0)
		)
		(min_thickness 0.25)
		(keepout
			(tracks not_allowed)
			(vias allowed)
			(pads allowed)
			(copperpour not_allowed)
			(footprints allowed)
		)
		(placement
			(enabled no)
			(sheetname "")
		)
		(fill yes
			(thermal_gap 0.5)
			(thermal_bridge_width 0.5)
			(island_removal_mode 0)
		)
		(polygon
			(pts
				(arc
					(start 165.60673 -314.821316)
					(mid 165.621609 -314.857237)
					(end 165.65753 -314.872116)
				)
				(arc
					(start 167.05707 -314.872116)
					(mid 167.092991 -314.857237)
					(end 167.10787 -314.821316)
				)
				(arc
					(start 167.10787 -314.412376)
					(mid 167.092991 -314.376455)
					(end 167.05707 -314.361576)
				)
				(arc
					(start 165.65753 -314.361576)
					(mid 165.621609 -314.376455)
					(end 165.60673 -314.412376)
				)
			)
		)
	)
	(zone
		(layers "In1.Cu" "In2.Cu")
		(hatch none 0.5)
		(connect_pads
			(clearance 0)
		)
		(min_thickness 0.25)
		(keepout
			(tracks not_allowed)
			(vias allowed)
			(pads allowed)
			(copperpour not_allowed)
			(footprints allowed)
		)
		(placement
			(enabled no)
			(sheetname "")
		)
		(fill yes
			(thermal_gap 0.5)
			(thermal_bridge_width 0.5)
			(island_removal_mode 0)
		)
		(polygon
			(pts
				(arc
					(start 410.103066 -302.071532)
					(mid 410.117945 -302.107453)
					(end 410.153866 -302.122332)
				)
				(arc
					(start 411.553406 -302.122332)
					(mid 411.589327 -302.107453)
					(end 411.604206 -302.071532)
				)
				(arc
					(start 411.604206 -301.662592)
					(mid 411.589327 -301.626671)
					(end 411.553406 -301.611792)
				)
				(arc
					(start 410.153866 -301.611792)
					(mid 410.117945 -301.626671)
					(end 410.103066 -301.662592)
				)
			)
		)
	)
	(zone
		(layers "In1.Cu" "In2.Cu")
		(hatch none 0.5)
		(connect_pads
			(clearance 0)
		)
		(min_thickness 0.25)
		(keepout
			(tracks not_allowed)
			(vias allowed)
			(pads allowed)
			(copperpour not_allowed)
			(footprints allowed)
		)
		(placement
			(enabled no)
			(sheetname "")
		)
		(fill yes
			(thermal_gap 0.5)
			(thermal_bridge_width 0.5)
			(island_removal_mode 0)
		)
		(polygon
			(pts
				(arc
					(start 308.136798 -282.521406)
					(mid 308.151677 -282.557327)
					(end 308.187598 -282.572206)
				)
				(arc
					(start 309.587138 -282.572206)
					(mid 309.623059 -282.557327)
					(end 309.637938 -282.521406)
				)
				(arc
					(start 309.637938 -282.112466)
					(mid 309.623059 -282.076545)
					(end 309.587138 -282.061666)
				)
				(arc
					(start 308.187598 -282.061666)
					(mid 308.151677 -282.076545)
					(end 308.136798 -282.112466)
				)
			)
		)
	)
	(zone
		(layers "In1.Cu" "In2.Cu")
		(hatch none 0.5)
		(connect_pads
			(clearance 0)
		)
		(min_thickness 0.25)
		(keepout
			(tracks not_allowed)
			(vias allowed)
			(pads allowed)
			(copperpour not_allowed)
			(footprints allowed)
		)
		(placement
			(enabled no)
			(sheetname "")
		)
		(fill yes
			(thermal_gap 0.5)
			(thermal_bridge_width 0.5)
			(island_removal_mode 0)
		)
		(polygon
			(pts
				(arc
					(start 14.93393 -228.971348)
					(mid 14.948809 -229.007269)
					(end 14.98473 -229.022148)
				)
				(arc
					(start 16.38427 -229.022148)
					(mid 16.420191 -229.007269)
					(end 16.43507 -228.971348)
				)
				(arc
					(start 16.43507 -228.562408)
					(mid 16.420191 -228.526487)
					(end 16.38427 -228.511608)
				)
				(arc
					(start 14.98473 -228.511608)
					(mid 14.948809 -228.526487)
					(end 14.93393 -228.562408)
				)
			)
		)
	)
	(zone
		(layers "In1.Cu" "In2.Cu")
		(hatch none 0.5)
		(connect_pads
			(clearance 0)
		)
		(min_thickness 0.25)
		(keepout
			(tracks not_allowed)
			(vias allowed)
			(pads allowed)
			(copperpour not_allowed)
			(footprints allowed)
		)
		(placement
			(enabled no)
			(sheetname "")
		)
		(fill yes
			(thermal_gap 0.5)
			(thermal_bridge_width 0.5)
			(island_removal_mode 0)
		)
		(polygon
			(pts
				(arc
					(start 49.209198 -195.821554)
					(mid 49.224077 -195.857475)
					(end 49.259998 -195.872354)
				)
				(arc
					(start 50.659538 -195.872354)
					(mid 50.695459 -195.857475)
					(end 50.710338 -195.821554)
				)
				(arc
					(start 50.710338 -195.412614)
					(mid 50.695459 -195.376693)
					(end 50.659538 -195.361814)
				)
				(arc
					(start 49.259998 -195.361814)
					(mid 49.224077 -195.376693)
					(end 49.209198 -195.412614)
				)
			)
		)
	)
	(zone
		(layers "In1.Cu" "In2.Cu")
		(hatch none 0.5)
		(connect_pads
			(clearance 0)
		)
		(min_thickness 0.25)
		(keepout
			(tracks not_allowed)
			(vias allowed)
			(pads allowed)
			(copperpour not_allowed)
			(footprints allowed)
		)
		(placement
			(enabled no)
			(sheetname "")
		)
		(fill yes
			(thermal_gap 0.5)
			(thermal_bridge_width 0.5)
			(island_removal_mode 0)
		)
		(polygon
			(pts
				(arc
					(start 180.69433 -312.27141)
					(mid 180.709209 -312.307331)
					(end 180.74513 -312.32221)
				)
				(arc
					(start 182.14467 -312.32221)
					(mid 182.180591 -312.307331)
					(end 182.19547 -312.27141)
				)
				(arc
					(start 182.19547 -311.86247)
					(mid 182.180591 -311.826549)
					(end 182.14467 -311.81167)
				)
				(arc
					(start 180.74513 -311.81167)
					(mid 180.709209 -311.826549)
					(end 180.69433 -311.86247)
				)
			)
		)
	)
	(zone
		(layers "In1.Cu" "In2.Cu")
		(hatch none 0.5)
		(connect_pads
			(clearance 0)
		)
		(min_thickness 0.25)
		(keepout
			(tracks not_allowed)
			(vias allowed)
			(pads allowed)
			(copperpour not_allowed)
			(footprints allowed)
		)
		(placement
			(enabled no)
			(sheetname "")
		)
		(fill yes
			(thermal_gap 0.5)
			(thermal_bridge_width 0.5)
			(island_removal_mode 0)
		)
		(polygon
			(pts
				(arc
					(start 410.103066 -311.421526)
					(mid 410.117945 -311.457447)
					(end 410.153866 -311.472326)
				)
				(arc
					(start 411.553406 -311.472326)
					(mid 411.589327 -311.457447)
					(end 411.604206 -311.421526)
				)
				(arc
					(start 411.604206 -311.012586)
					(mid 411.589327 -310.976665)
					(end 411.553406 -310.961786)
				)
				(arc
					(start 410.153866 -310.961786)
					(mid 410.117945 -310.976665)
					(end 410.103066 -311.012586)
				)
			)
		)
	)
	(zone
		(layers "In1.Cu" "In2.Cu")
		(hatch none 0.5)
		(connect_pads
			(clearance 0)
		)
		(min_thickness 0.25)
		(keepout
			(tracks not_allowed)
			(vias allowed)
			(pads allowed)
			(copperpour not_allowed)
			(footprints allowed)
		)
		(placement
			(enabled no)
			(sheetname "")
		)
		(fill yes
			(thermal_gap 0.5)
			(thermal_bridge_width 0.5)
			(island_removal_mode 0)
		)
		(polygon
			(pts
				(arc
					(start 192.338198 -250.221496)
					(mid 192.353077 -250.257417)
					(end 192.388998 -250.272296)
				)
				(arc
					(start 193.788538 -250.272296)
					(mid 193.824459 -250.257417)
					(end 193.839338 -250.221496)
				)
				(arc
					(start 193.839338 -249.812556)
					(mid 193.824459 -249.776635)
					(end 193.788538 -249.761756)
				)
				(arc
					(start 192.388998 -249.761756)
					(mid 192.353077 -249.776635)
					(end 192.338198 -249.812556)
				)
			)
		)
	)
	(zone
		(layers "In1.Cu" "In2.Cu")
		(hatch none 0.5)
		(connect_pads
			(clearance 0)
		)
		(min_thickness 0.25)
		(keepout
			(tracks not_allowed)
			(vias allowed)
			(pads allowed)
			(copperpour not_allowed)
			(footprints allowed)
		)
		(placement
			(enabled no)
			(sheetname "")
		)
		(fill yes
			(thermal_gap 0.5)
			(thermal_bridge_width 0.5)
			(island_removal_mode 0)
		)
		(polygon
			(pts
				(arc
					(start 255.330198 -290.171378)
					(mid 255.345077 -290.207299)
					(end 255.380998 -290.222178)
				)
				(arc
					(start 256.780538 -290.222178)
					(mid 256.816459 -290.207299)
					(end 256.831338 -290.171378)
				)
				(arc
					(start 256.831338 -289.762438)
					(mid 256.816459 -289.726517)
					(end 256.780538 -289.711638)
				)
				(arc
					(start 255.380998 -289.711638)
					(mid 255.345077 -289.726517)
					(end 255.330198 -289.762438)
				)
			)
		)
	)
	(zone
		(layers "In1.Cu" "In2.Cu")
		(hatch none 0.5)
		(connect_pads
			(clearance 0)
		)
		(min_thickness 0.25)
		(keepout
			(tracks not_allowed)
			(vias allowed)
			(pads allowed)
			(copperpour not_allowed)
			(footprints allowed)
		)
		(placement
			(enabled no)
			(sheetname "")
		)
		(fill yes
			(thermal_gap 0.5)
			(thermal_bridge_width 0.5)
			(island_removal_mode 0)
		)
		(polygon
			(pts
				(arc
					(start 49.209198 -292.721538)
					(mid 49.224077 -292.757459)
					(end 49.259998 -292.772338)
				)
				(arc
					(start 50.659538 -292.772338)
					(mid 50.695459 -292.757459)
					(end 50.710338 -292.721538)
				)
				(arc
					(start 50.710338 -292.312598)
					(mid 50.695459 -292.276677)
					(end 50.659538 -292.261798)
				)
				(arc
					(start 49.259998 -292.261798)
					(mid 49.224077 -292.276677)
					(end 49.209198 -292.312598)
				)
			)
		)
	)
	(zone
		(layers "In1.Cu" "In2.Cu")
		(hatch none 0.5)
		(connect_pads
			(clearance 0)
		)
		(min_thickness 0.25)
		(keepout
			(tracks not_allowed)
			(vias allowed)
			(pads allowed)
			(copperpour not_allowed)
			(footprints allowed)
		)
		(placement
			(enabled no)
			(sheetname "")
		)
		(fill yes
			(thermal_gap 0.5)
			(thermal_bridge_width 0.5)
			(island_removal_mode 0)
		)
		(polygon
			(pts
				(arc
					(start 462.909666 -209.421476)
					(mid 462.924545 -209.457397)
					(end 462.960466 -209.472276)
				)
				(arc
					(start 464.360006 -209.472276)
					(mid 464.395927 -209.457397)
					(end 464.410806 -209.421476)
				)
				(arc
					(start 464.410806 -209.012536)
					(mid 464.395927 -208.976615)
					(end 464.360006 -208.961736)
				)
				(arc
					(start 462.960466 -208.961736)
					(mid 462.924545 -208.976615)
					(end 462.909666 -209.012536)
				)
			)
		)
	)
	(zone
		(layers "In1.Cu" "In2.Cu")
		(hatch none 0.5)
		(connect_pads
			(clearance 0)
		)
		(min_thickness 0.25)
		(keepout
			(tracks not_allowed)
			(vias allowed)
			(pads allowed)
			(copperpour not_allowed)
			(footprints allowed)
		)
		(placement
			(enabled no)
			(sheetname "")
		)
		(fill yes
			(thermal_gap 0.5)
			(thermal_bridge_width 0.5)
			(island_removal_mode 0)
		)
		(polygon
			(pts
				(arc
					(start 41.665398 -233.22153)
					(mid 41.680277 -233.257451)
					(end 41.716198 -233.27233)
				)
				(arc
					(start 43.115738 -233.27233)
					(mid 43.151659 -233.257451)
					(end 43.166538 -233.22153)
				)
				(arc
					(start 43.166538 -232.81259)
					(mid 43.151659 -232.776669)
					(end 43.115738 -232.76179)
				)
				(arc
					(start 41.716198 -232.76179)
					(mid 41.680277 -232.776669)
					(end 41.665398 -232.81259)
				)
			)
		)
	)
	(zone
		(layers "In1.Cu" "In2.Cu")
		(hatch none 0.5)
		(connect_pads
			(clearance 0)
		)
		(min_thickness 0.25)
		(keepout
			(tracks not_allowed)
			(vias allowed)
			(pads allowed)
			(copperpour not_allowed)
			(footprints allowed)
		)
		(placement
			(enabled no)
			(sheetname "")
		)
		(fill yes
			(thermal_gap 0.5)
			(thermal_bridge_width 0.5)
			(island_removal_mode 0)
		)
		(polygon
			(pts
				(arc
					(start 26.577798 -239.17148)
					(mid 26.592677 -239.207401)
					(end 26.628598 -239.22228)
				)
				(arc
					(start 28.028138 -239.22228)
					(mid 28.064059 -239.207401)
					(end 28.078938 -239.17148)
				)
				(arc
					(start 28.078938 -238.76254)
					(mid 28.064059 -238.726619)
					(end 28.028138 -238.71174)
				)
				(arc
					(start 26.628598 -238.71174)
					(mid 26.592677 -238.726619)
					(end 26.577798 -238.76254)
				)
			)
		)
	)
	(zone
		(layers "In1.Cu" "In2.Cu")
		(hatch none 0.5)
		(connect_pads
			(clearance 0)
		)
		(min_thickness 0.25)
		(keepout
			(tracks not_allowed)
			(vias allowed)
			(pads allowed)
			(copperpour not_allowed)
			(footprints allowed)
		)
		(placement
			(enabled no)
			(sheetname "")
		)
		(fill yes
			(thermal_gap 0.5)
			(thermal_bridge_width 0.5)
			(island_removal_mode 0)
		)
		(polygon
			(pts
				(arc
					(start 203.32573 -207.721454)
					(mid 203.340609 -207.757375)
					(end 203.37653 -207.772254)
				)
				(arc
					(start 204.77607 -207.772254)
					(mid 204.811991 -207.757375)
					(end 204.82687 -207.721454)
				)
				(arc
					(start 204.82687 -207.312514)
					(mid 204.811991 -207.276593)
					(end 204.77607 -207.261714)
				)
				(arc
					(start 203.37653 -207.261714)
					(mid 203.340609 -207.276593)
					(end 203.32573 -207.312514)
				)
			)
		)
	)
	(zone
		(layers "In1.Cu" "In2.Cu")
		(hatch none 0.5)
		(connect_pads
			(clearance 0)
		)
		(min_thickness 0.25)
		(keepout
			(tracks not_allowed)
			(vias allowed)
			(pads allowed)
			(copperpour not_allowed)
			(footprints allowed)
		)
		(placement
			(enabled no)
			(sheetname "")
		)
		(fill yes
			(thermal_gap 0.5)
			(thermal_bridge_width 0.5)
			(island_removal_mode 0)
		)
		(polygon
			(pts
				(arc
					(start 270.417798 -238.321342)
					(mid 270.432677 -238.357263)
					(end 270.468598 -238.372142)
				)
				(arc
					(start 271.868138 -238.372142)
					(mid 271.904059 -238.357263)
					(end 271.918938 -238.321342)
				)
				(arc
					(start 271.918938 -237.912402)
					(mid 271.904059 -237.876481)
					(end 271.868138 -237.861602)
				)
				(arc
					(start 270.468598 -237.861602)
					(mid 270.432677 -237.876481)
					(end 270.417798 -237.912402)
				)
			)
		)
	)
	(zone
		(layers "In1.Cu" "In2.Cu")
		(hatch none 0.5)
		(connect_pads
			(clearance 0)
		)
		(min_thickness 0.25)
		(keepout
			(tracks not_allowed)
			(vias allowed)
			(pads allowed)
			(copperpour not_allowed)
			(footprints allowed)
		)
		(placement
			(enabled no)
			(sheetname "")
		)
		(fill yes
			(thermal_gap 0.5)
			(thermal_bridge_width 0.5)
			(island_removal_mode 0)
		)
		(polygon
			(pts
				(arc
					(start 428.634398 -269.771368)
					(mid 428.649277 -269.807289)
					(end 428.685198 -269.822168)
				)
				(arc
					(start 430.084738 -269.822168)
					(mid 430.120659 -269.807289)
					(end 430.135538 -269.771368)
				)
				(arc
					(start 430.135538 -269.362428)
					(mid 430.120659 -269.326507)
					(end 430.084738 -269.311628)
				)
				(arc
					(start 428.685198 -269.311628)
					(mid 428.649277 -269.326507)
					(end 428.634398 -269.362428)
				)
			)
		)
	)
	(zone
		(layers "In1.Cu" "In2.Cu")
		(hatch none 0.5)
		(connect_pads
			(clearance 0)
		)
		(min_thickness 0.25)
		(keepout
			(tracks not_allowed)
			(vias allowed)
			(pads allowed)
			(copperpour not_allowed)
			(footprints allowed)
		)
		(placement
			(enabled no)
			(sheetname "")
		)
		(fill yes
			(thermal_gap 0.5)
			(thermal_bridge_width 0.5)
			(island_removal_mode 0)
		)
		(polygon
			(pts
				(arc
					(start 259.430266 -240.871502)
					(mid 259.445145 -240.907423)
					(end 259.481066 -240.922302)
				)
				(arc
					(start 260.880606 -240.922302)
					(mid 260.916527 -240.907423)
					(end 260.931406 -240.871502)
				)
				(arc
					(start 260.931406 -240.462562)
					(mid 260.916527 -240.426641)
					(end 260.880606 -240.411762)
				)
				(arc
					(start 259.481066 -240.411762)
					(mid 259.445145 -240.426641)
					(end 259.430266 -240.462562)
				)
			)
		)
	)
	(zone
		(layers "In1.Cu" "In2.Cu")
		(hatch none 0.5)
		(connect_pads
			(clearance 0)
		)
		(min_thickness 0.25)
		(keepout
			(tracks not_allowed)
			(vias allowed)
			(pads allowed)
			(copperpour not_allowed)
			(footprints allowed)
		)
		(placement
			(enabled no)
			(sheetname "")
		)
		(fill yes
			(thermal_gap 0.5)
			(thermal_bridge_width 0.5)
			(island_removal_mode 0)
		)
		(polygon
			(pts
				(arc
					(start 188.23813 -232.371392)
					(mid 188.253009 -232.407313)
					(end 188.28893 -232.422192)
				)
				(arc
					(start 189.68847 -232.422192)
					(mid 189.724391 -232.407313)
					(end 189.73927 -232.371392)
				)
				(arc
					(start 189.73927 -231.962452)
					(mid 189.724391 -231.926531)
					(end 189.68847 -231.911652)
				)
				(arc
					(start 188.28893 -231.911652)
					(mid 188.253009 -231.926531)
					(end 188.23813 -231.962452)
				)
			)
		)
	)
	(zone
		(layers "In1.Cu" "In2.Cu")
		(hatch none 0.5)
		(connect_pads
			(clearance 0)
		)
		(min_thickness 0.25)
		(keepout
			(tracks not_allowed)
			(vias allowed)
			(pads allowed)
			(copperpour not_allowed)
			(footprints allowed)
		)
		(placement
			(enabled no)
			(sheetname "")
		)
		(fill yes
			(thermal_gap 0.5)
			(thermal_bridge_width 0.5)
			(island_removal_mode 0)
		)
		(polygon
			(pts
				(arc
					(start 173.15053 -235.771436)
					(mid 173.165409 -235.807357)
					(end 173.20133 -235.822236)
				)
				(arc
					(start 174.60087 -235.822236)
					(mid 174.636791 -235.807357)
					(end 174.65167 -235.771436)
				)
				(arc
					(start 174.65167 -235.362496)
					(mid 174.636791 -235.326575)
					(end 174.60087 -235.311696)
				)
				(arc
					(start 173.20133 -235.311696)
					(mid 173.165409 -235.326575)
					(end 173.15053 -235.362496)
				)
			)
		)
	)
	(zone
		(layers "In1.Cu" "In2.Cu")
		(hatch none 0.5)
		(connect_pads
			(clearance 0)
		)
		(min_thickness 0.25)
		(keepout
			(tracks not_allowed)
			(vias allowed)
			(pads allowed)
			(copperpour not_allowed)
			(footprints allowed)
		)
		(placement
			(enabled no)
			(sheetname "")
		)
		(fill yes
			(thermal_gap 0.5)
			(thermal_bridge_width 0.5)
			(island_removal_mode 0)
		)
		(polygon
			(pts
				(arc
					(start 300.592998 -196.671438)
					(mid 300.607877 -196.707359)
					(end 300.643798 -196.722238)
				)
				(arc
					(start 302.043338 -196.722238)
					(mid 302.079259 -196.707359)
					(end 302.094138 -196.671438)
				)
				(arc
					(start 302.094138 -196.262498)
					(mid 302.079259 -196.226577)
					(end 302.043338 -196.211698)
				)
				(arc
					(start 300.643798 -196.211698)
					(mid 300.607877 -196.226577)
					(end 300.592998 -196.262498)
				)
			)
		)
	)
	(zone
		(layers "In1.Cu" "In2.Cu")
		(hatch none 0.5)
		(connect_pads
			(clearance 0)
		)
		(min_thickness 0.25)
		(keepout
			(tracks not_allowed)
			(vias allowed)
			(pads allowed)
			(copperpour not_allowed)
			(footprints allowed)
		)
		(placement
			(enabled no)
			(sheetname "")
		)
		(fill yes
			(thermal_gap 0.5)
			(thermal_bridge_width 0.5)
			(island_removal_mode 0)
		)
		(polygon
			(pts
				(arc
					(start 255.330198 -213.671404)
					(mid 255.345077 -213.707325)
					(end 255.380998 -213.722204)
				)
				(arc
					(start 256.780538 -213.722204)
					(mid 256.816459 -213.707325)
					(end 256.831338 -213.671404)
				)
				(arc
					(start 256.831338 -213.262464)
					(mid 256.816459 -213.226543)
					(end 256.780538 -213.211664)
				)
				(arc
					(start 255.380998 -213.211664)
					(mid 255.345077 -213.226543)
					(end 255.330198 -213.262464)
				)
			)
		)
	)
	(zone
		(layers "In1.Cu" "In2.Cu")
		(hatch none 0.5)
		(connect_pads
			(clearance 0)
		)
		(min_thickness 0.25)
		(keepout
			(tracks not_allowed)
			(vias allowed)
			(pads allowed)
			(copperpour not_allowed)
			(footprints allowed)
		)
		(placement
			(enabled no)
			(sheetname "")
		)
		(fill yes
			(thermal_gap 0.5)
			(thermal_bridge_width 0.5)
			(island_removal_mode 0)
		)
		(polygon
			(pts
				(arc
					(start 199.881998 -263.821418)
					(mid 199.896877 -263.857339)
					(end 199.932798 -263.872218)
				)
				(arc
					(start 201.332338 -263.872218)
					(mid 201.368259 -263.857339)
					(end 201.383138 -263.821418)
				)
				(arc
					(start 201.383138 -263.412478)
					(mid 201.368259 -263.376557)
					(end 201.332338 -263.361678)
				)
				(arc
					(start 199.932798 -263.361678)
					(mid 199.896877 -263.376557)
					(end 199.881998 -263.412478)
				)
			)
		)
	)
	(zone
		(layers "In1.Cu" "In2.Cu")
		(hatch none 0.5)
		(connect_pads
			(clearance 0)
		)
		(min_thickness 0.25)
		(keepout
			(tracks not_allowed)
			(vias allowed)
			(pads allowed)
			(copperpour not_allowed)
			(footprints allowed)
		)
		(placement
			(enabled no)
			(sheetname "")
		)
		(fill yes
			(thermal_gap 0.5)
			(thermal_bridge_width 0.5)
			(island_removal_mode 0)
		)
		(polygon
			(pts
				(arc
					(start 22.47773 -314.821316)
					(mid 22.492609 -314.857237)
					(end 22.52853 -314.872116)
				)
				(arc
					(start 23.92807 -314.872116)
					(mid 23.963991 -314.857237)
					(end 23.97887 -314.821316)
				)
				(arc
					(start 23.97887 -314.412376)
					(mid 23.963991 -314.376455)
					(end 23.92807 -314.361576)
				)
				(arc
					(start 22.52853 -314.361576)
					(mid 22.492609 -314.376455)
					(end 22.47773 -314.412376)
				)
			)
		)
	)
	(zone
		(layers "In1.Cu" "In2.Cu")
		(hatch none 0.5)
		(connect_pads
			(clearance 0)
		)
		(min_thickness 0.25)
		(keepout
			(tracks not_allowed)
			(vias allowed)
			(pads allowed)
			(copperpour not_allowed)
			(footprints allowed)
		)
		(placement
			(enabled no)
			(sheetname "")
		)
		(fill yes
			(thermal_gap 0.5)
			(thermal_bridge_width 0.5)
			(island_removal_mode 0)
		)
		(polygon
			(pts
				(arc
					(start 180.69433 -251.07138)
					(mid 180.709209 -251.107301)
					(end 180.74513 -251.12218)
				)
				(arc
					(start 182.14467 -251.12218)
					(mid 182.180591 -251.107301)
					(end 182.19547 -251.07138)
				)
				(arc
					(start 182.19547 -250.66244)
					(mid 182.180591 -250.626519)
					(end 182.14467 -250.61164)
				)
				(arc
					(start 180.74513 -250.61164)
					(mid 180.709209 -250.626519)
					(end 180.69433 -250.66244)
				)
			)
		)
	)
	(zone
		(layers "In1.Cu" "In2.Cu")
		(hatch none 0.5)
		(connect_pads
			(clearance 0)
		)
		(min_thickness 0.25)
		(keepout
			(tracks not_allowed)
			(vias allowed)
			(pads allowed)
			(copperpour not_allowed)
			(footprints allowed)
		)
		(placement
			(enabled no)
			(sheetname "")
		)
		(fill yes
			(thermal_gap 0.5)
			(thermal_bridge_width 0.5)
			(island_removal_mode 0)
		)
		(polygon
			(pts
				(arc
					(start 455.365866 -289.321494)
					(mid 455.380745 -289.357415)
					(end 455.416666 -289.372294)
				)
				(arc
					(start 456.816206 -289.372294)
					(mid 456.852127 -289.357415)
					(end 456.867006 -289.321494)
				)
				(arc
					(start 456.867006 -288.912554)
					(mid 456.852127 -288.876633)
					(end 456.816206 -288.861754)
				)
				(arc
					(start 455.416666 -288.861754)
					(mid 455.380745 -288.876633)
					(end 455.365866 -288.912554)
				)
			)
		)
	)
	(zone
		(layers "In1.Cu" "In2.Cu")
		(hatch none 0.5)
		(connect_pads
			(clearance 0)
		)
		(min_thickness 0.25)
		(keepout
			(tracks not_allowed)
			(vias allowed)
			(pads allowed)
			(copperpour not_allowed)
			(footprints allowed)
		)
		(placement
			(enabled no)
			(sheetname "")
		)
		(fill yes
			(thermal_gap 0.5)
			(thermal_bridge_width 0.5)
			(island_removal_mode 0)
		)
		(polygon
			(pts
				(arc
					(start 277.961598 -213.671404)
					(mid 277.976477 -213.707325)
					(end 278.012398 -213.722204)
				)
				(arc
					(start 279.411938 -213.722204)
					(mid 279.447859 -213.707325)
					(end 279.462738 -213.671404)
				)
				(arc
					(start 279.462738 -213.262464)
					(mid 279.447859 -213.226543)
					(end 279.411938 -213.211664)
				)
				(arc
					(start 278.012398 -213.211664)
					(mid 277.976477 -213.226543)
					(end 277.961598 -213.262464)
				)
			)
		)
	)
	(zone
		(layers "In1.Cu" "In2.Cu")
		(hatch none 0.5)
		(connect_pads
			(clearance 0)
		)
		(min_thickness 0.25)
		(keepout
			(tracks not_allowed)
			(vias allowed)
			(pads allowed)
			(copperpour not_allowed)
			(footprints allowed)
		)
		(placement
			(enabled no)
			(sheetname "")
		)
		(fill yes
			(thermal_gap 0.5)
			(thermal_bridge_width 0.5)
			(island_removal_mode 0)
		)
		(polygon
			(pts
				(arc
					(start 432.734466 -293.571422)
					(mid 432.749345 -293.607343)
					(end 432.785266 -293.622222)
				)
				(arc
					(start 434.184806 -293.622222)
					(mid 434.220727 -293.607343)
					(end 434.235606 -293.571422)
				)
				(arc
					(start 434.235606 -293.162482)
					(mid 434.220727 -293.126561)
					(end 434.184806 -293.111682)
				)
				(arc
					(start 432.785266 -293.111682)
					(mid 432.749345 -293.126561)
					(end 432.734466 -293.162482)
				)
			)
		)
	)
	(zone
		(layers "In1.Cu" "In2.Cu")
		(hatch none 0.5)
		(connect_pads
			(clearance 0)
		)
		(min_thickness 0.25)
		(keepout
			(tracks not_allowed)
			(vias allowed)
			(pads allowed)
			(copperpour not_allowed)
			(footprints allowed)
		)
		(placement
			(enabled no)
			(sheetname "")
		)
		(fill yes
			(thermal_gap 0.5)
			(thermal_bridge_width 0.5)
			(island_removal_mode 0)
		)
		(polygon
			(pts
				(arc
					(start 56.752998 -302.071532)
					(mid 56.767877 -302.107453)
					(end 56.803798 -302.122332)
				)
				(arc
					(start 58.203338 -302.122332)
					(mid 58.239259 -302.107453)
					(end 58.254138 -302.071532)
				)
				(arc
					(start 58.254138 -301.662592)
					(mid 58.239259 -301.626671)
					(end 58.203338 -301.611792)
				)
				(arc
					(start 56.803798 -301.611792)
					(mid 56.767877 -301.626671)
					(end 56.752998 -301.662592)
				)
			)
		)
	)
	(zone
		(layers "In1.Cu" "In2.Cu")
		(hatch none 0.5)
		(connect_pads
			(clearance 0)
		)
		(min_thickness 0.25)
		(keepout
			(tracks not_allowed)
			(vias allowed)
			(pads allowed)
			(copperpour not_allowed)
			(footprints allowed)
		)
		(placement
			(enabled no)
			(sheetname "")
		)
		(fill yes
			(thermal_gap 0.5)
			(thermal_bridge_width 0.5)
			(island_removal_mode 0)
		)
		(polygon
			(pts
				(arc
					(start 203.32573 -274.871434)
					(mid 203.340609 -274.907355)
					(end 203.37653 -274.922234)
				)
				(arc
					(start 204.77607 -274.922234)
					(mid 204.811991 -274.907355)
					(end 204.82687 -274.871434)
				)
				(arc
					(start 204.82687 -274.462494)
					(mid 204.811991 -274.426573)
					(end 204.77607 -274.411694)
				)
				(arc
					(start 203.37653 -274.411694)
					(mid 203.340609 -274.426573)
					(end 203.32573 -274.462494)
				)
			)
		)
	)
	(zone
		(layers "In1.Cu" "In2.Cu")
		(hatch none 0.5)
		(connect_pads
			(clearance 0)
		)
		(min_thickness 0.25)
		(keepout
			(tracks not_allowed)
			(vias allowed)
			(pads allowed)
			(copperpour not_allowed)
			(footprints allowed)
		)
		(placement
			(enabled no)
			(sheetname "")
		)
		(fill yes
			(thermal_gap 0.5)
			(thermal_bridge_width 0.5)
			(island_removal_mode 0)
		)
		(polygon
			(pts
				(arc
					(start 22.47773 -209.421476)
					(mid 22.492609 -209.457397)
					(end 22.52853 -209.472276)
				)
				(arc
					(start 23.92807 -209.472276)
					(mid 23.963991 -209.457397)
					(end 23.97887 -209.421476)
				)
				(arc
					(start 23.97887 -209.012536)
					(mid 23.963991 -208.976615)
					(end 23.92807 -208.961736)
				)
				(arc
					(start 22.52853 -208.961736)
					(mid 22.492609 -208.976615)
					(end 22.47773 -209.012536)
				)
			)
		)
	)
	(zone
		(layers "In1.Cu" "In2.Cu")
		(hatch none 0.5)
		(connect_pads
			(clearance 0)
		)
		(min_thickness 0.25)
		(keepout
			(tracks not_allowed)
			(vias allowed)
			(pads allowed)
			(copperpour not_allowed)
			(footprints allowed)
		)
		(placement
			(enabled no)
			(sheetname "")
		)
		(fill yes
			(thermal_gap 0.5)
			(thermal_bridge_width 0.5)
			(island_removal_mode 0)
		)
		(polygon
			(pts
				(arc
					(start 14.93393 -247.671336)
					(mid 14.948809 -247.707257)
					(end 14.98473 -247.722136)
				)
				(arc
					(start 16.38427 -247.722136)
					(mid 16.420191 -247.707257)
					(end 16.43507 -247.671336)
				)
				(arc
					(start 16.43507 -247.262396)
					(mid 16.420191 -247.226475)
					(end 16.38427 -247.211596)
				)
				(arc
					(start 14.98473 -247.211596)
					(mid 14.948809 -247.226475)
					(end 14.93393 -247.262396)
				)
			)
		)
	)
	(zone
		(layers "In1.Cu" "In2.Cu")
		(hatch none 0.5)
		(connect_pads
			(clearance 0)
		)
		(min_thickness 0.25)
		(keepout
			(tracks not_allowed)
			(vias allowed)
			(pads allowed)
			(copperpour not_allowed)
			(footprints allowed)
		)
		(placement
			(enabled no)
			(sheetname "")
		)
		(fill yes
			(thermal_gap 0.5)
			(thermal_bridge_width 0.5)
			(island_removal_mode 0)
		)
		(polygon
			(pts
				(arc
					(start 162.162998 -274.02155)
					(mid 162.177877 -274.057471)
					(end 162.213798 -274.07235)
				)
				(arc
					(start 163.613338 -274.07235)
					(mid 163.649259 -274.057471)
					(end 163.664138 -274.02155)
				)
				(arc
					(start 163.664138 -273.61261)
					(mid 163.649259 -273.576689)
					(end 163.613338 -273.56181)
				)
				(arc
					(start 162.213798 -273.56181)
					(mid 162.177877 -273.576689)
					(end 162.162998 -273.61261)
				)
			)
		)
	)
	(zone
		(layers "In1.Cu" "In2.Cu")
		(hatch none 0.5)
		(connect_pads
			(clearance 0)
		)
		(min_thickness 0.25)
		(keepout
			(tracks not_allowed)
			(vias allowed)
			(pads allowed)
			(copperpour not_allowed)
			(footprints allowed)
		)
		(placement
			(enabled no)
			(sheetname "")
		)
		(fill yes
			(thermal_gap 0.5)
			(thermal_bridge_width 0.5)
			(island_removal_mode 0)
		)
		(polygon
			(pts
				(arc
					(start 282.061666 -281.671522)
					(mid 282.076545 -281.707443)
					(end 282.112466 -281.722322)
				)
				(arc
					(start 283.512006 -281.722322)
					(mid 283.547927 -281.707443)
					(end 283.562806 -281.671522)
				)
				(arc
					(start 283.562806 -281.262582)
					(mid 283.547927 -281.226661)
					(end 283.512006 -281.211782)
				)
				(arc
					(start 282.112466 -281.211782)
					(mid 282.076545 -281.226661)
					(end 282.061666 -281.262582)
				)
			)
		)
	)
	(zone
		(layers "In1.Cu" "In2.Cu")
		(hatch none 0.5)
		(connect_pads
			(clearance 0)
		)
		(min_thickness 0.25)
		(keepout
			(tracks not_allowed)
			(vias allowed)
			(pads allowed)
			(copperpour not_allowed)
			(footprints allowed)
		)
		(placement
			(enabled no)
			(sheetname "")
		)
		(fill yes
			(thermal_gap 0.5)
			(thermal_bridge_width 0.5)
			(island_removal_mode 0)
		)
		(polygon
			(pts
				(arc
					(start 188.23813 -297.82135)
					(mid 188.253009 -297.857271)
					(end 188.28893 -297.87215)
				)
				(arc
					(start 189.68847 -297.87215)
					(mid 189.724391 -297.857271)
					(end 189.73927 -297.82135)
				)
				(arc
					(start 189.73927 -297.41241)
					(mid 189.724391 -297.376489)
					(end 189.68847 -297.36161)
				)
				(arc
					(start 188.28893 -297.36161)
					(mid 188.253009 -297.376489)
					(end 188.23813 -297.41241)
				)
			)
		)
	)
	(zone
		(layers "In1.Cu" "In2.Cu")
		(hatch none 0.5)
		(connect_pads
			(clearance 0)
		)
		(min_thickness 0.25)
		(keepout
			(tracks not_allowed)
			(vias allowed)
			(pads allowed)
			(copperpour not_allowed)
			(footprints allowed)
		)
		(placement
			(enabled no)
			(sheetname "")
		)
		(fill yes
			(thermal_gap 0.5)
			(thermal_bridge_width 0.5)
			(island_removal_mode 0)
		)
		(polygon
			(pts
				(arc
					(start 436.178198 -202.621388)
					(mid 436.193077 -202.657309)
					(end 436.228998 -202.672188)
				)
				(arc
					(start 437.628538 -202.672188)
					(mid 437.664459 -202.657309)
					(end 437.679338 -202.621388)
				)
				(arc
					(start 437.679338 -202.212448)
					(mid 437.664459 -202.176527)
					(end 437.628538 -202.161648)
				)
				(arc
					(start 436.228998 -202.161648)
					(mid 436.193077 -202.176527)
					(end 436.178198 -202.212448)
				)
			)
		)
	)
	(zone
		(layers "In1.Cu" "In2.Cu")
		(hatch none 0.5)
		(connect_pads
			(clearance 0)
		)
		(min_thickness 0.25)
		(keepout
			(tracks not_allowed)
			(vias allowed)
			(pads allowed)
			(copperpour not_allowed)
			(footprints allowed)
		)
		(placement
			(enabled no)
			(sheetname "")
		)
		(fill yes
			(thermal_gap 0.5)
			(thermal_bridge_width 0.5)
			(island_removal_mode 0)
		)
		(polygon
			(pts
				(arc
					(start 304.693066 -250.221496)
					(mid 304.707945 -250.257417)
					(end 304.743866 -250.272296)
				)
				(arc
					(start 306.143406 -250.272296)
					(mid 306.179327 -250.257417)
					(end 306.194206 -250.221496)
				)
				(arc
					(start 306.194206 -249.812556)
					(mid 306.179327 -249.776635)
					(end 306.143406 -249.761756)
				)
				(arc
					(start 304.743866 -249.761756)
					(mid 304.707945 -249.776635)
					(end 304.693066 -249.812556)
				)
			)
		)
	)
	(zone
		(layers "In1.Cu" "In2.Cu")
		(hatch none 0.5)
		(connect_pads
			(clearance 0)
		)
		(min_thickness 0.25)
		(keepout
			(tracks not_allowed)
			(vias allowed)
			(pads allowed)
			(copperpour not_allowed)
			(footprints allowed)
		)
		(placement
			(enabled no)
			(sheetname "")
		)
		(fill yes
			(thermal_gap 0.5)
			(thermal_bridge_width 0.5)
			(island_removal_mode 0)
		)
		(polygon
			(pts
				(arc
					(start 451.265798 -244.271292)
					(mid 451.280677 -244.307213)
					(end 451.316598 -244.322092)
				)
				(arc
					(start 452.716138 -244.322092)
					(mid 452.752059 -244.307213)
					(end 452.766938 -244.271292)
				)
				(arc
					(start 452.766938 -243.862352)
					(mid 452.752059 -243.826431)
					(end 452.716138 -243.811552)
				)
				(arc
					(start 451.316598 -243.811552)
					(mid 451.280677 -243.826431)
					(end 451.265798 -243.862352)
				)
			)
		)
	)
	(zone
		(layers "In1.Cu" "In2.Cu")
		(hatch none 0.5)
		(connect_pads
			(clearance 0)
		)
		(min_thickness 0.25)
		(keepout
			(tracks not_allowed)
			(vias allowed)
			(pads allowed)
			(copperpour not_allowed)
			(footprints allowed)
		)
		(placement
			(enabled no)
			(sheetname "")
		)
		(fill yes
			(thermal_gap 0.5)
			(thermal_bridge_width 0.5)
			(island_removal_mode 0)
		)
		(polygon
			(pts
				(arc
					(start 210.86953 -247.671336)
					(mid 210.884409 -247.707257)
					(end 210.92033 -247.722136)
				)
				(arc
					(start 212.31987 -247.722136)
					(mid 212.355791 -247.707257)
					(end 212.37067 -247.671336)
				)
				(arc
					(start 212.37067 -247.262396)
					(mid 212.355791 -247.226475)
					(end 212.31987 -247.211596)
				)
				(arc
					(start 210.92033 -247.211596)
					(mid 210.884409 -247.226475)
					(end 210.86953 -247.262396)
				)
			)
		)
	)
	(zone
		(layers "In1.Cu" "In2.Cu")
		(hatch none 0.5)
		(connect_pads
			(clearance 0)
		)
		(min_thickness 0.25)
		(keepout
			(tracks not_allowed)
			(vias allowed)
			(pads allowed)
			(copperpour not_allowed)
			(footprints allowed)
		)
		(placement
			(enabled no)
			(sheetname "")
		)
		(fill yes
			(thermal_gap 0.5)
			(thermal_bridge_width 0.5)
			(island_removal_mode 0)
		)
		(polygon
			(pts
				(arc
					(start 428.634398 -261.271512)
					(mid 428.649277 -261.307433)
					(end 428.685198 -261.322312)
				)
				(arc
					(start 430.084738 -261.322312)
					(mid 430.120659 -261.307433)
					(end 430.135538 -261.271512)
				)
				(arc
					(start 430.135538 -260.862572)
					(mid 430.120659 -260.826651)
					(end 430.084738 -260.811772)
				)
				(arc
					(start 428.685198 -260.811772)
					(mid 428.649277 -260.826651)
					(end 428.634398 -260.862572)
				)
			)
		)
	)
	(zone
		(layers "In1.Cu" "In2.Cu")
		(hatch none 0.5)
		(connect_pads
			(clearance 0)
		)
		(min_thickness 0.25)
		(keepout
			(tracks not_allowed)
			(vias allowed)
			(pads allowed)
			(copperpour not_allowed)
			(footprints allowed)
		)
		(placement
			(enabled no)
			(sheetname "")
		)
		(fill yes
			(thermal_gap 0.5)
			(thermal_bridge_width 0.5)
			(island_removal_mode 0)
		)
		(polygon
			(pts
				(arc
					(start 259.430266 -212.82152)
					(mid 259.445145 -212.857441)
					(end 259.481066 -212.87232)
				)
				(arc
					(start 260.880606 -212.87232)
					(mid 260.916527 -212.857441)
					(end 260.931406 -212.82152)
				)
				(arc
					(start 260.931406 -212.41258)
					(mid 260.916527 -212.376659)
					(end 260.880606 -212.36178)
				)
				(arc
					(start 259.481066 -212.36178)
					(mid 259.445145 -212.376659)
					(end 259.430266 -212.41258)
				)
			)
		)
	)
	(zone
		(layers "In1.Cu" "In2.Cu")
		(hatch none 0.5)
		(connect_pads
			(clearance 0)
		)
		(min_thickness 0.25)
		(keepout
			(tracks not_allowed)
			(vias allowed)
			(pads allowed)
			(copperpour not_allowed)
			(footprints allowed)
		)
		(placement
			(enabled no)
			(sheetname "")
		)
		(fill yes
			(thermal_gap 0.5)
			(thermal_bridge_width 0.5)
			(island_removal_mode 0)
		)
		(polygon
			(pts
				(arc
					(start 410.103066 -278.271478)
					(mid 410.117945 -278.307399)
					(end 410.153866 -278.322278)
				)
				(arc
					(start 411.553406 -278.322278)
					(mid 411.589327 -278.307399)
					(end 411.604206 -278.271478)
				)
				(arc
					(start 411.604206 -277.862538)
					(mid 411.589327 -277.826617)
					(end 411.553406 -277.811738)
				)
				(arc
					(start 410.153866 -277.811738)
					(mid 410.117945 -277.826617)
					(end 410.103066 -277.862538)
				)
			)
		)
	)
	(zone
		(layers "In1.Cu" "In2.Cu")
		(hatch none 0.5)
		(connect_pads
			(clearance 0)
		)
		(min_thickness 0.25)
		(keepout
			(tracks not_allowed)
			(vias allowed)
			(pads allowed)
			(copperpour not_allowed)
			(footprints allowed)
		)
		(placement
			(enabled no)
			(sheetname "")
		)
		(fill yes
			(thermal_gap 0.5)
			(thermal_bridge_width 0.5)
			(island_removal_mode 0)
		)
		(polygon
			(pts
				(arc
					(start 300.592998 -247.671336)
					(mid 300.607877 -247.707257)
					(end 300.643798 -247.722136)
				)
				(arc
					(start 302.043338 -247.722136)
					(mid 302.079259 -247.707257)
					(end 302.094138 -247.671336)
				)
				(arc
					(start 302.094138 -247.262396)
					(mid 302.079259 -247.226475)
					(end 302.043338 -247.211596)
				)
				(arc
					(start 300.643798 -247.211596)
					(mid 300.607877 -247.226475)
					(end 300.592998 -247.262396)
				)
			)
		)
	)
	(zone
		(layers "In1.Cu" "In2.Cu")
		(hatch none 0.5)
		(connect_pads
			(clearance 0)
		)
		(min_thickness 0.25)
		(keepout
			(tracks not_allowed)
			(vias allowed)
			(pads allowed)
			(copperpour not_allowed)
			(footprints allowed)
		)
		(placement
			(enabled no)
			(sheetname "")
		)
		(fill yes
			(thermal_gap 0.5)
			(thermal_bridge_width 0.5)
			(island_removal_mode 0)
		)
		(polygon
			(pts
				(arc
					(start 180.69433 -235.771436)
					(mid 180.709209 -235.807357)
					(end 180.74513 -235.822236)
				)
				(arc
					(start 182.14467 -235.822236)
					(mid 182.180591 -235.807357)
					(end 182.19547 -235.771436)
				)
				(arc
					(start 182.19547 -235.362496)
					(mid 182.180591 -235.326575)
					(end 182.14467 -235.311696)
				)
				(arc
					(start 180.74513 -235.311696)
					(mid 180.709209 -235.326575)
					(end 180.69433 -235.362496)
				)
			)
		)
	)
	(zone
		(layers "In1.Cu" "In2.Cu")
		(hatch none 0.5)
		(connect_pads
			(clearance 0)
		)
		(min_thickness 0.25)
		(keepout
			(tracks not_allowed)
			(vias allowed)
			(pads allowed)
			(copperpour not_allowed)
			(footprints allowed)
		)
		(placement
			(enabled no)
			(sheetname "")
		)
		(fill yes
			(thermal_gap 0.5)
			(thermal_bridge_width 0.5)
			(island_removal_mode 0)
		)
		(polygon
			(pts
				(arc
					(start 406.002998 -198.37146)
					(mid 406.017877 -198.407381)
					(end 406.053798 -198.42226)
				)
				(arc
					(start 407.453338 -198.42226)
					(mid 407.489259 -198.407381)
					(end 407.504138 -198.37146)
				)
				(arc
					(start 407.504138 -197.96252)
					(mid 407.489259 -197.926599)
					(end 407.453338 -197.91172)
				)
				(arc
					(start 406.053798 -197.91172)
					(mid 406.017877 -197.926599)
					(end 406.002998 -197.96252)
				)
			)
		)
	)
	(zone
		(layers "In1.Cu" "In2.Cu")
		(hatch none 0.5)
		(connect_pads
			(clearance 0)
		)
		(min_thickness 0.25)
		(keepout
			(tracks not_allowed)
			(vias allowed)
			(pads allowed)
			(copperpour not_allowed)
			(footprints allowed)
		)
		(placement
			(enabled no)
			(sheetname "")
		)
		(fill yes
			(thermal_gap 0.5)
			(thermal_bridge_width 0.5)
			(island_removal_mode 0)
		)
		(polygon
			(pts
				(arc
					(start 297.149266 -203.471526)
					(mid 297.164145 -203.507447)
					(end 297.200066 -203.522326)
				)
				(arc
					(start 298.599606 -203.522326)
					(mid 298.635527 -203.507447)
					(end 298.650406 -203.471526)
				)
				(arc
					(start 298.650406 -203.062586)
					(mid 298.635527 -203.026665)
					(end 298.599606 -203.011786)
				)
				(arc
					(start 297.200066 -203.011786)
					(mid 297.164145 -203.026665)
					(end 297.149266 -203.062586)
				)
			)
		)
	)
	(zone
		(layers "In1.Cu" "In2.Cu")
		(hatch none 0.5)
		(connect_pads
			(clearance 0)
		)
		(min_thickness 0.25)
		(keepout
			(tracks not_allowed)
			(vias allowed)
			(pads allowed)
			(copperpour not_allowed)
			(footprints allowed)
		)
		(placement
			(enabled no)
			(sheetname "")
		)
		(fill yes
			(thermal_gap 0.5)
			(thermal_bridge_width 0.5)
			(island_removal_mode 0)
		)
		(polygon
			(pts
				(arc
					(start 11.490198 -240.871502)
					(mid 11.505077 -240.907423)
					(end 11.540998 -240.922302)
				)
				(arc
					(start 12.940538 -240.922302)
					(mid 12.976459 -240.907423)
					(end 12.991338 -240.871502)
				)
				(arc
					(start 12.991338 -240.462562)
					(mid 12.976459 -240.426641)
					(end 12.940538 -240.411762)
				)
				(arc
					(start 11.540998 -240.411762)
					(mid 11.505077 -240.426641)
					(end 11.490198 -240.462562)
				)
			)
		)
	)
	(zone
		(layers "In1.Cu" "In2.Cu")
		(hatch none 0.5)
		(connect_pads
			(clearance 0)
		)
		(min_thickness 0.25)
		(keepout
			(tracks not_allowed)
			(vias allowed)
			(pads allowed)
			(copperpour not_allowed)
			(footprints allowed)
		)
		(placement
			(enabled no)
			(sheetname "")
		)
		(fill yes
			(thermal_gap 0.5)
			(thermal_bridge_width 0.5)
			(island_removal_mode 0)
		)
		(polygon
			(pts
				(arc
					(start 406.002998 -251.07138)
					(mid 406.017877 -251.107301)
					(end 406.053798 -251.12218)
				)
				(arc
					(start 407.453338 -251.12218)
					(mid 407.489259 -251.107301)
					(end 407.504138 -251.07138)
				)
				(arc
					(start 407.504138 -250.66244)
					(mid 407.489259 -250.626519)
					(end 407.453338 -250.61164)
				)
				(arc
					(start 406.053798 -250.61164)
					(mid 406.017877 -250.626519)
					(end 406.002998 -250.66244)
				)
			)
		)
	)
	(zone
		(layers "In1.Cu" "In2.Cu")
		(hatch none 0.5)
		(connect_pads
			(clearance 0)
		)
		(min_thickness 0.25)
		(keepout
			(tracks not_allowed)
			(vias allowed)
			(pads allowed)
			(copperpour not_allowed)
			(footprints allowed)
		)
		(placement
			(enabled no)
			(sheetname "")
		)
		(fill yes
			(thermal_gap 0.5)
			(thermal_bridge_width 0.5)
			(island_removal_mode 0)
		)
		(polygon
			(pts
				(arc
					(start 60.19673 -291.8714)
					(mid 60.211609 -291.907321)
					(end 60.24753 -291.9222)
				)
				(arc
					(start 61.64707 -291.9222)
					(mid 61.682991 -291.907321)
					(end 61.69787 -291.8714)
				)
				(arc
					(start 61.69787 -291.46246)
					(mid 61.682991 -291.426539)
					(end 61.64707 -291.41166)
				)
				(arc
					(start 60.24753 -291.41166)
					(mid 60.211609 -291.426539)
					(end 60.19673 -291.46246)
				)
			)
		)
	)
	(zone
		(layers "In1.Cu" "In2.Cu")
		(hatch none 0.5)
		(connect_pads
			(clearance 0)
		)
		(min_thickness 0.25)
		(keepout
			(tracks not_allowed)
			(vias allowed)
			(pads allowed)
			(copperpour not_allowed)
			(footprints allowed)
		)
		(placement
			(enabled no)
			(sheetname "")
		)
		(fill yes
			(thermal_gap 0.5)
			(thermal_bridge_width 0.5)
			(island_removal_mode 0)
		)
		(polygon
			(pts
				(arc
					(start 413.546798 -226.421442)
					(mid 413.561677 -226.457363)
					(end 413.597598 -226.472242)
				)
				(arc
					(start 414.997138 -226.472242)
					(mid 415.033059 -226.457363)
					(end 415.047938 -226.421442)
				)
				(arc
					(start 415.047938 -226.012502)
					(mid 415.033059 -225.976581)
					(end 414.997138 -225.961702)
				)
				(arc
					(start 413.597598 -225.961702)
					(mid 413.561677 -225.976581)
					(end 413.546798 -226.012502)
				)
			)
		)
	)
	(zone
		(layers "In1.Cu" "In2.Cu")
		(hatch none 0.5)
		(connect_pads
			(clearance 0)
		)
		(min_thickness 0.25)
		(keepout
			(tracks not_allowed)
			(vias allowed)
			(pads allowed)
			(copperpour not_allowed)
			(footprints allowed)
		)
		(placement
			(enabled no)
			(sheetname "")
		)
		(fill yes
			(thermal_gap 0.5)
			(thermal_bridge_width 0.5)
			(island_removal_mode 0)
		)
		(polygon
			(pts
				(arc
					(start 293.049198 -277.42134)
					(mid 293.064077 -277.457261)
					(end 293.099998 -277.47214)
				)
				(arc
					(start 294.499538 -277.47214)
					(mid 294.535459 -277.457261)
					(end 294.550338 -277.42134)
				)
				(arc
					(start 294.550338 -277.0124)
					(mid 294.535459 -276.976479)
					(end 294.499538 -276.9616)
				)
				(arc
					(start 293.099998 -276.9616)
					(mid 293.064077 -276.976479)
					(end 293.049198 -277.0124)
				)
			)
		)
	)
	(zone
		(layers "In1.Cu" "In2.Cu")
		(hatch none 0.5)
		(connect_pads
			(clearance 0)
		)
		(min_thickness 0.25)
		(keepout
			(tracks not_allowed)
			(vias allowed)
			(pads allowed)
			(copperpour not_allowed)
			(footprints allowed)
		)
		(placement
			(enabled no)
			(sheetname "")
		)
		(fill yes
			(thermal_gap 0.5)
			(thermal_bridge_width 0.5)
			(island_removal_mode 0)
		)
		(polygon
			(pts
				(arc
					(start 304.693066 -237.471458)
					(mid 304.707945 -237.507379)
					(end 304.743866 -237.522258)
				)
				(arc
					(start 306.143406 -237.522258)
					(mid 306.179327 -237.507379)
					(end 306.194206 -237.471458)
				)
				(arc
					(start 306.194206 -237.062518)
					(mid 306.179327 -237.026597)
					(end 306.143406 -237.011718)
				)
				(arc
					(start 304.743866 -237.011718)
					(mid 304.707945 -237.026597)
					(end 304.693066 -237.062518)
				)
			)
		)
	)
	(zone
		(layers "In1.Cu" "In2.Cu")
		(hatch none 0.5)
		(connect_pads
			(clearance 0)
		)
		(min_thickness 0.25)
		(keepout
			(tracks not_allowed)
			(vias allowed)
			(pads allowed)
			(copperpour not_allowed)
			(footprints allowed)
		)
		(placement
			(enabled no)
			(sheetname "")
		)
		(fill yes
			(thermal_gap 0.5)
			(thermal_bridge_width 0.5)
			(island_removal_mode 0)
		)
		(polygon
			(pts
				(arc
					(start 158.06293 -217.071448)
					(mid 158.077809 -217.107369)
					(end 158.11373 -217.122248)
				)
				(arc
					(start 159.51327 -217.122248)
					(mid 159.549191 -217.107369)
					(end 159.56407 -217.071448)
				)
				(arc
					(start 159.56407 -216.662508)
					(mid 159.549191 -216.626587)
					(end 159.51327 -216.611708)
				)
				(arc
					(start 158.11373 -216.611708)
					(mid 158.077809 -216.626587)
					(end 158.06293 -216.662508)
				)
			)
		)
	)
	(zone
		(layers "In1.Cu" "In2.Cu")
		(hatch none 0.5)
		(connect_pads
			(clearance 0)
		)
		(min_thickness 0.25)
		(keepout
			(tracks not_allowed)
			(vias allowed)
			(pads allowed)
			(copperpour not_allowed)
			(footprints allowed)
		)
		(placement
			(enabled no)
			(sheetname "")
		)
		(fill yes
			(thermal_gap 0.5)
			(thermal_bridge_width 0.5)
			(island_removal_mode 0)
		)
		(polygon
			(pts
				(arc
					(start 162.162998 -281.671522)
					(mid 162.177877 -281.707443)
					(end 162.213798 -281.722322)
				)
				(arc
					(start 163.613338 -281.722322)
					(mid 163.649259 -281.707443)
					(end 163.664138 -281.671522)
				)
				(arc
					(start 163.664138 -281.262582)
					(mid 163.649259 -281.226661)
					(end 163.613338 -281.211782)
				)
				(arc
					(start 162.213798 -281.211782)
					(mid 162.177877 -281.226661)
					(end 162.162998 -281.262582)
				)
			)
		)
	)
	(zone
		(layers "In1.Cu" "In2.Cu")
		(hatch none 0.5)
		(connect_pads
			(clearance 0)
		)
		(min_thickness 0.25)
		(keepout
			(tracks not_allowed)
			(vias allowed)
			(pads allowed)
			(copperpour not_allowed)
			(footprints allowed)
		)
		(placement
			(enabled no)
			(sheetname "")
		)
		(fill yes
			(thermal_gap 0.5)
			(thermal_bridge_width 0.5)
			(island_removal_mode 0)
		)
		(polygon
			(pts
				(arc
					(start 37.56533 -202.621388)
					(mid 37.580209 -202.657309)
					(end 37.61613 -202.672188)
				)
				(arc
					(start 39.01567 -202.672188)
					(mid 39.051591 -202.657309)
					(end 39.06647 -202.621388)
				)
				(arc
					(start 39.06647 -202.212448)
					(mid 39.051591 -202.176527)
					(end 39.01567 -202.161648)
				)
				(arc
					(start 37.61613 -202.161648)
					(mid 37.580209 -202.176527)
					(end 37.56533 -202.212448)
				)
			)
		)
	)
	(zone
		(layers "In1.Cu" "In2.Cu")
		(hatch none 0.5)
		(connect_pads
			(clearance 0)
		)
		(min_thickness 0.25)
		(keepout
			(tracks not_allowed)
			(vias allowed)
			(pads allowed)
			(copperpour not_allowed)
			(footprints allowed)
		)
		(placement
			(enabled no)
			(sheetname "")
		)
		(fill yes
			(thermal_gap 0.5)
			(thermal_bridge_width 0.5)
			(island_removal_mode 0)
		)
		(polygon
			(pts
				(arc
					(start 19.033998 -212.82152)
					(mid 19.048877 -212.857441)
					(end 19.084798 -212.87232)
				)
				(arc
					(start 20.484338 -212.87232)
					(mid 20.520259 -212.857441)
					(end 20.535138 -212.82152)
				)
				(arc
					(start 20.535138 -212.41258)
					(mid 20.520259 -212.376659)
					(end 20.484338 -212.36178)
				)
				(arc
					(start 19.084798 -212.36178)
					(mid 19.048877 -212.376659)
					(end 19.033998 -212.41258)
				)
			)
		)
	)
	(zone
		(layers "In1.Cu" "In2.Cu")
		(hatch none 0.5)
		(connect_pads
			(clearance 0)
		)
		(min_thickness 0.25)
		(keepout
			(tracks not_allowed)
			(vias allowed)
			(pads allowed)
			(copperpour not_allowed)
			(footprints allowed)
		)
		(placement
			(enabled no)
			(sheetname "")
		)
		(fill yes
			(thermal_gap 0.5)
			(thermal_bridge_width 0.5)
			(island_removal_mode 0)
		)
		(polygon
			(pts
				(arc
					(start 214.969598 -311.421526)
					(mid 214.984477 -311.457447)
					(end 215.020398 -311.472326)
				)
				(arc
					(start 216.419938 -311.472326)
					(mid 216.455859 -311.457447)
					(end 216.470738 -311.421526)
				)
				(arc
					(start 216.470738 -311.012586)
					(mid 216.455859 -310.976665)
					(end 216.419938 -310.961786)
				)
				(arc
					(start 215.020398 -310.961786)
					(mid 214.984477 -310.976665)
					(end 214.969598 -311.012586)
				)
			)
		)
	)
	(zone
		(layers "In1.Cu" "In2.Cu")
		(hatch none 0.5)
		(connect_pads
			(clearance 0)
		)
		(min_thickness 0.25)
		(keepout
			(tracks not_allowed)
			(vias allowed)
			(pads allowed)
			(copperpour not_allowed)
			(footprints allowed)
		)
		(placement
			(enabled no)
			(sheetname "")
		)
		(fill yes
			(thermal_gap 0.5)
			(thermal_bridge_width 0.5)
			(island_removal_mode 0)
		)
		(polygon
			(pts
				(arc
					(start 188.23813 -238.321342)
					(mid 188.253009 -238.357263)
					(end 188.28893 -238.372142)
				)
				(arc
					(start 189.68847 -238.372142)
					(mid 189.724391 -238.357263)
					(end 189.73927 -238.321342)
				)
				(arc
					(start 189.73927 -237.912402)
					(mid 189.724391 -237.876481)
					(end 189.68847 -237.861602)
				)
				(arc
					(start 188.28893 -237.861602)
					(mid 188.253009 -237.876481)
					(end 188.23813 -237.912402)
				)
			)
		)
	)
	(zone
		(layers "In1.Cu" "In2.Cu")
		(hatch none 0.5)
		(connect_pads
			(clearance 0)
		)
		(min_thickness 0.25)
		(keepout
			(tracks not_allowed)
			(vias allowed)
			(pads allowed)
			(copperpour not_allowed)
			(footprints allowed)
		)
		(placement
			(enabled no)
			(sheetname "")
		)
		(fill yes
			(thermal_gap 0.5)
			(thermal_bridge_width 0.5)
			(island_removal_mode 0)
		)
		(polygon
			(pts
				(arc
					(start 458.809598 -284.221428)
					(mid 458.824477 -284.257349)
					(end 458.860398 -284.272228)
				)
				(arc
					(start 460.259938 -284.272228)
					(mid 460.295859 -284.257349)
					(end 460.310738 -284.221428)
				)
				(arc
					(start 460.310738 -283.812488)
					(mid 460.295859 -283.776567)
					(end 460.259938 -283.761688)
				)
				(arc
					(start 458.860398 -283.761688)
					(mid 458.824477 -283.776567)
					(end 458.809598 -283.812488)
				)
			)
		)
	)
	(zone
		(layers "In1.Cu" "In2.Cu")
		(hatch none 0.5)
		(connect_pads
			(clearance 0)
		)
		(min_thickness 0.25)
		(keepout
			(tracks not_allowed)
			(vias allowed)
			(pads allowed)
			(copperpour not_allowed)
			(footprints allowed)
		)
		(placement
			(enabled no)
			(sheetname "")
		)
		(fill yes
			(thermal_gap 0.5)
			(thermal_bridge_width 0.5)
			(island_removal_mode 0)
		)
		(polygon
			(pts
				(arc
					(start 458.809598 -198.37146)
					(mid 458.824477 -198.407381)
					(end 458.860398 -198.42226)
				)
				(arc
					(start 460.259938 -198.42226)
					(mid 460.295859 -198.407381)
					(end 460.310738 -198.37146)
				)
				(arc
					(start 460.310738 -197.96252)
					(mid 460.295859 -197.926599)
					(end 460.259938 -197.91172)
				)
				(arc
					(start 458.860398 -197.91172)
					(mid 458.824477 -197.926599)
					(end 458.809598 -197.96252)
				)
			)
		)
	)
	(zone
		(layers "In1.Cu" "In2.Cu")
		(hatch none 0.5)
		(connect_pads
			(clearance 0)
		)
		(min_thickness 0.25)
		(keepout
			(tracks not_allowed)
			(vias allowed)
			(pads allowed)
			(copperpour not_allowed)
			(footprints allowed)
		)
		(placement
			(enabled no)
			(sheetname "")
		)
		(fill yes
			(thermal_gap 0.5)
			(thermal_bridge_width 0.5)
			(island_removal_mode 0)
		)
		(polygon
			(pts
				(arc
					(start 19.033998 -292.721538)
					(mid 19.048877 -292.757459)
					(end 19.084798 -292.772338)
				)
				(arc
					(start 20.484338 -292.772338)
					(mid 20.520259 -292.757459)
					(end 20.535138 -292.721538)
				)
				(arc
					(start 20.535138 -292.312598)
					(mid 20.520259 -292.276677)
					(end 20.484338 -292.261798)
				)
				(arc
					(start 19.084798 -292.261798)
					(mid 19.048877 -292.276677)
					(end 19.033998 -292.312598)
				)
			)
		)
	)
	(zone
		(layers "In1.Cu" "In2.Cu")
		(hatch none 0.5)
		(connect_pads
			(clearance 0)
		)
		(min_thickness 0.25)
		(keepout
			(tracks not_allowed)
			(vias allowed)
			(pads allowed)
			(copperpour not_allowed)
			(footprints allowed)
		)
		(placement
			(enabled no)
			(sheetname "")
		)
		(fill yes
			(thermal_gap 0.5)
			(thermal_bridge_width 0.5)
			(island_removal_mode 0)
		)
		(polygon
			(pts
				(arc
					(start 451.265798 -269.771368)
					(mid 451.280677 -269.807289)
					(end 451.316598 -269.822168)
				)
				(arc
					(start 452.716138 -269.822168)
					(mid 452.752059 -269.807289)
					(end 452.766938 -269.771368)
				)
				(arc
					(start 452.766938 -269.362428)
					(mid 452.752059 -269.326507)
					(end 452.716138 -269.311628)
				)
				(arc
					(start 451.316598 -269.311628)
					(mid 451.280677 -269.326507)
					(end 451.265798 -269.362428)
				)
			)
		)
	)
	(zone
		(layers "In1.Cu" "In2.Cu")
		(hatch none 0.5)
		(connect_pads
			(clearance 0)
		)
		(min_thickness 0.25)
		(keepout
			(tracks not_allowed)
			(vias allowed)
			(pads allowed)
			(copperpour not_allowed)
			(footprints allowed)
		)
		(placement
			(enabled no)
			(sheetname "")
		)
		(fill yes
			(thermal_gap 0.5)
			(thermal_bridge_width 0.5)
			(island_removal_mode 0)
		)
		(polygon
			(pts
				(arc
					(start 7.39013 -247.671336)
					(mid 7.405009 -247.707257)
					(end 7.44093 -247.722136)
				)
				(arc
					(start 8.84047 -247.722136)
					(mid 8.876391 -247.707257)
					(end 8.89127 -247.671336)
				)
				(arc
					(start 8.89127 -247.262396)
					(mid 8.876391 -247.226475)
					(end 8.84047 -247.211596)
				)
				(arc
					(start 7.44093 -247.211596)
					(mid 7.405009 -247.226475)
					(end 7.39013 -247.262396)
				)
			)
		)
	)
	(zone
		(layers "In1.Cu" "In2.Cu")
		(hatch none 0.5)
		(connect_pads
			(clearance 0)
		)
		(min_thickness 0.25)
		(keepout
			(tracks not_allowed)
			(vias allowed)
			(pads allowed)
			(copperpour not_allowed)
			(footprints allowed)
		)
		(placement
			(enabled no)
			(sheetname "")
		)
		(fill yes
			(thermal_gap 0.5)
			(thermal_bridge_width 0.5)
			(island_removal_mode 0)
		)
		(polygon
			(pts
				(arc
					(start 45.10913 -268.071346)
					(mid 45.124009 -268.107267)
					(end 45.15993 -268.122146)
				)
				(arc
					(start 46.55947 -268.122146)
					(mid 46.595391 -268.107267)
					(end 46.61027 -268.071346)
				)
				(arc
					(start 46.61027 -267.662406)
					(mid 46.595391 -267.626485)
					(end 46.55947 -267.611606)
				)
				(arc
					(start 45.15993 -267.611606)
					(mid 45.124009 -267.626485)
					(end 45.10913 -267.662406)
				)
			)
		)
	)
	(zone
		(layers "In1.Cu" "In2.Cu")
		(hatch none 0.5)
		(connect_pads
			(clearance 0)
		)
		(min_thickness 0.25)
		(keepout
			(tracks not_allowed)
			(vias allowed)
			(pads allowed)
			(copperpour not_allowed)
			(footprints allowed)
		)
		(placement
			(enabled no)
			(sheetname "")
		)
		(fill yes
			(thermal_gap 0.5)
			(thermal_bridge_width 0.5)
			(island_removal_mode 0)
		)
		(polygon
			(pts
				(arc
					(start 277.961598 -290.171378)
					(mid 277.976477 -290.207299)
					(end 278.012398 -290.222178)
				)
				(arc
					(start 279.411938 -290.222178)
					(mid 279.447859 -290.207299)
					(end 279.462738 -290.171378)
				)
				(arc
					(start 279.462738 -289.762438)
					(mid 279.447859 -289.726517)
					(end 279.411938 -289.711638)
				)
				(arc
					(start 278.012398 -289.711638)
					(mid 277.976477 -289.726517)
					(end 277.961598 -289.762438)
				)
			)
		)
	)
	(zone
		(layers "In1.Cu" "In2.Cu")
		(hatch none 0.5)
		(connect_pads
			(clearance 0)
		)
		(min_thickness 0.25)
		(keepout
			(tracks not_allowed)
			(vias allowed)
			(pads allowed)
			(copperpour not_allowed)
			(footprints allowed)
		)
		(placement
			(enabled no)
			(sheetname "")
		)
		(fill yes
			(thermal_gap 0.5)
			(thermal_bridge_width 0.5)
			(island_removal_mode 0)
		)
		(polygon
			(pts
				(arc
					(start 259.430266 -292.721538)
					(mid 259.445145 -292.757459)
					(end 259.481066 -292.772338)
				)
				(arc
					(start 260.880606 -292.772338)
					(mid 260.916527 -292.757459)
					(end 260.931406 -292.721538)
				)
				(arc
					(start 260.931406 -292.312598)
					(mid 260.916527 -292.276677)
					(end 260.880606 -292.261798)
				)
				(arc
					(start 259.481066 -292.261798)
					(mid 259.445145 -292.276677)
					(end 259.430266 -292.312598)
				)
			)
		)
	)
	(zone
		(layers "In1.Cu" "In2.Cu")
		(hatch none 0.5)
		(connect_pads
			(clearance 0)
		)
		(min_thickness 0.25)
		(keepout
			(tracks not_allowed)
			(vias allowed)
			(pads allowed)
			(copperpour not_allowed)
			(footprints allowed)
		)
		(placement
			(enabled no)
			(sheetname "")
		)
		(fill yes
			(thermal_gap 0.5)
			(thermal_bridge_width 0.5)
			(island_removal_mode 0)
		)
		(polygon
			(pts
				(arc
					(start 207.425798 -263.821418)
					(mid 207.440677 -263.857339)
					(end 207.476598 -263.872218)
				)
				(arc
					(start 208.876138 -263.872218)
					(mid 208.912059 -263.857339)
					(end 208.926938 -263.821418)
				)
				(arc
					(start 208.926938 -263.412478)
					(mid 208.912059 -263.376557)
					(end 208.876138 -263.361678)
				)
				(arc
					(start 207.476598 -263.361678)
					(mid 207.440677 -263.376557)
					(end 207.425798 -263.412478)
				)
			)
		)
	)
	(zone
		(layers "In1.Cu" "In2.Cu")
		(hatch none 0.5)
		(connect_pads
			(clearance 0)
		)
		(min_thickness 0.25)
		(keepout
			(tracks not_allowed)
			(vias allowed)
			(pads allowed)
			(copperpour not_allowed)
			(footprints allowed)
		)
		(placement
			(enabled no)
			(sheetname "")
		)
		(fill yes
			(thermal_gap 0.5)
			(thermal_bridge_width 0.5)
			(island_removal_mode 0)
		)
		(polygon
			(pts
				(arc
					(start 289.605466 -274.02155)
					(mid 289.620345 -274.057471)
					(end 289.656266 -274.07235)
				)
				(arc
					(start 291.055806 -274.07235)
					(mid 291.091727 -274.057471)
					(end 291.106606 -274.02155)
				)
				(arc
					(start 291.106606 -273.61261)
					(mid 291.091727 -273.576689)
					(end 291.055806 -273.56181)
				)
				(arc
					(start 289.656266 -273.56181)
					(mid 289.620345 -273.576689)
					(end 289.605466 -273.61261)
				)
			)
		)
	)
	(zone
		(layers "In1.Cu" "In2.Cu")
		(hatch none 0.5)
		(connect_pads
			(clearance 0)
		)
		(min_thickness 0.25)
		(keepout
			(tracks not_allowed)
			(vias allowed)
			(pads allowed)
			(copperpour not_allowed)
			(footprints allowed)
		)
		(placement
			(enabled no)
			(sheetname "")
		)
		(fill yes
			(thermal_gap 0.5)
			(thermal_bridge_width 0.5)
			(island_removal_mode 0)
		)
		(polygon
			(pts
				(arc
					(start 285.505398 -232.371392)
					(mid 285.520277 -232.407313)
					(end 285.556198 -232.422192)
				)
				(arc
					(start 286.955738 -232.422192)
					(mid 286.991659 -232.407313)
					(end 287.006538 -232.371392)
				)
				(arc
					(start 287.006538 -231.962452)
					(mid 286.991659 -231.926531)
					(end 286.955738 -231.911652)
				)
				(arc
					(start 285.556198 -231.911652)
					(mid 285.520277 -231.926531)
					(end 285.505398 -231.962452)
				)
			)
		)
	)
	(zone
		(layers "In1.Cu" "In2.Cu")
		(hatch none 0.5)
		(connect_pads
			(clearance 0)
		)
		(min_thickness 0.25)
		(keepout
			(tracks not_allowed)
			(vias allowed)
			(pads allowed)
			(copperpour not_allowed)
			(footprints allowed)
		)
		(placement
			(enabled no)
			(sheetname "")
		)
		(fill yes
			(thermal_gap 0.5)
			(thermal_bridge_width 0.5)
			(island_removal_mode 0)
		)
		(polygon
			(pts
				(arc
					(start 207.425798 -234.921298)
					(mid 207.440677 -234.957219)
					(end 207.476598 -234.972098)
				)
				(arc
					(start 208.876138 -234.972098)
					(mid 208.912059 -234.957219)
					(end 208.926938 -234.921298)
				)
				(arc
					(start 208.926938 -234.512358)
					(mid 208.912059 -234.476437)
					(end 208.876138 -234.461558)
				)
				(arc
					(start 207.476598 -234.461558)
					(mid 207.440677 -234.476437)
					(end 207.425798 -234.512358)
				)
			)
		)
	)
	(zone
		(layers "In1.Cu" "In2.Cu")
		(hatch none 0.5)
		(connect_pads
			(clearance 0)
		)
		(min_thickness 0.25)
		(keepout
			(tracks not_allowed)
			(vias allowed)
			(pads allowed)
			(copperpour not_allowed)
			(footprints allowed)
		)
		(placement
			(enabled no)
			(sheetname "")
		)
		(fill yes
			(thermal_gap 0.5)
			(thermal_bridge_width 0.5)
			(island_removal_mode 0)
		)
		(polygon
			(pts
				(arc
					(start 270.417798 -207.721454)
					(mid 270.432677 -207.757375)
					(end 270.468598 -207.772254)
				)
				(arc
					(start 271.868138 -207.772254)
					(mid 271.904059 -207.757375)
					(end 271.918938 -207.721454)
				)
				(arc
					(start 271.918938 -207.312514)
					(mid 271.904059 -207.276593)
					(end 271.868138 -207.261714)
				)
				(arc
					(start 270.468598 -207.261714)
					(mid 270.432677 -207.276593)
					(end 270.417798 -207.312514)
				)
			)
		)
	)
	(zone
		(layers "In1.Cu" "In2.Cu")
		(hatch none 0.5)
		(connect_pads
			(clearance 0)
		)
		(min_thickness 0.25)
		(keepout
			(tracks not_allowed)
			(vias allowed)
			(pads allowed)
			(copperpour not_allowed)
			(footprints allowed)
		)
		(placement
			(enabled no)
			(sheetname "")
		)
		(fill yes
			(thermal_gap 0.5)
			(thermal_bridge_width 0.5)
			(island_removal_mode 0)
		)
		(polygon
			(pts
				(arc
					(start 304.693066 -206.871316)
					(mid 304.707945 -206.907237)
					(end 304.743866 -206.922116)
				)
				(arc
					(start 306.143406 -206.922116)
					(mid 306.179327 -206.907237)
					(end 306.194206 -206.871316)
				)
				(arc
					(start 306.194206 -206.462376)
					(mid 306.179327 -206.426455)
					(end 306.143406 -206.411576)
				)
				(arc
					(start 304.743866 -206.411576)
					(mid 304.707945 -206.426455)
					(end 304.693066 -206.462376)
				)
			)
		)
	)
	(zone
		(layers "In1.Cu" "In2.Cu")
		(hatch none 0.5)
		(connect_pads
			(clearance 0)
		)
		(min_thickness 0.25)
		(keepout
			(tracks not_allowed)
			(vias allowed)
			(pads allowed)
			(copperpour not_allowed)
			(footprints allowed)
		)
		(placement
			(enabled no)
			(sheetname "")
		)
		(fill yes
			(thermal_gap 0.5)
			(thermal_bridge_width 0.5)
			(island_removal_mode 0)
		)
		(polygon
			(pts
				(arc
					(start 277.961598 -209.421476)
					(mid 277.976477 -209.457397)
					(end 278.012398 -209.472276)
				)
				(arc
					(start 279.411938 -209.472276)
					(mid 279.447859 -209.457397)
					(end 279.462738 -209.421476)
				)
				(arc
					(start 279.462738 -209.012536)
					(mid 279.447859 -208.976615)
					(end 279.411938 -208.961736)
				)
				(arc
					(start 278.012398 -208.961736)
					(mid 277.976477 -208.976615)
					(end 277.961598 -209.012536)
				)
			)
		)
	)
	(zone
		(layers "In1.Cu" "In2.Cu")
		(hatch none 0.5)
		(connect_pads
			(clearance 0)
		)
		(min_thickness 0.25)
		(keepout
			(tracks not_allowed)
			(vias allowed)
			(pads allowed)
			(copperpour not_allowed)
			(footprints allowed)
		)
		(placement
			(enabled no)
			(sheetname "")
		)
		(fill yes
			(thermal_gap 0.5)
			(thermal_bridge_width 0.5)
			(island_removal_mode 0)
		)
		(polygon
			(pts
				(arc
					(start 11.490198 -251.921518)
					(mid 11.505077 -251.957439)
					(end 11.540998 -251.972318)
				)
				(arc
					(start 12.940538 -251.972318)
					(mid 12.976459 -251.957439)
					(end 12.991338 -251.921518)
				)
				(arc
					(start 12.991338 -251.512578)
					(mid 12.976459 -251.476657)
					(end 12.940538 -251.461778)
				)
				(arc
					(start 11.540998 -251.461778)
					(mid 11.505077 -251.476657)
					(end 11.490198 -251.512578)
				)
			)
		)
	)
	(zone
		(layers "In1.Cu" "In2.Cu")
		(hatch none 0.5)
		(connect_pads
			(clearance 0)
		)
		(min_thickness 0.25)
		(keepout
			(tracks not_allowed)
			(vias allowed)
			(pads allowed)
			(copperpour not_allowed)
			(footprints allowed)
		)
		(placement
			(enabled no)
			(sheetname "")
		)
		(fill yes
			(thermal_gap 0.5)
			(thermal_bridge_width 0.5)
			(island_removal_mode 0)
		)
		(polygon
			(pts
				(arc
					(start 308.136798 -310.571388)
					(mid 308.151677 -310.607309)
					(end 308.187598 -310.622188)
				)
				(arc
					(start 309.587138 -310.622188)
					(mid 309.623059 -310.607309)
					(end 309.637938 -310.571388)
				)
				(arc
					(start 309.637938 -310.162448)
					(mid 309.623059 -310.126527)
					(end 309.587138 -310.111648)
				)
				(arc
					(start 308.187598 -310.111648)
					(mid 308.151677 -310.126527)
					(end 308.136798 -310.162448)
				)
			)
		)
	)
	(zone
		(layers "In1.Cu" "In2.Cu")
		(hatch none 0.5)
		(connect_pads
			(clearance 0)
		)
		(min_thickness 0.25)
		(keepout
			(tracks not_allowed)
			(vias allowed)
			(pads allowed)
			(copperpour not_allowed)
			(footprints allowed)
		)
		(placement
			(enabled no)
			(sheetname "")
		)
		(fill yes
			(thermal_gap 0.5)
			(thermal_bridge_width 0.5)
			(island_removal_mode 0)
		)
		(polygon
			(pts
				(arc
					(start 255.330198 -293.571422)
					(mid 255.345077 -293.607343)
					(end 255.380998 -293.622222)
				)
				(arc
					(start 256.780538 -293.622222)
					(mid 256.816459 -293.607343)
					(end 256.831338 -293.571422)
				)
				(arc
					(start 256.831338 -293.162482)
					(mid 256.816459 -293.126561)
					(end 256.780538 -293.111682)
				)
				(arc
					(start 255.380998 -293.111682)
					(mid 255.345077 -293.126561)
					(end 255.330198 -293.162482)
				)
			)
		)
	)
	(zone
		(layers "In1.Cu" "In2.Cu")
		(hatch none 0.5)
		(connect_pads
			(clearance 0)
		)
		(min_thickness 0.25)
		(keepout
			(tracks not_allowed)
			(vias allowed)
			(pads allowed)
			(copperpour not_allowed)
			(footprints allowed)
		)
		(placement
			(enabled no)
			(sheetname "")
		)
		(fill yes
			(thermal_gap 0.5)
			(thermal_bridge_width 0.5)
			(island_removal_mode 0)
		)
		(polygon
			(pts
				(arc
					(start 19.033998 -248.521474)
					(mid 19.048877 -248.557395)
					(end 19.084798 -248.572274)
				)
				(arc
					(start 20.484338 -248.572274)
					(mid 20.520259 -248.557395)
					(end 20.535138 -248.521474)
				)
				(arc
					(start 20.535138 -248.112534)
					(mid 20.520259 -248.076613)
					(end 20.484338 -248.061734)
				)
				(arc
					(start 19.084798 -248.061734)
					(mid 19.048877 -248.076613)
					(end 19.033998 -248.112534)
				)
			)
		)
	)
	(zone
		(layers "In1.Cu" "In2.Cu")
		(hatch none 0.5)
		(connect_pads
			(clearance 0)
		)
		(min_thickness 0.25)
		(keepout
			(tracks not_allowed)
			(vias allowed)
			(pads allowed)
			(copperpour not_allowed)
			(footprints allowed)
		)
		(placement
			(enabled no)
			(sheetname "")
		)
		(fill yes
			(thermal_gap 0.5)
			(thermal_bridge_width 0.5)
			(island_removal_mode 0)
		)
		(polygon
			(pts
				(arc
					(start 64.296798 -274.871434)
					(mid 64.311677 -274.907355)
					(end 64.347598 -274.922234)
				)
				(arc
					(start 65.747138 -274.922234)
					(mid 65.783059 -274.907355)
					(end 65.797938 -274.871434)
				)
				(arc
					(start 65.797938 -274.462494)
					(mid 65.783059 -274.426573)
					(end 65.747138 -274.411694)
				)
				(arc
					(start 64.347598 -274.411694)
					(mid 64.311677 -274.426573)
					(end 64.296798 -274.462494)
				)
			)
		)
	)
	(zone
		(layers "In1.Cu" "In2.Cu")
		(hatch none 0.5)
		(connect_pads
			(clearance 0)
		)
		(min_thickness 0.25)
		(keepout
			(tracks not_allowed)
			(vias allowed)
			(pads allowed)
			(copperpour not_allowed)
			(footprints allowed)
		)
		(placement
			(enabled no)
			(sheetname "")
		)
		(fill yes
			(thermal_gap 0.5)
			(thermal_bridge_width 0.5)
			(island_removal_mode 0)
		)
		(polygon
			(pts
				(arc
					(start 443.721998 -206.021432)
					(mid 443.736877 -206.057353)
					(end 443.772798 -206.072232)
				)
				(arc
					(start 445.172338 -206.072232)
					(mid 445.208259 -206.057353)
					(end 445.223138 -206.021432)
				)
				(arc
					(start 445.223138 -205.612492)
					(mid 445.208259 -205.576571)
					(end 445.172338 -205.561692)
				)
				(arc
					(start 443.772798 -205.561692)
					(mid 443.736877 -205.576571)
					(end 443.721998 -205.612492)
				)
			)
		)
	)
	(zone
		(layers "In1.Cu" "In2.Cu")
		(hatch none 0.5)
		(connect_pads
			(clearance 0)
		)
		(min_thickness 0.25)
		(keepout
			(tracks not_allowed)
			(vias allowed)
			(pads allowed)
			(copperpour not_allowed)
			(footprints allowed)
		)
		(placement
			(enabled no)
			(sheetname "")
		)
		(fill yes
			(thermal_gap 0.5)
			(thermal_bridge_width 0.5)
			(island_removal_mode 0)
		)
		(polygon
			(pts
				(arc
					(start 270.417798 -243.421408)
					(mid 270.432677 -243.457329)
					(end 270.468598 -243.472208)
				)
				(arc
					(start 271.868138 -243.472208)
					(mid 271.904059 -243.457329)
					(end 271.918938 -243.421408)
				)
				(arc
					(start 271.918938 -243.012468)
					(mid 271.904059 -242.976547)
					(end 271.868138 -242.961668)
				)
				(arc
					(start 270.468598 -242.961668)
					(mid 270.432677 -242.976547)
					(end 270.417798 -243.012468)
				)
			)
		)
	)
	(zone
		(layers "In1.Cu" "In2.Cu")
		(hatch none 0.5)
		(connect_pads
			(clearance 0)
		)
		(min_thickness 0.25)
		(keepout
			(tracks not_allowed)
			(vias allowed)
			(pads allowed)
			(copperpour not_allowed)
			(footprints allowed)
		)
		(placement
			(enabled no)
			(sheetname "")
		)
		(fill yes
			(thermal_gap 0.5)
			(thermal_bridge_width 0.5)
			(island_removal_mode 0)
		)
		(polygon
			(pts
				(arc
					(start 285.505398 -198.37146)
					(mid 285.520277 -198.407381)
					(end 285.556198 -198.42226)
				)
				(arc
					(start 286.955738 -198.42226)
					(mid 286.991659 -198.407381)
					(end 287.006538 -198.37146)
				)
				(arc
					(start 287.006538 -197.96252)
					(mid 286.991659 -197.926599)
					(end 286.955738 -197.91172)
				)
				(arc
					(start 285.556198 -197.91172)
					(mid 285.520277 -197.926599)
					(end 285.505398 -197.96252)
				)
			)
		)
	)
	(zone
		(layers "In1.Cu" "In2.Cu")
		(hatch none 0.5)
		(connect_pads
			(clearance 0)
		)
		(min_thickness 0.25)
		(keepout
			(tracks not_allowed)
			(vias allowed)
			(pads allowed)
			(copperpour not_allowed)
			(footprints allowed)
		)
		(placement
			(enabled no)
			(sheetname "")
		)
		(fill yes
			(thermal_gap 0.5)
			(thermal_bridge_width 0.5)
			(island_removal_mode 0)
		)
		(polygon
			(pts
				(arc
					(start 177.250598 -302.071532)
					(mid 177.265477 -302.107453)
					(end 177.301398 -302.122332)
				)
				(arc
					(start 178.700938 -302.122332)
					(mid 178.736859 -302.107453)
					(end 178.751738 -302.071532)
				)
				(arc
					(start 178.751738 -301.662592)
					(mid 178.736859 -301.626671)
					(end 178.700938 -301.611792)
				)
				(arc
					(start 177.301398 -301.611792)
					(mid 177.265477 -301.626671)
					(end 177.250598 -301.662592)
				)
			)
		)
	)
	(zone
		(layers "In1.Cu" "In2.Cu")
		(hatch none 0.5)
		(connect_pads
			(clearance 0)
		)
		(min_thickness 0.25)
		(keepout
			(tracks not_allowed)
			(vias allowed)
			(pads allowed)
			(copperpour not_allowed)
			(footprints allowed)
		)
		(placement
			(enabled no)
			(sheetname "")
		)
		(fill yes
			(thermal_gap 0.5)
			(thermal_bridge_width 0.5)
			(island_removal_mode 0)
		)
		(polygon
			(pts
				(arc
					(start 22.47773 -316.521338)
					(mid 22.492609 -316.557259)
					(end 22.52853 -316.572138)
				)
				(arc
					(start 23.92807 -316.572138)
					(mid 23.963991 -316.557259)
					(end 23.97887 -316.521338)
				)
				(arc
					(start 23.97887 -316.112398)
					(mid 23.963991 -316.076477)
					(end 23.92807 -316.061598)
				)
				(arc
					(start 22.52853 -316.061598)
					(mid 22.492609 -316.076477)
					(end 22.47773 -316.112398)
				)
			)
		)
	)
	(zone
		(layers "In1.Cu" "In2.Cu")
		(hatch none 0.5)
		(connect_pads
			(clearance 0)
		)
		(min_thickness 0.25)
		(keepout
			(tracks not_allowed)
			(vias allowed)
			(pads allowed)
			(copperpour not_allowed)
			(footprints allowed)
		)
		(placement
			(enabled no)
			(sheetname "")
		)
		(fill yes
			(thermal_gap 0.5)
			(thermal_bridge_width 0.5)
			(island_removal_mode 0)
		)
		(polygon
			(pts
				(arc
					(start 30.02153 -293.571422)
					(mid 30.036409 -293.607343)
					(end 30.07233 -293.622222)
				)
				(arc
					(start 31.47187 -293.622222)
					(mid 31.507791 -293.607343)
					(end 31.52267 -293.571422)
				)
				(arc
					(start 31.52267 -293.162482)
					(mid 31.507791 -293.126561)
					(end 31.47187 -293.111682)
				)
				(arc
					(start 30.07233 -293.111682)
					(mid 30.036409 -293.126561)
					(end 30.02153 -293.162482)
				)
			)
		)
	)
	(zone
		(layers "In1.Cu" "In2.Cu")
		(hatch none 0.5)
		(connect_pads
			(clearance 0)
		)
		(min_thickness 0.25)
		(keepout
			(tracks not_allowed)
			(vias allowed)
			(pads allowed)
			(copperpour not_allowed)
			(footprints allowed)
		)
		(placement
			(enabled no)
			(sheetname "")
		)
		(fill yes
			(thermal_gap 0.5)
			(thermal_bridge_width 0.5)
			(island_removal_mode 0)
		)
		(polygon
			(pts
				(arc
					(start 421.090598 -275.721318)
					(mid 421.105477 -275.757239)
					(end 421.141398 -275.772118)
				)
				(arc
					(start 422.540938 -275.772118)
					(mid 422.576859 -275.757239)
					(end 422.591738 -275.721318)
				)
				(arc
					(start 422.591738 -275.312378)
					(mid 422.576859 -275.276457)
					(end 422.540938 -275.261578)
				)
				(arc
					(start 421.141398 -275.261578)
					(mid 421.105477 -275.276457)
					(end 421.090598 -275.312378)
				)
			)
		)
	)
	(zone
		(layers "In1.Cu" "In2.Cu")
		(hatch none 0.5)
		(connect_pads
			(clearance 0)
		)
		(min_thickness 0.25)
		(keepout
			(tracks not_allowed)
			(vias allowed)
			(pads allowed)
			(copperpour not_allowed)
			(footprints allowed)
		)
		(placement
			(enabled no)
			(sheetname "")
		)
		(fill yes
			(thermal_gap 0.5)
			(thermal_bridge_width 0.5)
			(island_removal_mode 0)
		)
		(polygon
			(pts
				(arc
					(start 207.425798 -195.821554)
					(mid 207.440677 -195.857475)
					(end 207.476598 -195.872354)
				)
				(arc
					(start 208.876138 -195.872354)
					(mid 208.912059 -195.857475)
					(end 208.926938 -195.821554)
				)
				(arc
					(start 208.926938 -195.412614)
					(mid 208.912059 -195.376693)
					(end 208.876138 -195.361814)
				)
				(arc
					(start 207.476598 -195.361814)
					(mid 207.440677 -195.376693)
					(end 207.425798 -195.412614)
				)
			)
		)
	)
	(zone
		(layers "In1.Cu" "In2.Cu")
		(hatch none 0.5)
		(connect_pads
			(clearance 0)
		)
		(min_thickness 0.25)
		(keepout
			(tracks not_allowed)
			(vias allowed)
			(pads allowed)
			(copperpour not_allowed)
			(footprints allowed)
		)
		(placement
			(enabled no)
			(sheetname "")
		)
		(fill yes
			(thermal_gap 0.5)
			(thermal_bridge_width 0.5)
			(island_removal_mode 0)
		)
		(polygon
			(pts
				(arc
					(start 421.090598 -268.071346)
					(mid 421.105477 -268.107267)
					(end 421.141398 -268.122146)
				)
				(arc
					(start 422.540938 -268.122146)
					(mid 422.576859 -268.107267)
					(end 422.591738 -268.071346)
				)
				(arc
					(start 422.591738 -267.662406)
					(mid 422.576859 -267.626485)
					(end 422.540938 -267.611606)
				)
				(arc
					(start 421.141398 -267.611606)
					(mid 421.105477 -267.626485)
					(end 421.090598 -267.662406)
				)
			)
		)
	)
	(zone
		(layers "In1.Cu" "In2.Cu")
		(hatch none 0.5)
		(connect_pads
			(clearance 0)
		)
		(min_thickness 0.25)
		(keepout
			(tracks not_allowed)
			(vias allowed)
			(pads allowed)
			(copperpour not_allowed)
			(footprints allowed)
		)
		(placement
			(enabled no)
			(sheetname "")
		)
		(fill yes
			(thermal_gap 0.5)
			(thermal_bridge_width 0.5)
			(island_removal_mode 0)
		)
		(polygon
			(pts
				(arc
					(start 304.693066 -211.121498)
					(mid 304.707945 -211.157419)
					(end 304.743866 -211.172298)
				)
				(arc
					(start 306.143406 -211.172298)
					(mid 306.179327 -211.157419)
					(end 306.194206 -211.121498)
				)
				(arc
					(start 306.194206 -210.712558)
					(mid 306.179327 -210.676637)
					(end 306.143406 -210.661758)
				)
				(arc
					(start 304.743866 -210.661758)
					(mid 304.707945 -210.676637)
					(end 304.693066 -210.712558)
				)
			)
		)
	)
	(zone
		(layers "In1.Cu" "In2.Cu")
		(hatch none 0.5)
		(connect_pads
			(clearance 0)
		)
		(min_thickness 0.25)
		(keepout
			(tracks not_allowed)
			(vias allowed)
			(pads allowed)
			(copperpour not_allowed)
			(footprints allowed)
		)
		(placement
			(enabled no)
			(sheetname "")
		)
		(fill yes
			(thermal_gap 0.5)
			(thermal_bridge_width 0.5)
			(island_removal_mode 0)
		)
		(polygon
			(pts
				(arc
					(start 300.592998 -224.72142)
					(mid 300.607877 -224.757341)
					(end 300.643798 -224.77222)
				)
				(arc
					(start 302.043338 -224.77222)
					(mid 302.079259 -224.757341)
					(end 302.094138 -224.72142)
				)
				(arc
					(start 302.094138 -224.31248)
					(mid 302.079259 -224.276559)
					(end 302.043338 -224.26168)
				)
				(arc
					(start 300.643798 -224.26168)
					(mid 300.607877 -224.276559)
					(end 300.592998 -224.31248)
				)
			)
		)
	)
	(zone
		(layers "In1.Cu" "In2.Cu")
		(hatch none 0.5)
		(connect_pads
			(clearance 0)
		)
		(min_thickness 0.25)
		(keepout
			(tracks not_allowed)
			(vias allowed)
			(pads allowed)
			(copperpour not_allowed)
			(footprints allowed)
		)
		(placement
			(enabled no)
			(sheetname "")
		)
		(fill yes
			(thermal_gap 0.5)
			(thermal_bridge_width 0.5)
			(island_removal_mode 0)
		)
		(polygon
			(pts
				(arc
					(start 266.974066 -228.121464)
					(mid 266.988945 -228.157385)
					(end 267.024866 -228.172264)
				)
				(arc
					(start 268.424406 -228.172264)
					(mid 268.460327 -228.157385)
					(end 268.475206 -228.121464)
				)
				(arc
					(start 268.475206 -227.712524)
					(mid 268.460327 -227.676603)
					(end 268.424406 -227.661724)
				)
				(arc
					(start 267.024866 -227.661724)
					(mid 266.988945 -227.676603)
					(end 266.974066 -227.712524)
				)
			)
		)
	)
	(zone
		(layers "In1.Cu" "In2.Cu")
		(hatch none 0.5)
		(connect_pads
			(clearance 0)
		)
		(min_thickness 0.25)
		(keepout
			(tracks not_allowed)
			(vias allowed)
			(pads allowed)
			(copperpour not_allowed)
			(footprints allowed)
		)
		(placement
			(enabled no)
			(sheetname "")
		)
		(fill yes
			(thermal_gap 0.5)
			(thermal_bridge_width 0.5)
			(island_removal_mode 0)
		)
		(polygon
			(pts
				(arc
					(start 45.10913 -307.171344)
					(mid 45.124009 -307.207265)
					(end 45.15993 -307.222144)
				)
				(arc
					(start 46.55947 -307.222144)
					(mid 46.595391 -307.207265)
					(end 46.61027 -307.171344)
				)
				(arc
					(start 46.61027 -306.762404)
					(mid 46.595391 -306.726483)
					(end 46.55947 -306.711604)
				)
				(arc
					(start 45.15993 -306.711604)
					(mid 45.124009 -306.726483)
					(end 45.10913 -306.762404)
				)
			)
		)
	)
	(zone
		(layers "In1.Cu" "In2.Cu")
		(hatch none 0.5)
		(connect_pads
			(clearance 0)
		)
		(min_thickness 0.25)
		(keepout
			(tracks not_allowed)
			(vias allowed)
			(pads allowed)
			(copperpour not_allowed)
			(footprints allowed)
		)
		(placement
			(enabled no)
			(sheetname "")
		)
		(fill yes
			(thermal_gap 0.5)
			(thermal_bridge_width 0.5)
			(island_removal_mode 0)
		)
		(polygon
			(pts
				(arc
					(start 274.517866 -220.471492)
					(mid 274.532745 -220.507413)
					(end 274.568666 -220.522292)
				)
				(arc
					(start 275.968206 -220.522292)
					(mid 276.004127 -220.507413)
					(end 276.019006 -220.471492)
				)
				(arc
					(start 276.019006 -220.062552)
					(mid 276.004127 -220.026631)
					(end 275.968206 -220.011752)
				)
				(arc
					(start 274.568666 -220.011752)
					(mid 274.532745 -220.026631)
					(end 274.517866 -220.062552)
				)
			)
		)
	)
	(zone
		(layers "In1.Cu" "In2.Cu")
		(hatch none 0.5)
		(connect_pads
			(clearance 0)
		)
		(min_thickness 0.25)
		(keepout
			(tracks not_allowed)
			(vias allowed)
			(pads allowed)
			(copperpour not_allowed)
			(footprints allowed)
		)
		(placement
			(enabled no)
			(sheetname "")
		)
		(fill yes
			(thermal_gap 0.5)
			(thermal_bridge_width 0.5)
			(island_removal_mode 0)
		)
		(polygon
			(pts
				(arc
					(start 293.049198 -297.82135)
					(mid 293.064077 -297.857271)
					(end 293.099998 -297.87215)
				)
				(arc
					(start 294.499538 -297.87215)
					(mid 294.535459 -297.857271)
					(end 294.550338 -297.82135)
				)
				(arc
					(start 294.550338 -297.41241)
					(mid 294.535459 -297.376489)
					(end 294.499538 -297.36161)
				)
				(arc
					(start 293.099998 -297.36161)
					(mid 293.064077 -297.376489)
					(end 293.049198 -297.41241)
				)
			)
		)
	)
	(zone
		(layers "In1.Cu" "In2.Cu")
		(hatch none 0.5)
		(connect_pads
			(clearance 0)
		)
		(min_thickness 0.25)
		(keepout
			(tracks not_allowed)
			(vias allowed)
			(pads allowed)
			(copperpour not_allowed)
			(footprints allowed)
		)
		(placement
			(enabled no)
			(sheetname "")
		)
		(fill yes
			(thermal_gap 0.5)
			(thermal_bridge_width 0.5)
			(island_removal_mode 0)
		)
		(polygon
			(pts
				(arc
					(start 26.577798 -246.821452)
					(mid 26.592677 -246.857373)
					(end 26.628598 -246.872252)
				)
				(arc
					(start 28.028138 -246.872252)
					(mid 28.064059 -246.857373)
					(end 28.078938 -246.821452)
				)
				(arc
					(start 28.078938 -246.412512)
					(mid 28.064059 -246.376591)
					(end 28.028138 -246.361712)
				)
				(arc
					(start 26.628598 -246.361712)
					(mid 26.592677 -246.376591)
					(end 26.577798 -246.412512)
				)
			)
		)
	)
	(zone
		(layers "In1.Cu" "In2.Cu")
		(hatch none 0.5)
		(connect_pads
			(clearance 0)
		)
		(min_thickness 0.25)
		(keepout
			(tracks not_allowed)
			(vias allowed)
			(pads allowed)
			(copperpour not_allowed)
			(footprints allowed)
		)
		(placement
			(enabled no)
			(sheetname "")
		)
		(fill yes
			(thermal_gap 0.5)
			(thermal_bridge_width 0.5)
			(island_removal_mode 0)
		)
		(polygon
			(pts
				(arc
					(start 37.56533 -297.82135)
					(mid 37.580209 -297.857271)
					(end 37.61613 -297.87215)
				)
				(arc
					(start 39.01567 -297.87215)
					(mid 39.051591 -297.857271)
					(end 39.06647 -297.82135)
				)
				(arc
					(start 39.06647 -297.41241)
					(mid 39.051591 -297.376489)
					(end 39.01567 -297.36161)
				)
				(arc
					(start 37.61613 -297.36161)
					(mid 37.580209 -297.376489)
					(end 37.56533 -297.41241)
				)
			)
		)
	)
	(zone
		(layers "In1.Cu" "In2.Cu")
		(hatch none 0.5)
		(connect_pads
			(clearance 0)
		)
		(min_thickness 0.25)
		(keepout
			(tracks not_allowed)
			(vias allowed)
			(pads allowed)
			(copperpour not_allowed)
			(footprints allowed)
		)
		(placement
			(enabled no)
			(sheetname "")
		)
		(fill yes
			(thermal_gap 0.5)
			(thermal_bridge_width 0.5)
			(island_removal_mode 0)
		)
		(polygon
			(pts
				(arc
					(start 45.10913 -219.621354)
					(mid 45.124009 -219.657275)
					(end 45.15993 -219.672154)
				)
				(arc
					(start 46.55947 -219.672154)
					(mid 46.595391 -219.657275)
					(end 46.61027 -219.621354)
				)
				(arc
					(start 46.61027 -219.212414)
					(mid 46.595391 -219.176493)
					(end 46.55947 -219.161614)
				)
				(arc
					(start 45.15993 -219.161614)
					(mid 45.124009 -219.176493)
					(end 45.10913 -219.212414)
				)
			)
		)
	)
	(zone
		(layers "In1.Cu" "In2.Cu")
		(hatch none 0.5)
		(connect_pads
			(clearance 0)
		)
		(min_thickness 0.25)
		(keepout
			(tracks not_allowed)
			(vias allowed)
			(pads allowed)
			(copperpour not_allowed)
			(footprints allowed)
		)
		(placement
			(enabled no)
			(sheetname "")
		)
		(fill yes
			(thermal_gap 0.5)
			(thermal_bridge_width 0.5)
			(island_removal_mode 0)
		)
		(polygon
			(pts
				(arc
					(start 451.265798 -207.721454)
					(mid 451.280677 -207.757375)
					(end 451.316598 -207.772254)
				)
				(arc
					(start 452.716138 -207.772254)
					(mid 452.752059 -207.757375)
					(end 452.766938 -207.721454)
				)
				(arc
					(start 452.766938 -207.312514)
					(mid 452.752059 -207.276593)
					(end 452.716138 -207.261714)
				)
				(arc
					(start 451.316598 -207.261714)
					(mid 451.280677 -207.276593)
					(end 451.265798 -207.312514)
				)
			)
		)
	)
	(zone
		(layers "In1.Cu" "In2.Cu")
		(hatch none 0.5)
		(connect_pads
			(clearance 0)
		)
		(min_thickness 0.25)
		(keepout
			(tracks not_allowed)
			(vias allowed)
			(pads allowed)
			(copperpour not_allowed)
			(footprints allowed)
		)
		(placement
			(enabled no)
			(sheetname "")
		)
		(fill yes
			(thermal_gap 0.5)
			(thermal_bridge_width 0.5)
			(island_removal_mode 0)
		)
		(polygon
			(pts
				(arc
					(start 184.794398 -218.77147)
					(mid 184.809277 -218.807391)
					(end 184.845198 -218.82227)
				)
				(arc
					(start 186.244738 -218.82227)
					(mid 186.280659 -218.807391)
					(end 186.295538 -218.77147)
				)
				(arc
					(start 186.295538 -218.36253)
					(mid 186.280659 -218.326609)
					(end 186.244738 -218.31173)
				)
				(arc
					(start 184.845198 -218.31173)
					(mid 184.809277 -218.326609)
					(end 184.794398 -218.36253)
				)
			)
		)
	)
	(zone
		(layers "In1.Cu" "In2.Cu")
		(hatch none 0.5)
		(connect_pads
			(clearance 0)
		)
		(min_thickness 0.25)
		(keepout
			(tracks not_allowed)
			(vias allowed)
			(pads allowed)
			(copperpour not_allowed)
			(footprints allowed)
		)
		(placement
			(enabled no)
			(sheetname "")
		)
		(fill yes
			(thermal_gap 0.5)
			(thermal_bridge_width 0.5)
			(island_removal_mode 0)
		)
		(polygon
			(pts
				(arc
					(start 436.178198 -282.521406)
					(mid 436.193077 -282.557327)
					(end 436.228998 -282.572206)
				)
				(arc
					(start 437.628538 -282.572206)
					(mid 437.664459 -282.557327)
					(end 437.679338 -282.521406)
				)
				(arc
					(start 437.679338 -282.112466)
					(mid 437.664459 -282.076545)
					(end 437.628538 -282.061666)
				)
				(arc
					(start 436.228998 -282.061666)
					(mid 436.193077 -282.076545)
					(end 436.178198 -282.112466)
				)
			)
		)
	)
	(zone
		(layers "In1.Cu" "In2.Cu")
		(hatch none 0.5)
		(connect_pads
			(clearance 0)
		)
		(min_thickness 0.25)
		(keepout
			(tracks not_allowed)
			(vias allowed)
			(pads allowed)
			(copperpour not_allowed)
			(footprints allowed)
		)
		(placement
			(enabled no)
			(sheetname "")
		)
		(fill yes
			(thermal_gap 0.5)
			(thermal_bridge_width 0.5)
			(island_removal_mode 0)
		)
		(polygon
			(pts
				(arc
					(start 180.69433 -313.121294)
					(mid 180.709209 -313.157215)
					(end 180.74513 -313.172094)
				)
				(arc
					(start 182.14467 -313.172094)
					(mid 182.180591 -313.157215)
					(end 182.19547 -313.121294)
				)
				(arc
					(start 182.19547 -312.712354)
					(mid 182.180591 -312.676433)
					(end 182.14467 -312.661554)
				)
				(arc
					(start 180.74513 -312.661554)
					(mid 180.709209 -312.676433)
					(end 180.69433 -312.712354)
				)
			)
		)
	)
	(zone
		(layers "In1.Cu" "In2.Cu")
		(hatch none 0.5)
		(connect_pads
			(clearance 0)
		)
		(min_thickness 0.25)
		(keepout
			(tracks not_allowed)
			(vias allowed)
			(pads allowed)
			(copperpour not_allowed)
			(footprints allowed)
		)
		(placement
			(enabled no)
			(sheetname "")
		)
		(fill yes
			(thermal_gap 0.5)
			(thermal_bridge_width 0.5)
			(island_removal_mode 0)
		)
		(polygon
			(pts
				(arc
					(start 266.974066 -227.271326)
					(mid 266.988945 -227.307247)
					(end 267.024866 -227.322126)
				)
				(arc
					(start 268.424406 -227.322126)
					(mid 268.460327 -227.307247)
					(end 268.475206 -227.271326)
				)
				(arc
					(start 268.475206 -226.862386)
					(mid 268.460327 -226.826465)
					(end 268.424406 -226.811586)
				)
				(arc
					(start 267.024866 -226.811586)
					(mid 266.988945 -226.826465)
					(end 266.974066 -226.862386)
				)
			)
		)
	)
	(zone
		(layers "In1.Cu" "In2.Cu")
		(hatch none 0.5)
		(connect_pads
			(clearance 0)
		)
		(min_thickness 0.25)
		(keepout
			(tracks not_allowed)
			(vias allowed)
			(pads allowed)
			(copperpour not_allowed)
			(footprints allowed)
		)
		(placement
			(enabled no)
			(sheetname "")
		)
		(fill yes
			(thermal_gap 0.5)
			(thermal_bridge_width 0.5)
			(island_removal_mode 0)
		)
		(polygon
			(pts
				(arc
					(start 458.809598 -228.971348)
					(mid 458.824477 -229.007269)
					(end 458.860398 -229.022148)
				)
				(arc
					(start 460.259938 -229.022148)
					(mid 460.295859 -229.007269)
					(end 460.310738 -228.971348)
				)
				(arc
					(start 460.310738 -228.562408)
					(mid 460.295859 -228.526487)
					(end 460.259938 -228.511608)
				)
				(arc
					(start 458.860398 -228.511608)
					(mid 458.824477 -228.526487)
					(end 458.809598 -228.562408)
				)
			)
		)
	)
	(zone
		(layers "In1.Cu" "In2.Cu")
		(hatch none 0.5)
		(connect_pads
			(clearance 0)
		)
		(min_thickness 0.25)
		(keepout
			(tracks not_allowed)
			(vias allowed)
			(pads allowed)
			(copperpour not_allowed)
			(footprints allowed)
		)
		(placement
			(enabled no)
			(sheetname "")
		)
		(fill yes
			(thermal_gap 0.5)
			(thermal_bridge_width 0.5)
			(island_removal_mode 0)
		)
		(polygon
			(pts
				(arc
					(start 11.490198 -312.27141)
					(mid 11.505077 -312.307331)
					(end 11.540998 -312.32221)
				)
				(arc
					(start 12.940538 -312.32221)
					(mid 12.976459 -312.307331)
					(end 12.991338 -312.27141)
				)
				(arc
					(start 12.991338 -311.86247)
					(mid 12.976459 -311.826549)
					(end 12.940538 -311.81167)
				)
				(arc
					(start 11.540998 -311.81167)
					(mid 11.505077 -311.826549)
					(end 11.490198 -311.86247)
				)
			)
		)
	)
	(zone
		(layers "In1.Cu" "In2.Cu")
		(hatch none 0.5)
		(connect_pads
			(clearance 0)
		)
		(min_thickness 0.25)
		(keepout
			(tracks not_allowed)
			(vias allowed)
			(pads allowed)
			(copperpour not_allowed)
			(footprints allowed)
		)
		(placement
			(enabled no)
			(sheetname "")
		)
		(fill yes
			(thermal_gap 0.5)
			(thermal_bridge_width 0.5)
			(island_removal_mode 0)
		)
		(polygon
			(pts
				(arc
					(start 52.65293 -279.121362)
					(mid 52.667809 -279.157283)
					(end 52.70373 -279.172162)
				)
				(arc
					(start 54.10327 -279.172162)
					(mid 54.139191 -279.157283)
					(end 54.15407 -279.121362)
				)
				(arc
					(start 54.15407 -278.712422)
					(mid 54.139191 -278.676501)
					(end 54.10327 -278.661622)
				)
				(arc
					(start 52.70373 -278.661622)
					(mid 52.667809 -278.676501)
					(end 52.65293 -278.712422)
				)
			)
		)
	)
	(zone
		(layers "In1.Cu" "In2.Cu")
		(hatch none 0.5)
		(connect_pads
			(clearance 0)
		)
		(min_thickness 0.25)
		(keepout
			(tracks not_allowed)
			(vias allowed)
			(pads allowed)
			(copperpour not_allowed)
			(footprints allowed)
		)
		(placement
			(enabled no)
			(sheetname "")
		)
		(fill yes
			(thermal_gap 0.5)
			(thermal_bridge_width 0.5)
			(island_removal_mode 0)
		)
		(polygon
			(pts
				(arc
					(start 11.490198 -259.57149)
					(mid 11.505077 -259.607411)
					(end 11.540998 -259.62229)
				)
				(arc
					(start 12.940538 -259.62229)
					(mid 12.976459 -259.607411)
					(end 12.991338 -259.57149)
				)
				(arc
					(start 12.991338 -259.16255)
					(mid 12.976459 -259.126629)
					(end 12.940538 -259.11175)
				)
				(arc
					(start 11.540998 -259.11175)
					(mid 11.505077 -259.126629)
					(end 11.490198 -259.16255)
				)
			)
		)
	)
	(zone
		(layers "In1.Cu" "In2.Cu")
		(hatch none 0.5)
		(connect_pads
			(clearance 0)
		)
		(min_thickness 0.25)
		(keepout
			(tracks not_allowed)
			(vias allowed)
			(pads allowed)
			(copperpour not_allowed)
			(footprints allowed)
		)
		(placement
			(enabled no)
			(sheetname "")
		)
		(fill yes
			(thermal_gap 0.5)
			(thermal_bridge_width 0.5)
			(island_removal_mode 0)
		)
		(polygon
			(pts
				(arc
					(start 207.425798 -296.971466)
					(mid 207.440677 -297.007387)
					(end 207.476598 -297.022266)
				)
				(arc
					(start 208.876138 -297.022266)
					(mid 208.912059 -297.007387)
					(end 208.926938 -296.971466)
				)
				(arc
					(start 208.926938 -296.562526)
					(mid 208.912059 -296.526605)
					(end 208.876138 -296.511726)
				)
				(arc
					(start 207.476598 -296.511726)
					(mid 207.440677 -296.526605)
					(end 207.425798 -296.562526)
				)
			)
		)
	)
	(zone
		(layers "In1.Cu" "In2.Cu")
		(hatch none 0.5)
		(connect_pads
			(clearance 0)
		)
		(min_thickness 0.25)
		(keepout
			(tracks not_allowed)
			(vias allowed)
			(pads allowed)
			(copperpour not_allowed)
			(footprints allowed)
		)
		(placement
			(enabled no)
			(sheetname "")
		)
		(fill yes
			(thermal_gap 0.5)
			(thermal_bridge_width 0.5)
			(island_removal_mode 0)
		)
		(polygon
			(pts
				(arc
					(start 19.033998 -237.471458)
					(mid 19.048877 -237.507379)
					(end 19.084798 -237.522258)
				)
				(arc
					(start 20.484338 -237.522258)
					(mid 20.520259 -237.507379)
					(end 20.535138 -237.471458)
				)
				(arc
					(start 20.535138 -237.062518)
					(mid 20.520259 -237.026597)
					(end 20.484338 -237.011718)
				)
				(arc
					(start 19.084798 -237.011718)
					(mid 19.048877 -237.026597)
					(end 19.033998 -237.062518)
				)
			)
		)
	)
	(zone
		(layers "In1.Cu" "In2.Cu")
		(hatch none 0.5)
		(connect_pads
			(clearance 0)
		)
		(min_thickness 0.25)
		(keepout
			(tracks not_allowed)
			(vias allowed)
			(pads allowed)
			(copperpour not_allowed)
			(footprints allowed)
		)
		(placement
			(enabled no)
			(sheetname "")
		)
		(fill yes
			(thermal_gap 0.5)
			(thermal_bridge_width 0.5)
			(island_removal_mode 0)
		)
		(polygon
			(pts
				(arc
					(start 274.517866 -300.37151)
					(mid 274.532745 -300.407431)
					(end 274.568666 -300.42231)
				)
				(arc
					(start 275.968206 -300.42231)
					(mid 276.004127 -300.407431)
					(end 276.019006 -300.37151)
				)
				(arc
					(start 276.019006 -299.96257)
					(mid 276.004127 -299.926649)
					(end 275.968206 -299.91177)
				)
				(arc
					(start 274.568666 -299.91177)
					(mid 274.532745 -299.926649)
					(end 274.517866 -299.96257)
				)
			)
		)
	)
	(zone
		(layers "In1.Cu" "In2.Cu")
		(hatch none 0.5)
		(connect_pads
			(clearance 0)
		)
		(min_thickness 0.25)
		(keepout
			(tracks not_allowed)
			(vias allowed)
			(pads allowed)
			(copperpour not_allowed)
			(footprints allowed)
		)
		(placement
			(enabled no)
			(sheetname "")
		)
		(fill yes
			(thermal_gap 0.5)
			(thermal_bridge_width 0.5)
			(island_removal_mode 0)
		)
		(polygon
			(pts
				(arc
					(start 34.121598 -274.02155)
					(mid 34.136477 -274.057471)
					(end 34.172398 -274.07235)
				)
				(arc
					(start 35.571938 -274.07235)
					(mid 35.607859 -274.057471)
					(end 35.622738 -274.02155)
				)
				(arc
					(start 35.622738 -273.61261)
					(mid 35.607859 -273.576689)
					(end 35.571938 -273.56181)
				)
				(arc
					(start 34.172398 -273.56181)
					(mid 34.136477 -273.576689)
					(end 34.121598 -273.61261)
				)
			)
		)
	)
	(zone
		(layers "In1.Cu" "In2.Cu")
		(hatch none 0.5)
		(connect_pads
			(clearance 0)
		)
		(min_thickness 0.25)
		(keepout
			(tracks not_allowed)
			(vias allowed)
			(pads allowed)
			(copperpour not_allowed)
			(footprints allowed)
		)
		(placement
			(enabled no)
			(sheetname "")
		)
		(fill yes
			(thermal_gap 0.5)
			(thermal_bridge_width 0.5)
			(island_removal_mode 0)
		)
		(polygon
			(pts
				(arc
					(start 45.10913 -286.771334)
					(mid 45.124009 -286.807255)
					(end 45.15993 -286.822134)
				)
				(arc
					(start 46.55947 -286.822134)
					(mid 46.595391 -286.807255)
					(end 46.61027 -286.771334)
				)
				(arc
					(start 46.61027 -286.362394)
					(mid 46.595391 -286.326473)
					(end 46.55947 -286.311594)
				)
				(arc
					(start 45.15993 -286.311594)
					(mid 45.124009 -286.326473)
					(end 45.10913 -286.362394)
				)
			)
		)
	)
	(zone
		(layers "In1.Cu" "In2.Cu")
		(hatch none 0.5)
		(connect_pads
			(clearance 0)
		)
		(min_thickness 0.25)
		(keepout
			(tracks not_allowed)
			(vias allowed)
			(pads allowed)
			(copperpour not_allowed)
			(footprints allowed)
		)
		(placement
			(enabled no)
			(sheetname "")
		)
		(fill yes
			(thermal_gap 0.5)
			(thermal_bridge_width 0.5)
			(island_removal_mode 0)
		)
		(polygon
			(pts
				(arc
					(start 41.665398 -209.421476)
					(mid 41.680277 -209.457397)
					(end 41.716198 -209.472276)
				)
				(arc
					(start 43.115738 -209.472276)
					(mid 43.151659 -209.457397)
					(end 43.166538 -209.421476)
				)
				(arc
					(start 43.166538 -209.012536)
					(mid 43.151659 -208.976615)
					(end 43.115738 -208.961736)
				)
				(arc
					(start 41.716198 -208.961736)
					(mid 41.680277 -208.976615)
					(end 41.665398 -209.012536)
				)
			)
		)
	)
	(zone
		(layers "In1.Cu" "In2.Cu")
		(hatch none 0.5)
		(connect_pads
			(clearance 0)
		)
		(min_thickness 0.25)
		(keepout
			(tracks not_allowed)
			(vias allowed)
			(pads allowed)
			(copperpour not_allowed)
			(footprints allowed)
		)
		(placement
			(enabled no)
			(sheetname "")
		)
		(fill yes
			(thermal_gap 0.5)
			(thermal_bridge_width 0.5)
			(island_removal_mode 0)
		)
		(polygon
			(pts
				(arc
					(start 180.69433 -268.071346)
					(mid 180.709209 -268.107267)
					(end 180.74513 -268.122146)
				)
				(arc
					(start 182.14467 -268.122146)
					(mid 182.180591 -268.107267)
					(end 182.19547 -268.071346)
				)
				(arc
					(start 182.19547 -267.662406)
					(mid 182.180591 -267.626485)
					(end 182.14467 -267.611606)
				)
				(arc
					(start 180.74513 -267.611606)
					(mid 180.709209 -267.626485)
					(end 180.69433 -267.662406)
				)
			)
		)
	)
	(zone
		(layers "In1.Cu" "In2.Cu")
		(hatch none 0.5)
		(connect_pads
			(clearance 0)
		)
		(min_thickness 0.25)
		(keepout
			(tracks not_allowed)
			(vias allowed)
			(pads allowed)
			(copperpour not_allowed)
			(footprints allowed)
		)
		(placement
			(enabled no)
			(sheetname "")
		)
		(fill yes
			(thermal_gap 0.5)
			(thermal_bridge_width 0.5)
			(island_removal_mode 0)
		)
		(polygon
			(pts
				(arc
					(start 451.265798 -314.821316)
					(mid 451.280677 -314.857237)
					(end 451.316598 -314.872116)
				)
				(arc
					(start 452.716138 -314.872116)
					(mid 452.752059 -314.857237)
					(end 452.766938 -314.821316)
				)
				(arc
					(start 452.766938 -314.412376)
					(mid 452.752059 -314.376455)
					(end 452.716138 -314.361576)
				)
				(arc
					(start 451.316598 -314.361576)
					(mid 451.280677 -314.376455)
					(end 451.265798 -314.412376)
				)
			)
		)
	)
	(zone
		(layers "In1.Cu" "In2.Cu")
		(hatch none 0.5)
		(connect_pads
			(clearance 0)
		)
		(min_thickness 0.25)
		(keepout
			(tracks not_allowed)
			(vias allowed)
			(pads allowed)
			(copperpour not_allowed)
			(footprints allowed)
		)
		(placement
			(enabled no)
			(sheetname "")
		)
		(fill yes
			(thermal_gap 0.5)
			(thermal_bridge_width 0.5)
			(island_removal_mode 0)
		)
		(polygon
			(pts
				(arc
					(start 289.605466 -274.871434)
					(mid 289.620345 -274.907355)
					(end 289.656266 -274.922234)
				)
				(arc
					(start 291.055806 -274.922234)
					(mid 291.091727 -274.907355)
					(end 291.106606 -274.871434)
				)
				(arc
					(start 291.106606 -274.462494)
					(mid 291.091727 -274.426573)
					(end 291.055806 -274.411694)
				)
				(arc
					(start 289.656266 -274.411694)
					(mid 289.620345 -274.426573)
					(end 289.605466 -274.462494)
				)
			)
		)
	)
	(zone
		(layers "In1.Cu" "In2.Cu")
		(hatch none 0.5)
		(connect_pads
			(clearance 0)
		)
		(min_thickness 0.25)
		(keepout
			(tracks not_allowed)
			(vias allowed)
			(pads allowed)
			(copperpour not_allowed)
			(footprints allowed)
		)
		(placement
			(enabled no)
			(sheetname "")
		)
		(fill yes
			(thermal_gap 0.5)
			(thermal_bridge_width 0.5)
			(island_removal_mode 0)
		)
		(polygon
			(pts
				(arc
					(start 210.86953 -284.221428)
					(mid 210.884409 -284.257349)
					(end 210.92033 -284.272228)
				)
				(arc
					(start 212.31987 -284.272228)
					(mid 212.355791 -284.257349)
					(end 212.37067 -284.221428)
				)
				(arc
					(start 212.37067 -283.812488)
					(mid 212.355791 -283.776567)
					(end 212.31987 -283.761688)
				)
				(arc
					(start 210.92033 -283.761688)
					(mid 210.884409 -283.776567)
					(end 210.86953 -283.812488)
				)
			)
		)
	)
	(zone
		(layers "In1.Cu" "In2.Cu")
		(hatch none 0.5)
		(connect_pads
			(clearance 0)
		)
		(min_thickness 0.25)
		(keepout
			(tracks not_allowed)
			(vias allowed)
			(pads allowed)
			(copperpour not_allowed)
			(footprints allowed)
		)
		(placement
			(enabled no)
			(sheetname "")
		)
		(fill yes
			(thermal_gap 0.5)
			(thermal_bridge_width 0.5)
			(island_removal_mode 0)
		)
		(polygon
			(pts
				(arc
					(start 49.209198 -197.521322)
					(mid 49.224077 -197.557243)
					(end 49.259998 -197.572122)
				)
				(arc
					(start 50.659538 -197.572122)
					(mid 50.695459 -197.557243)
					(end 50.710338 -197.521322)
				)
				(arc
					(start 50.710338 -197.112382)
					(mid 50.695459 -197.076461)
					(end 50.659538 -197.061582)
				)
				(arc
					(start 49.259998 -197.061582)
					(mid 49.224077 -197.076461)
					(end 49.209198 -197.112382)
				)
			)
		)
	)
	(zone
		(layers "In1.Cu" "In2.Cu")
		(hatch none 0.5)
		(connect_pads
			(clearance 0)
		)
		(min_thickness 0.25)
		(keepout
			(tracks not_allowed)
			(vias allowed)
			(pads allowed)
			(copperpour not_allowed)
			(footprints allowed)
		)
		(placement
			(enabled no)
			(sheetname "")
		)
		(fill yes
			(thermal_gap 0.5)
			(thermal_bridge_width 0.5)
			(island_removal_mode 0)
		)
		(polygon
			(pts
				(arc
					(start 304.693066 -315.671454)
					(mid 304.707945 -315.707375)
					(end 304.743866 -315.722254)
				)
				(arc
					(start 306.143406 -315.722254)
					(mid 306.179327 -315.707375)
					(end 306.194206 -315.671454)
				)
				(arc
					(start 306.194206 -315.262514)
					(mid 306.179327 -315.226593)
					(end 306.143406 -315.211714)
				)
				(arc
					(start 304.743866 -315.211714)
					(mid 304.707945 -315.226593)
					(end 304.693066 -315.262514)
				)
			)
		)
	)
	(zone
		(layers "In1.Cu" "In2.Cu")
		(hatch none 0.5)
		(connect_pads
			(clearance 0)
		)
		(min_thickness 0.25)
		(keepout
			(tracks not_allowed)
			(vias allowed)
			(pads allowed)
			(copperpour not_allowed)
			(footprints allowed)
		)
		(placement
			(enabled no)
			(sheetname "")
		)
		(fill yes
			(thermal_gap 0.5)
			(thermal_bridge_width 0.5)
			(island_removal_mode 0)
		)
		(polygon
			(pts
				(arc
					(start 255.330198 -209.421476)
					(mid 255.345077 -209.457397)
					(end 255.380998 -209.472276)
				)
				(arc
					(start 256.780538 -209.472276)
					(mid 256.816459 -209.457397)
					(end 256.831338 -209.421476)
				)
				(arc
					(start 256.831338 -209.012536)
					(mid 256.816459 -208.976615)
					(end 256.780538 -208.961736)
				)
				(arc
					(start 255.380998 -208.961736)
					(mid 255.345077 -208.976615)
					(end 255.330198 -209.012536)
				)
			)
		)
	)
	(zone
		(layers "In1.Cu" "In2.Cu")
		(hatch none 0.5)
		(connect_pads
			(clearance 0)
		)
		(min_thickness 0.25)
		(keepout
			(tracks not_allowed)
			(vias allowed)
			(pads allowed)
			(copperpour not_allowed)
			(footprints allowed)
		)
		(placement
			(enabled no)
			(sheetname "")
		)
		(fill yes
			(thermal_gap 0.5)
			(thermal_bridge_width 0.5)
			(island_removal_mode 0)
		)
		(polygon
			(pts
				(arc
					(start 274.517866 -216.22131)
					(mid 274.532745 -216.257231)
					(end 274.568666 -216.27211)
				)
				(arc
					(start 275.968206 -216.27211)
					(mid 276.004127 -216.257231)
					(end 276.019006 -216.22131)
				)
				(arc
					(start 276.019006 -215.81237)
					(mid 276.004127 -215.776449)
					(end 275.968206 -215.76157)
				)
				(arc
					(start 274.568666 -215.76157)
					(mid 274.532745 -215.776449)
					(end 274.517866 -215.81237)
				)
			)
		)
	)
	(zone
		(layers "In1.Cu" "In2.Cu")
		(hatch none 0.5)
		(connect_pads
			(clearance 0)
		)
		(min_thickness 0.25)
		(keepout
			(tracks not_allowed)
			(vias allowed)
			(pads allowed)
			(copperpour not_allowed)
			(footprints allowed)
		)
		(placement
			(enabled no)
			(sheetname "")
		)
		(fill yes
			(thermal_gap 0.5)
			(thermal_bridge_width 0.5)
			(island_removal_mode 0)
		)
		(polygon
			(pts
				(arc
					(start 300.592998 -266.371324)
					(mid 300.607877 -266.407245)
					(end 300.643798 -266.422124)
				)
				(arc
					(start 302.043338 -266.422124)
					(mid 302.079259 -266.407245)
					(end 302.094138 -266.371324)
				)
				(arc
					(start 302.094138 -265.962384)
					(mid 302.079259 -265.926463)
					(end 302.043338 -265.911584)
				)
				(arc
					(start 300.643798 -265.911584)
					(mid 300.607877 -265.926463)
					(end 300.592998 -265.962384)
				)
			)
		)
	)
	(zone
		(layers "In1.Cu" "In2.Cu")
		(hatch none 0.5)
		(connect_pads
			(clearance 0)
		)
		(min_thickness 0.25)
		(keepout
			(tracks not_allowed)
			(vias allowed)
			(pads allowed)
			(copperpour not_allowed)
			(footprints allowed)
		)
		(placement
			(enabled no)
			(sheetname "")
		)
		(fill yes
			(thermal_gap 0.5)
			(thermal_bridge_width 0.5)
			(island_removal_mode 0)
		)
		(polygon
			(pts
				(arc
					(start 34.121598 -205.171548)
					(mid 34.136477 -205.207469)
					(end 34.172398 -205.222348)
				)
				(arc
					(start 35.571938 -205.222348)
					(mid 35.607859 -205.207469)
					(end 35.622738 -205.171548)
				)
				(arc
					(start 35.622738 -204.762608)
					(mid 35.607859 -204.726687)
					(end 35.571938 -204.711808)
				)
				(arc
					(start 34.172398 -204.711808)
					(mid 34.136477 -204.726687)
					(end 34.121598 -204.762608)
				)
			)
		)
	)
	(zone
		(layers "In1.Cu" "In2.Cu")
		(hatch none 0.5)
		(connect_pads
			(clearance 0)
		)
		(min_thickness 0.25)
		(keepout
			(tracks not_allowed)
			(vias allowed)
			(pads allowed)
			(copperpour not_allowed)
			(footprints allowed)
		)
		(placement
			(enabled no)
			(sheetname "")
		)
		(fill yes
			(thermal_gap 0.5)
			(thermal_bridge_width 0.5)
			(island_removal_mode 0)
		)
		(polygon
			(pts
				(arc
					(start 277.961598 -251.07138)
					(mid 277.976477 -251.107301)
					(end 278.012398 -251.12218)
				)
				(arc
					(start 279.411938 -251.12218)
					(mid 279.447859 -251.107301)
					(end 279.462738 -251.07138)
				)
				(arc
					(start 279.462738 -250.66244)
					(mid 279.447859 -250.626519)
					(end 279.411938 -250.61164)
				)
				(arc
					(start 278.012398 -250.61164)
					(mid 277.976477 -250.626519)
					(end 277.961598 -250.66244)
				)
			)
		)
	)
	(zone
		(layers "In1.Cu" "In2.Cu")
		(hatch none 0.5)
		(connect_pads
			(clearance 0)
		)
		(min_thickness 0.25)
		(keepout
			(tracks not_allowed)
			(vias allowed)
			(pads allowed)
			(copperpour not_allowed)
			(footprints allowed)
		)
		(placement
			(enabled no)
			(sheetname "")
		)
		(fill yes
			(thermal_gap 0.5)
			(thermal_bridge_width 0.5)
			(island_removal_mode 0)
		)
		(polygon
			(pts
				(arc
					(start 277.961598 -204.32141)
					(mid 277.976477 -204.357331)
					(end 278.012398 -204.37221)
				)
				(arc
					(start 279.411938 -204.37221)
					(mid 279.447859 -204.357331)
					(end 279.462738 -204.32141)
				)
				(arc
					(start 279.462738 -203.91247)
					(mid 279.447859 -203.876549)
					(end 279.411938 -203.86167)
				)
				(arc
					(start 278.012398 -203.86167)
					(mid 277.976477 -203.876549)
					(end 277.961598 -203.91247)
				)
			)
		)
	)
	(zone
		(layers "In1.Cu" "In2.Cu")
		(hatch none 0.5)
		(connect_pads
			(clearance 0)
		)
		(min_thickness 0.25)
		(keepout
			(tracks not_allowed)
			(vias allowed)
			(pads allowed)
			(copperpour not_allowed)
			(footprints allowed)
		)
		(placement
			(enabled no)
			(sheetname "")
		)
		(fill yes
			(thermal_gap 0.5)
			(thermal_bridge_width 0.5)
			(island_removal_mode 0)
		)
		(polygon
			(pts
				(arc
					(start 255.330198 -224.72142)
					(mid 255.345077 -224.757341)
					(end 255.380998 -224.77222)
				)
				(arc
					(start 256.780538 -224.77222)
					(mid 256.816459 -224.757341)
					(end 256.831338 -224.72142)
				)
				(arc
					(start 256.831338 -224.31248)
					(mid 256.816459 -224.276559)
					(end 256.780538 -224.26168)
				)
				(arc
					(start 255.380998 -224.26168)
					(mid 255.345077 -224.276559)
					(end 255.330198 -224.31248)
				)
			)
		)
	)
	(zone
		(layers "In1.Cu" "In2.Cu")
		(hatch none 0.5)
		(connect_pads
			(clearance 0)
		)
		(min_thickness 0.25)
		(keepout
			(tracks not_allowed)
			(vias allowed)
			(pads allowed)
			(copperpour not_allowed)
			(footprints allowed)
		)
		(placement
			(enabled no)
			(sheetname "")
		)
		(fill yes
			(thermal_gap 0.5)
			(thermal_bridge_width 0.5)
			(island_removal_mode 0)
		)
		(polygon
			(pts
				(arc
					(start 195.78193 -235.771436)
					(mid 195.796809 -235.807357)
					(end 195.83273 -235.822236)
				)
				(arc
					(start 197.23227 -235.822236)
					(mid 197.268191 -235.807357)
					(end 197.28307 -235.771436)
				)
				(arc
					(start 197.28307 -235.362496)
					(mid 197.268191 -235.326575)
					(end 197.23227 -235.311696)
				)
				(arc
					(start 195.83273 -235.311696)
					(mid 195.796809 -235.326575)
					(end 195.78193 -235.362496)
				)
			)
		)
	)
	(zone
		(layers "In1.Cu" "In2.Cu")
		(hatch none 0.5)
		(connect_pads
			(clearance 0)
		)
		(min_thickness 0.25)
		(keepout
			(tracks not_allowed)
			(vias allowed)
			(pads allowed)
			(copperpour not_allowed)
			(footprints allowed)
		)
		(placement
			(enabled no)
			(sheetname "")
		)
		(fill yes
			(thermal_gap 0.5)
			(thermal_bridge_width 0.5)
			(island_removal_mode 0)
		)
		(polygon
			(pts
				(arc
					(start 304.693066 -276.571456)
					(mid 304.707945 -276.607377)
					(end 304.743866 -276.622256)
				)
				(arc
					(start 306.143406 -276.622256)
					(mid 306.179327 -276.607377)
					(end 306.194206 -276.571456)
				)
				(arc
					(start 306.194206 -276.162516)
					(mid 306.179327 -276.126595)
					(end 306.143406 -276.111716)
				)
				(arc
					(start 304.743866 -276.111716)
					(mid 304.707945 -276.126595)
					(end 304.693066 -276.162516)
				)
			)
		)
	)
	(zone
		(layers "In1.Cu" "In2.Cu")
		(hatch none 0.5)
		(connect_pads
			(clearance 0)
		)
		(min_thickness 0.25)
		(keepout
			(tracks not_allowed)
			(vias allowed)
			(pads allowed)
			(copperpour not_allowed)
			(footprints allowed)
		)
		(placement
			(enabled no)
			(sheetname "")
		)
		(fill yes
			(thermal_gap 0.5)
			(thermal_bridge_width 0.5)
			(island_removal_mode 0)
		)
		(polygon
			(pts
				(arc
					(start 34.121598 -292.721538)
					(mid 34.136477 -292.757459)
					(end 34.172398 -292.772338)
				)
				(arc
					(start 35.571938 -292.772338)
					(mid 35.607859 -292.757459)
					(end 35.622738 -292.721538)
				)
				(arc
					(start 35.622738 -292.312598)
					(mid 35.607859 -292.276677)
					(end 35.571938 -292.261798)
				)
				(arc
					(start 34.172398 -292.261798)
					(mid 34.136477 -292.276677)
					(end 34.121598 -292.312598)
				)
			)
		)
	)
	(zone
		(layers "In1.Cu" "In2.Cu")
		(hatch none 0.5)
		(connect_pads
			(clearance 0)
		)
		(min_thickness 0.25)
		(keepout
			(tracks not_allowed)
			(vias allowed)
			(pads allowed)
			(copperpour not_allowed)
			(footprints allowed)
		)
		(placement
			(enabled no)
			(sheetname "")
		)
		(fill yes
			(thermal_gap 0.5)
			(thermal_bridge_width 0.5)
			(island_removal_mode 0)
		)
		(polygon
			(pts
				(arc
					(start 425.190666 -220.471492)
					(mid 425.205545 -220.507413)
					(end 425.241466 -220.522292)
				)
				(arc
					(start 426.641006 -220.522292)
					(mid 426.676927 -220.507413)
					(end 426.691806 -220.471492)
				)
				(arc
					(start 426.691806 -220.062552)
					(mid 426.676927 -220.026631)
					(end 426.641006 -220.011752)
				)
				(arc
					(start 425.241466 -220.011752)
					(mid 425.205545 -220.026631)
					(end 425.190666 -220.062552)
				)
			)
		)
	)
	(zone
		(layers "In1.Cu" "In2.Cu")
		(hatch none 0.5)
		(connect_pads
			(clearance 0)
		)
		(min_thickness 0.25)
		(keepout
			(tracks not_allowed)
			(vias allowed)
			(pads allowed)
			(copperpour not_allowed)
			(footprints allowed)
		)
		(placement
			(enabled no)
			(sheetname "")
		)
		(fill yes
			(thermal_gap 0.5)
			(thermal_bridge_width 0.5)
			(island_removal_mode 0)
		)
		(polygon
			(pts
				(arc
					(start 45.10913 -202.621388)
					(mid 45.124009 -202.657309)
					(end 45.15993 -202.672188)
				)
				(arc
					(start 46.55947 -202.672188)
					(mid 46.595391 -202.657309)
					(end 46.61027 -202.621388)
				)
				(arc
					(start 46.61027 -202.212448)
					(mid 46.595391 -202.176527)
					(end 46.55947 -202.161648)
				)
				(arc
					(start 45.15993 -202.161648)
					(mid 45.124009 -202.176527)
					(end 45.10913 -202.212448)
				)
			)
		)
	)
	(zone
		(layers "In1.Cu" "In2.Cu")
		(hatch none 0.5)
		(connect_pads
			(clearance 0)
		)
		(min_thickness 0.25)
		(keepout
			(tracks not_allowed)
			(vias allowed)
			(pads allowed)
			(copperpour not_allowed)
			(footprints allowed)
		)
		(placement
			(enabled no)
			(sheetname "")
		)
		(fill yes
			(thermal_gap 0.5)
			(thermal_bridge_width 0.5)
			(island_removal_mode 0)
		)
		(polygon
			(pts
				(arc
					(start 443.721998 -226.421442)
					(mid 443.736877 -226.457363)
					(end 443.772798 -226.472242)
				)
				(arc
					(start 445.172338 -226.472242)
					(mid 445.208259 -226.457363)
					(end 445.223138 -226.421442)
				)
				(arc
					(start 445.223138 -226.012502)
					(mid 445.208259 -225.976581)
					(end 445.172338 -225.961702)
				)
				(arc
					(start 443.772798 -225.961702)
					(mid 443.736877 -225.976581)
					(end 443.721998 -226.012502)
				)
			)
		)
	)
	(zone
		(layers "In1.Cu" "In2.Cu")
		(hatch none 0.5)
		(connect_pads
			(clearance 0)
		)
		(min_thickness 0.25)
		(keepout
			(tracks not_allowed)
			(vias allowed)
			(pads allowed)
			(copperpour not_allowed)
			(footprints allowed)
		)
		(placement
			(enabled no)
			(sheetname "")
		)
		(fill yes
			(thermal_gap 0.5)
			(thermal_bridge_width 0.5)
			(island_removal_mode 0)
		)
		(polygon
			(pts
				(arc
					(start 432.734466 -240.871502)
					(mid 432.749345 -240.907423)
					(end 432.785266 -240.922302)
				)
				(arc
					(start 434.184806 -240.922302)
					(mid 434.220727 -240.907423)
					(end 434.235606 -240.871502)
				)
				(arc
					(start 434.235606 -240.462562)
					(mid 434.220727 -240.426641)
					(end 434.184806 -240.411762)
				)
				(arc
					(start 432.785266 -240.411762)
					(mid 432.749345 -240.426641)
					(end 432.734466 -240.462562)
				)
			)
		)
	)
	(zone
		(layers "In1.Cu" "In2.Cu")
		(hatch none 0.5)
		(connect_pads
			(clearance 0)
		)
		(min_thickness 0.25)
		(keepout
			(tracks not_allowed)
			(vias allowed)
			(pads allowed)
			(copperpour not_allowed)
			(footprints allowed)
		)
		(placement
			(enabled no)
			(sheetname "")
		)
		(fill yes
			(thermal_gap 0.5)
			(thermal_bridge_width 0.5)
			(island_removal_mode 0)
		)
		(polygon
			(pts
				(arc
					(start 312.236866 -284.221428)
					(mid 312.251745 -284.257349)
					(end 312.287666 -284.272228)
				)
				(arc
					(start 313.687206 -284.272228)
					(mid 313.723127 -284.257349)
					(end 313.738006 -284.221428)
				)
				(arc
					(start 313.738006 -283.812488)
					(mid 313.723127 -283.776567)
					(end 313.687206 -283.761688)
				)
				(arc
					(start 312.287666 -283.761688)
					(mid 312.251745 -283.776567)
					(end 312.236866 -283.812488)
				)
			)
		)
	)
	(zone
		(layers "In1.Cu" "In2.Cu")
		(hatch none 0.5)
		(connect_pads
			(clearance 0)
		)
		(min_thickness 0.25)
		(keepout
			(tracks not_allowed)
			(vias allowed)
			(pads allowed)
			(copperpour not_allowed)
			(footprints allowed)
		)
		(placement
			(enabled no)
			(sheetname "")
		)
		(fill yes
			(thermal_gap 0.5)
			(thermal_bridge_width 0.5)
			(island_removal_mode 0)
		)
		(polygon
			(pts
				(arc
					(start 300.592998 -303.7713)
					(mid 300.607877 -303.807221)
					(end 300.643798 -303.8221)
				)
				(arc
					(start 302.043338 -303.8221)
					(mid 302.079259 -303.807221)
					(end 302.094138 -303.7713)
				)
				(arc
					(start 302.094138 -303.36236)
					(mid 302.079259 -303.326439)
					(end 302.043338 -303.31156)
				)
				(arc
					(start 300.643798 -303.31156)
					(mid 300.607877 -303.326439)
					(end 300.592998 -303.36236)
				)
			)
		)
	)
	(zone
		(layers "In1.Cu" "In2.Cu")
		(hatch none 0.5)
		(connect_pads
			(clearance 0)
		)
		(min_thickness 0.25)
		(keepout
			(tracks not_allowed)
			(vias allowed)
			(pads allowed)
			(copperpour not_allowed)
			(footprints allowed)
		)
		(placement
			(enabled no)
			(sheetname "")
		)
		(fill yes
			(thermal_gap 0.5)
			(thermal_bridge_width 0.5)
			(island_removal_mode 0)
		)
		(polygon
			(pts
				(arc
					(start 443.721998 -202.621388)
					(mid 443.736877 -202.657309)
					(end 443.772798 -202.672188)
				)
				(arc
					(start 445.172338 -202.672188)
					(mid 445.208259 -202.657309)
					(end 445.223138 -202.621388)
				)
				(arc
					(start 445.223138 -202.212448)
					(mid 445.208259 -202.176527)
					(end 445.172338 -202.161648)
				)
				(arc
					(start 443.772798 -202.161648)
					(mid 443.736877 -202.176527)
					(end 443.721998 -202.212448)
				)
			)
		)
	)
	(zone
		(layers "In1.Cu" "In2.Cu")
		(hatch none 0.5)
		(connect_pads
			(clearance 0)
		)
		(min_thickness 0.25)
		(keepout
			(tracks not_allowed)
			(vias allowed)
			(pads allowed)
			(copperpour not_allowed)
			(footprints allowed)
		)
		(placement
			(enabled no)
			(sheetname "")
		)
		(fill yes
			(thermal_gap 0.5)
			(thermal_bridge_width 0.5)
			(island_removal_mode 0)
		)
		(polygon
			(pts
				(arc
					(start 277.961598 -244.271292)
					(mid 277.976477 -244.307213)
					(end 278.012398 -244.322092)
				)
				(arc
					(start 279.411938 -244.322092)
					(mid 279.447859 -244.307213)
					(end 279.462738 -244.271292)
				)
				(arc
					(start 279.462738 -243.862352)
					(mid 279.447859 -243.826431)
					(end 279.411938 -243.811552)
				)
				(arc
					(start 278.012398 -243.811552)
					(mid 277.976477 -243.826431)
					(end 277.961598 -243.862352)
				)
			)
		)
	)
	(zone
		(layers "In1.Cu" "In2.Cu")
		(hatch none 0.5)
		(connect_pads
			(clearance 0)
		)
		(min_thickness 0.25)
		(keepout
			(tracks not_allowed)
			(vias allowed)
			(pads allowed)
			(copperpour not_allowed)
			(footprints allowed)
		)
		(placement
			(enabled no)
			(sheetname "")
		)
		(fill yes
			(thermal_gap 0.5)
			(thermal_bridge_width 0.5)
			(island_removal_mode 0)
		)
		(polygon
			(pts
				(arc
					(start 455.365866 -312.27141)
					(mid 455.380745 -312.307331)
					(end 455.416666 -312.32221)
				)
				(arc
					(start 456.816206 -312.32221)
					(mid 456.852127 -312.307331)
					(end 456.867006 -312.27141)
				)
				(arc
					(start 456.867006 -311.86247)
					(mid 456.852127 -311.826549)
					(end 456.816206 -311.81167)
				)
				(arc
					(start 455.416666 -311.81167)
					(mid 455.380745 -311.826549)
					(end 455.365866 -311.86247)
				)
			)
		)
	)
	(zone
		(layers "In1.Cu" "In2.Cu")
		(hatch none 0.5)
		(connect_pads
			(clearance 0)
		)
		(min_thickness 0.25)
		(keepout
			(tracks not_allowed)
			(vias allowed)
			(pads allowed)
			(copperpour not_allowed)
			(footprints allowed)
		)
		(placement
			(enabled no)
			(sheetname "")
		)
		(fill yes
			(thermal_gap 0.5)
			(thermal_bridge_width 0.5)
			(island_removal_mode 0)
		)
		(polygon
			(pts
				(arc
					(start 274.517866 -281.671522)
					(mid 274.532745 -281.707443)
					(end 274.568666 -281.722322)
				)
				(arc
					(start 275.968206 -281.722322)
					(mid 276.004127 -281.707443)
					(end 276.019006 -281.671522)
				)
				(arc
					(start 276.019006 -281.262582)
					(mid 276.004127 -281.226661)
					(end 275.968206 -281.211782)
				)
				(arc
					(start 274.568666 -281.211782)
					(mid 274.532745 -281.226661)
					(end 274.517866 -281.262582)
				)
			)
		)
	)
	(zone
		(layers "In1.Cu" "In2.Cu")
		(hatch none 0.5)
		(connect_pads
			(clearance 0)
		)
		(min_thickness 0.25)
		(keepout
			(tracks not_allowed)
			(vias allowed)
			(pads allowed)
			(copperpour not_allowed)
			(footprints allowed)
		)
		(placement
			(enabled no)
			(sheetname "")
		)
		(fill yes
			(thermal_gap 0.5)
			(thermal_bridge_width 0.5)
			(island_removal_mode 0)
		)
		(polygon
			(pts
				(arc
					(start 41.665398 -250.221496)
					(mid 41.680277 -250.257417)
					(end 41.716198 -250.272296)
				)
				(arc
					(start 43.115738 -250.272296)
					(mid 43.151659 -250.257417)
					(end 43.166538 -250.221496)
				)
				(arc
					(start 43.166538 -249.812556)
					(mid 43.151659 -249.776635)
					(end 43.115738 -249.761756)
				)
				(arc
					(start 41.716198 -249.761756)
					(mid 41.680277 -249.776635)
					(end 41.665398 -249.812556)
				)
			)
		)
	)
	(zone
		(layers "In1.Cu" "In2.Cu")
		(hatch none 0.5)
		(connect_pads
			(clearance 0)
		)
		(min_thickness 0.25)
		(keepout
			(tracks not_allowed)
			(vias allowed)
			(pads allowed)
			(copperpour not_allowed)
			(footprints allowed)
		)
		(placement
			(enabled no)
			(sheetname "")
		)
		(fill yes
			(thermal_gap 0.5)
			(thermal_bridge_width 0.5)
			(island_removal_mode 0)
		)
		(polygon
			(pts
				(arc
					(start 270.417798 -268.071346)
					(mid 270.432677 -268.107267)
					(end 270.468598 -268.122146)
				)
				(arc
					(start 271.868138 -268.122146)
					(mid 271.904059 -268.107267)
					(end 271.918938 -268.071346)
				)
				(arc
					(start 271.918938 -267.662406)
					(mid 271.904059 -267.626485)
					(end 271.868138 -267.611606)
				)
				(arc
					(start 270.468598 -267.611606)
					(mid 270.432677 -267.626485)
					(end 270.417798 -267.662406)
				)
			)
		)
	)
	(zone
		(layers "In1.Cu" "In2.Cu")
		(hatch none 0.5)
		(connect_pads
			(clearance 0)
		)
		(min_thickness 0.25)
		(keepout
			(tracks not_allowed)
			(vias allowed)
			(pads allowed)
			(copperpour not_allowed)
			(footprints allowed)
		)
		(placement
			(enabled no)
			(sheetname "")
		)
		(fill yes
			(thermal_gap 0.5)
			(thermal_bridge_width 0.5)
			(island_removal_mode 0)
		)
		(polygon
			(pts
				(arc
					(start 413.546798 -232.371392)
					(mid 413.561677 -232.407313)
					(end 413.597598 -232.422192)
				)
				(arc
					(start 414.997138 -232.422192)
					(mid 415.033059 -232.407313)
					(end 415.047938 -232.371392)
				)
				(arc
					(start 415.047938 -231.962452)
					(mid 415.033059 -231.926531)
					(end 414.997138 -231.911652)
				)
				(arc
					(start 413.597598 -231.911652)
					(mid 413.561677 -231.926531)
					(end 413.546798 -231.962452)
				)
			)
		)
	)
	(zone
		(layers "In1.Cu" "In2.Cu")
		(hatch none 0.5)
		(connect_pads
			(clearance 0)
		)
		(min_thickness 0.25)
		(keepout
			(tracks not_allowed)
			(vias allowed)
			(pads allowed)
			(copperpour not_allowed)
			(footprints allowed)
		)
		(placement
			(enabled no)
			(sheetname "")
		)
		(fill yes
			(thermal_gap 0.5)
			(thermal_bridge_width 0.5)
			(island_removal_mode 0)
		)
		(polygon
			(pts
				(arc
					(start 49.209198 -223.871536)
					(mid 49.224077 -223.907457)
					(end 49.259998 -223.922336)
				)
				(arc
					(start 50.659538 -223.922336)
					(mid 50.695459 -223.907457)
					(end 50.710338 -223.871536)
				)
				(arc
					(start 50.710338 -223.462596)
					(mid 50.695459 -223.426675)
					(end 50.659538 -223.411796)
				)
				(arc
					(start 49.259998 -223.411796)
					(mid 49.224077 -223.426675)
					(end 49.209198 -223.462596)
				)
			)
		)
	)
	(zone
		(layers "In1.Cu" "In2.Cu")
		(hatch none 0.5)
		(connect_pads
			(clearance 0)
		)
		(min_thickness 0.25)
		(keepout
			(tracks not_allowed)
			(vias allowed)
			(pads allowed)
			(copperpour not_allowed)
			(footprints allowed)
		)
		(placement
			(enabled no)
			(sheetname "")
		)
		(fill yes
			(thermal_gap 0.5)
			(thermal_bridge_width 0.5)
			(island_removal_mode 0)
		)
		(polygon
			(pts
				(arc
					(start 37.56533 -244.271292)
					(mid 37.580209 -244.307213)
					(end 37.61613 -244.322092)
				)
				(arc
					(start 39.01567 -244.322092)
					(mid 39.051591 -244.307213)
					(end 39.06647 -244.271292)
				)
				(arc
					(start 39.06647 -243.862352)
					(mid 39.051591 -243.826431)
					(end 39.01567 -243.811552)
				)
				(arc
					(start 37.61613 -243.811552)
					(mid 37.580209 -243.826431)
					(end 37.56533 -243.862352)
				)
			)
		)
	)
	(zone
		(layers "In1.Cu" "In2.Cu")
		(hatch none 0.5)
		(connect_pads
			(clearance 0)
		)
		(min_thickness 0.25)
		(keepout
			(tracks not_allowed)
			(vias allowed)
			(pads allowed)
			(copperpour not_allowed)
			(footprints allowed)
		)
		(placement
			(enabled no)
			(sheetname "")
		)
		(fill yes
			(thermal_gap 0.5)
			(thermal_bridge_width 0.5)
			(island_removal_mode 0)
		)
		(polygon
			(pts
				(arc
					(start 455.365866 -236.62132)
					(mid 455.380745 -236.657241)
					(end 455.416666 -236.67212)
				)
				(arc
					(start 456.816206 -236.67212)
					(mid 456.852127 -236.657241)
					(end 456.867006 -236.62132)
				)
				(arc
					(start 456.867006 -236.21238)
					(mid 456.852127 -236.176459)
					(end 456.816206 -236.16158)
				)
				(arc
					(start 455.416666 -236.16158)
					(mid 455.380745 -236.176459)
					(end 455.365866 -236.21238)
				)
			)
		)
	)
	(zone
		(layers "In1.Cu" "In2.Cu")
		(hatch none 0.5)
		(connect_pads
			(clearance 0)
		)
		(min_thickness 0.25)
		(keepout
			(tracks not_allowed)
			(vias allowed)
			(pads allowed)
			(copperpour not_allowed)
			(footprints allowed)
		)
		(placement
			(enabled no)
			(sheetname "")
		)
		(fill yes
			(thermal_gap 0.5)
			(thermal_bridge_width 0.5)
			(island_removal_mode 0)
		)
		(polygon
			(pts
				(arc
					(start 277.961598 -226.421442)
					(mid 277.976477 -226.457363)
					(end 278.012398 -226.472242)
				)
				(arc
					(start 279.411938 -226.472242)
					(mid 279.447859 -226.457363)
					(end 279.462738 -226.421442)
				)
				(arc
					(start 279.462738 -226.012502)
					(mid 279.447859 -225.976581)
					(end 279.411938 -225.961702)
				)
				(arc
					(start 278.012398 -225.961702)
					(mid 277.976477 -225.976581)
					(end 277.961598 -226.012502)
				)
			)
		)
	)
	(zone
		(layers "In1.Cu" "In2.Cu")
		(hatch none 0.5)
		(connect_pads
			(clearance 0)
		)
		(min_thickness 0.25)
		(keepout
			(tracks not_allowed)
			(vias allowed)
			(pads allowed)
			(copperpour not_allowed)
			(footprints allowed)
		)
		(placement
			(enabled no)
			(sheetname "")
		)
		(fill yes
			(thermal_gap 0.5)
			(thermal_bridge_width 0.5)
			(island_removal_mode 0)
		)
		(polygon
			(pts
				(arc
					(start 274.517866 -311.421526)
					(mid 274.532745 -311.457447)
					(end 274.568666 -311.472326)
				)
				(arc
					(start 275.968206 -311.472326)
					(mid 276.004127 -311.457447)
					(end 276.019006 -311.421526)
				)
				(arc
					(start 276.019006 -311.012586)
					(mid 276.004127 -310.976665)
					(end 275.968206 -310.961786)
				)
				(arc
					(start 274.568666 -310.961786)
					(mid 274.532745 -310.976665)
					(end 274.517866 -311.012586)
				)
			)
		)
	)
	(zone
		(layers "In1.Cu" "In2.Cu")
		(hatch none 0.5)
		(connect_pads
			(clearance 0)
		)
		(min_thickness 0.25)
		(keepout
			(tracks not_allowed)
			(vias allowed)
			(pads allowed)
			(copperpour not_allowed)
			(footprints allowed)
		)
		(placement
			(enabled no)
			(sheetname "")
		)
		(fill yes
			(thermal_gap 0.5)
			(thermal_bridge_width 0.5)
			(island_removal_mode 0)
		)
		(polygon
			(pts
				(arc
					(start 7.39013 -251.07138)
					(mid 7.405009 -251.107301)
					(end 7.44093 -251.12218)
				)
				(arc
					(start 8.84047 -251.12218)
					(mid 8.876391 -251.107301)
					(end 8.89127 -251.07138)
				)
				(arc
					(start 8.89127 -250.66244)
					(mid 8.876391 -250.626519)
					(end 8.84047 -250.61164)
				)
				(arc
					(start 7.44093 -250.61164)
					(mid 7.405009 -250.626519)
					(end 7.39013 -250.66244)
				)
			)
		)
	)
	(zone
		(layers "In1.Cu" "In2.Cu")
		(hatch none 0.5)
		(connect_pads
			(clearance 0)
		)
		(min_thickness 0.25)
		(keepout
			(tracks not_allowed)
			(vias allowed)
			(pads allowed)
			(copperpour not_allowed)
			(footprints allowed)
		)
		(placement
			(enabled no)
			(sheetname "")
		)
		(fill yes
			(thermal_gap 0.5)
			(thermal_bridge_width 0.5)
			(island_removal_mode 0)
		)
		(polygon
			(pts
				(arc
					(start 410.103066 -281.671522)
					(mid 410.117945 -281.707443)
					(end 410.153866 -281.722322)
				)
				(arc
					(start 411.553406 -281.722322)
					(mid 411.589327 -281.707443)
					(end 411.604206 -281.671522)
				)
				(arc
					(start 411.604206 -281.262582)
					(mid 411.589327 -281.226661)
					(end 411.553406 -281.211782)
				)
				(arc
					(start 410.153866 -281.211782)
					(mid 410.117945 -281.226661)
					(end 410.103066 -281.262582)
				)
			)
		)
	)
	(zone
		(layers "In1.Cu" "In2.Cu")
		(hatch none 0.5)
		(connect_pads
			(clearance 0)
		)
		(min_thickness 0.25)
		(keepout
			(tracks not_allowed)
			(vias allowed)
			(pads allowed)
			(copperpour not_allowed)
			(footprints allowed)
		)
		(placement
			(enabled no)
			(sheetname "")
		)
		(fill yes
			(thermal_gap 0.5)
			(thermal_bridge_width 0.5)
			(island_removal_mode 0)
		)
		(polygon
			(pts
				(arc
					(start 458.809598 -291.8714)
					(mid 458.824477 -291.907321)
					(end 458.860398 -291.9222)
				)
				(arc
					(start 460.259938 -291.9222)
					(mid 460.295859 -291.907321)
					(end 460.310738 -291.8714)
				)
				(arc
					(start 460.310738 -291.46246)
					(mid 460.295859 -291.426539)
					(end 460.259938 -291.41166)
				)
				(arc
					(start 458.860398 -291.41166)
					(mid 458.824477 -291.426539)
					(end 458.809598 -291.46246)
				)
			)
		)
	)
	(zone
		(layers "In1.Cu" "In2.Cu")
		(hatch none 0.5)
		(connect_pads
			(clearance 0)
		)
		(min_thickness 0.25)
		(keepout
			(tracks not_allowed)
			(vias allowed)
			(pads allowed)
			(copperpour not_allowed)
			(footprints allowed)
		)
		(placement
			(enabled no)
			(sheetname "")
		)
		(fill yes
			(thermal_gap 0.5)
			(thermal_bridge_width 0.5)
			(island_removal_mode 0)
		)
		(polygon
			(pts
				(arc
					(start 428.634398 -280.821384)
					(mid 428.649277 -280.857305)
					(end 428.685198 -280.872184)
				)
				(arc
					(start 430.084738 -280.872184)
					(mid 430.120659 -280.857305)
					(end 430.135538 -280.821384)
				)
				(arc
					(start 430.135538 -280.412444)
					(mid 430.120659 -280.376523)
					(end 430.084738 -280.361644)
				)
				(arc
					(start 428.685198 -280.361644)
					(mid 428.649277 -280.376523)
					(end 428.634398 -280.412444)
				)
			)
		)
	)
	(zone
		(layers "In1.Cu" "In2.Cu")
		(hatch none 0.5)
		(connect_pads
			(clearance 0)
		)
		(min_thickness 0.25)
		(keepout
			(tracks not_allowed)
			(vias allowed)
			(pads allowed)
			(copperpour not_allowed)
			(footprints allowed)
		)
		(placement
			(enabled no)
			(sheetname "")
		)
		(fill yes
			(thermal_gap 0.5)
			(thermal_bridge_width 0.5)
			(island_removal_mode 0)
		)
		(polygon
			(pts
				(arc
					(start 30.02153 -247.671336)
					(mid 30.036409 -247.707257)
					(end 30.07233 -247.722136)
				)
				(arc
					(start 31.47187 -247.722136)
					(mid 31.507791 -247.707257)
					(end 31.52267 -247.671336)
				)
				(arc
					(start 31.52267 -247.262396)
					(mid 31.507791 -247.226475)
					(end 31.47187 -247.211596)
				)
				(arc
					(start 30.07233 -247.211596)
					(mid 30.036409 -247.226475)
					(end 30.02153 -247.262396)
				)
			)
		)
	)
	(zone
		(layers "In1.Cu" "In2.Cu")
		(hatch none 0.5)
		(connect_pads
			(clearance 0)
		)
		(min_thickness 0.25)
		(keepout
			(tracks not_allowed)
			(vias allowed)
			(pads allowed)
			(copperpour not_allowed)
			(footprints allowed)
		)
		(placement
			(enabled no)
			(sheetname "")
		)
		(fill yes
			(thermal_gap 0.5)
			(thermal_bridge_width 0.5)
			(island_removal_mode 0)
		)
		(polygon
			(pts
				(arc
					(start 11.490198 -308.021482)
					(mid 11.505077 -308.057403)
					(end 11.540998 -308.072282)
				)
				(arc
					(start 12.940538 -308.072282)
					(mid 12.976459 -308.057403)
					(end 12.991338 -308.021482)
				)
				(arc
					(start 12.991338 -307.612542)
					(mid 12.976459 -307.576621)
					(end 12.940538 -307.561742)
				)
				(arc
					(start 11.540998 -307.561742)
					(mid 11.505077 -307.576621)
					(end 11.490198 -307.612542)
				)
			)
		)
	)
	(zone
		(layers "In1.Cu" "In2.Cu")
		(hatch none 0.5)
		(connect_pads
			(clearance 0)
		)
		(min_thickness 0.25)
		(keepout
			(tracks not_allowed)
			(vias allowed)
			(pads allowed)
			(copperpour not_allowed)
			(footprints allowed)
		)
		(placement
			(enabled no)
			(sheetname "")
		)
		(fill yes
			(thermal_gap 0.5)
			(thermal_bridge_width 0.5)
			(island_removal_mode 0)
		)
		(polygon
			(pts
				(arc
					(start 255.330198 -207.721454)
					(mid 255.345077 -207.757375)
					(end 255.380998 -207.772254)
				)
				(arc
					(start 256.780538 -207.772254)
					(mid 256.816459 -207.757375)
					(end 256.831338 -207.721454)
				)
				(arc
					(start 256.831338 -207.312514)
					(mid 256.816459 -207.276593)
					(end 256.780538 -207.261714)
				)
				(arc
					(start 255.380998 -207.261714)
					(mid 255.345077 -207.276593)
					(end 255.330198 -207.312514)
				)
			)
		)
	)
	(zone
		(layers "In1.Cu" "In2.Cu")
		(hatch none 0.5)
		(connect_pads
			(clearance 0)
		)
		(min_thickness 0.25)
		(keepout
			(tracks not_allowed)
			(vias allowed)
			(pads allowed)
			(copperpour not_allowed)
			(footprints allowed)
		)
		(placement
			(enabled no)
			(sheetname "")
		)
		(fill yes
			(thermal_gap 0.5)
			(thermal_bridge_width 0.5)
			(island_removal_mode 0)
		)
		(polygon
			(pts
				(arc
					(start 60.19673 -210.27136)
					(mid 60.211609 -210.307281)
					(end 60.24753 -210.32216)
				)
				(arc
					(start 61.64707 -210.32216)
					(mid 61.682991 -210.307281)
					(end 61.69787 -210.27136)
				)
				(arc
					(start 61.69787 -209.86242)
					(mid 61.682991 -209.826499)
					(end 61.64707 -209.81162)
				)
				(arc
					(start 60.24753 -209.81162)
					(mid 60.211609 -209.826499)
					(end 60.19673 -209.86242)
				)
			)
		)
	)
	(zone
		(layers "In1.Cu" "In2.Cu")
		(hatch none 0.5)
		(connect_pads
			(clearance 0)
		)
		(min_thickness 0.25)
		(keepout
			(tracks not_allowed)
			(vias allowed)
			(pads allowed)
			(copperpour not_allowed)
			(footprints allowed)
		)
		(placement
			(enabled no)
			(sheetname "")
		)
		(fill yes
			(thermal_gap 0.5)
			(thermal_bridge_width 0.5)
			(island_removal_mode 0)
		)
		(polygon
			(pts
				(arc
					(start 458.809598 -297.82135)
					(mid 458.824477 -297.857271)
					(end 458.860398 -297.87215)
				)
				(arc
					(start 460.259938 -297.87215)
					(mid 460.295859 -297.857271)
					(end 460.310738 -297.82135)
				)
				(arc
					(start 460.310738 -297.41241)
					(mid 460.295859 -297.376489)
					(end 460.259938 -297.36161)
				)
				(arc
					(start 458.860398 -297.36161)
					(mid 458.824477 -297.376489)
					(end 458.809598 -297.41241)
				)
			)
		)
	)
	(zone
		(layers "In1.Cu" "In2.Cu")
		(hatch none 0.5)
		(connect_pads
			(clearance 0)
		)
		(min_thickness 0.25)
		(keepout
			(tracks not_allowed)
			(vias allowed)
			(pads allowed)
			(copperpour not_allowed)
			(footprints allowed)
		)
		(placement
			(enabled no)
			(sheetname "")
		)
		(fill yes
			(thermal_gap 0.5)
			(thermal_bridge_width 0.5)
			(island_removal_mode 0)
		)
		(polygon
			(pts
				(arc
					(start 210.86953 -209.421476)
					(mid 210.884409 -209.457397)
					(end 210.92033 -209.472276)
				)
				(arc
					(start 212.31987 -209.472276)
					(mid 212.355791 -209.457397)
					(end 212.37067 -209.421476)
				)
				(arc
					(start 212.37067 -209.012536)
					(mid 212.355791 -208.976615)
					(end 212.31987 -208.961736)
				)
				(arc
					(start 210.92033 -208.961736)
					(mid 210.884409 -208.976615)
					(end 210.86953 -209.012536)
				)
			)
		)
	)
	(zone
		(layers "In1.Cu" "In2.Cu")
		(hatch none 0.5)
		(connect_pads
			(clearance 0)
		)
		(min_thickness 0.25)
		(keepout
			(tracks not_allowed)
			(vias allowed)
			(pads allowed)
			(copperpour not_allowed)
			(footprints allowed)
		)
		(placement
			(enabled no)
			(sheetname "")
		)
		(fill yes
			(thermal_gap 0.5)
			(thermal_bridge_width 0.5)
			(island_removal_mode 0)
		)
		(polygon
			(pts
				(arc
					(start 259.430266 -289.321494)
					(mid 259.445145 -289.357415)
					(end 259.481066 -289.372294)
				)
				(arc
					(start 260.880606 -289.372294)
					(mid 260.916527 -289.357415)
					(end 260.931406 -289.321494)
				)
				(arc
					(start 260.931406 -288.912554)
					(mid 260.916527 -288.876633)
					(end 260.880606 -288.861754)
				)
				(arc
					(start 259.481066 -288.861754)
					(mid 259.445145 -288.876633)
					(end 259.430266 -288.912554)
				)
			)
		)
	)
	(zone
		(layers "In1.Cu" "In2.Cu")
		(hatch none 0.5)
		(connect_pads
			(clearance 0)
		)
		(min_thickness 0.25)
		(keepout
			(tracks not_allowed)
			(vias allowed)
			(pads allowed)
			(copperpour not_allowed)
			(footprints allowed)
		)
		(placement
			(enabled no)
			(sheetname "")
		)
		(fill yes
			(thermal_gap 0.5)
			(thermal_bridge_width 0.5)
			(island_removal_mode 0)
		)
		(polygon
			(pts
				(arc
					(start 37.56533 -299.521372)
					(mid 37.580209 -299.557293)
					(end 37.61613 -299.572172)
				)
				(arc
					(start 39.01567 -299.572172)
					(mid 39.051591 -299.557293)
					(end 39.06647 -299.521372)
				)
				(arc
					(start 39.06647 -299.112432)
					(mid 39.051591 -299.076511)
					(end 39.01567 -299.061632)
				)
				(arc
					(start 37.61613 -299.061632)
					(mid 37.580209 -299.076511)
					(end 37.56533 -299.112432)
				)
			)
		)
	)
	(zone
		(layers "In1.Cu" "In2.Cu")
		(hatch none 0.5)
		(connect_pads
			(clearance 0)
		)
		(min_thickness 0.25)
		(keepout
			(tracks not_allowed)
			(vias allowed)
			(pads allowed)
			(copperpour not_allowed)
			(footprints allowed)
		)
		(placement
			(enabled no)
			(sheetname "")
		)
		(fill yes
			(thermal_gap 0.5)
			(thermal_bridge_width 0.5)
			(island_removal_mode 0)
		)
		(polygon
			(pts
				(arc
					(start 436.178198 -215.371426)
					(mid 436.193077 -215.407347)
					(end 436.228998 -215.422226)
				)
				(arc
					(start 437.628538 -215.422226)
					(mid 437.664459 -215.407347)
					(end 437.679338 -215.371426)
				)
				(arc
					(start 437.679338 -214.962486)
					(mid 437.664459 -214.926565)
					(end 437.628538 -214.911686)
				)
				(arc
					(start 436.228998 -214.911686)
					(mid 436.193077 -214.926565)
					(end 436.178198 -214.962486)
				)
			)
		)
	)
	(zone
		(layers "In1.Cu" "In2.Cu")
		(hatch none 0.5)
		(connect_pads
			(clearance 0)
		)
		(min_thickness 0.25)
		(keepout
			(tracks not_allowed)
			(vias allowed)
			(pads allowed)
			(copperpour not_allowed)
			(footprints allowed)
		)
		(placement
			(enabled no)
			(sheetname "")
		)
		(fill yes
			(thermal_gap 0.5)
			(thermal_bridge_width 0.5)
			(island_removal_mode 0)
		)
		(polygon
			(pts
				(arc
					(start 447.822066 -245.12143)
					(mid 447.836945 -245.157351)
					(end 447.872866 -245.17223)
				)
				(arc
					(start 449.272406 -245.17223)
					(mid 449.308327 -245.157351)
					(end 449.323206 -245.12143)
				)
				(arc
					(start 449.323206 -244.71249)
					(mid 449.308327 -244.676569)
					(end 449.272406 -244.66169)
				)
				(arc
					(start 447.872866 -244.66169)
					(mid 447.836945 -244.676569)
					(end 447.822066 -244.71249)
				)
			)
		)
	)
	(zone
		(layers "In1.Cu" "In2.Cu")
		(hatch none 0.5)
		(connect_pads
			(clearance 0)
		)
		(min_thickness 0.25)
		(keepout
			(tracks not_allowed)
			(vias allowed)
			(pads allowed)
			(copperpour not_allowed)
			(footprints allowed)
		)
		(placement
			(enabled no)
			(sheetname "")
		)
		(fill yes
			(thermal_gap 0.5)
			(thermal_bridge_width 0.5)
			(island_removal_mode 0)
		)
		(polygon
			(pts
				(arc
					(start 410.103066 -214.521542)
					(mid 410.117945 -214.557463)
					(end 410.153866 -214.572342)
				)
				(arc
					(start 411.553406 -214.572342)
					(mid 411.589327 -214.557463)
					(end 411.604206 -214.521542)
				)
				(arc
					(start 411.604206 -214.112602)
					(mid 411.589327 -214.076681)
					(end 411.553406 -214.061802)
				)
				(arc
					(start 410.153866 -214.061802)
					(mid 410.117945 -214.076681)
					(end 410.103066 -214.112602)
				)
			)
		)
	)
	(zone
		(layers "In1.Cu" "In2.Cu")
		(hatch none 0.5)
		(connect_pads
			(clearance 0)
		)
		(min_thickness 0.25)
		(keepout
			(tracks not_allowed)
			(vias allowed)
			(pads allowed)
			(copperpour not_allowed)
			(footprints allowed)
		)
		(placement
			(enabled no)
			(sheetname "")
		)
		(fill yes
			(thermal_gap 0.5)
			(thermal_bridge_width 0.5)
			(island_removal_mode 0)
		)
		(polygon
			(pts
				(arc
					(start 308.136798 -211.971382)
					(mid 308.151677 -212.007303)
					(end 308.187598 -212.022182)
				)
				(arc
					(start 309.587138 -212.022182)
					(mid 309.623059 -212.007303)
					(end 309.637938 -211.971382)
				)
				(arc
					(start 309.637938 -211.562442)
					(mid 309.623059 -211.526521)
					(end 309.587138 -211.511642)
				)
				(arc
					(start 308.187598 -211.511642)
					(mid 308.151677 -211.526521)
					(end 308.136798 -211.562442)
				)
			)
		)
	)
	(zone
		(layers "In1.Cu" "In2.Cu")
		(hatch none 0.5)
		(connect_pads
			(clearance 0)
		)
		(min_thickness 0.25)
		(keepout
			(tracks not_allowed)
			(vias allowed)
			(pads allowed)
			(copperpour not_allowed)
			(footprints allowed)
		)
		(placement
			(enabled no)
			(sheetname "")
		)
		(fill yes
			(thermal_gap 0.5)
			(thermal_bridge_width 0.5)
			(island_removal_mode 0)
		)
		(polygon
			(pts
				(arc
					(start 289.605466 -229.821486)
					(mid 289.620345 -229.857407)
					(end 289.656266 -229.872286)
				)
				(arc
					(start 291.055806 -229.872286)
					(mid 291.091727 -229.857407)
					(end 291.106606 -229.821486)
				)
				(arc
					(start 291.106606 -229.412546)
					(mid 291.091727 -229.376625)
					(end 291.055806 -229.361746)
				)
				(arc
					(start 289.656266 -229.361746)
					(mid 289.620345 -229.376625)
					(end 289.605466 -229.412546)
				)
			)
		)
	)
	(zone
		(layers "In1.Cu" "In2.Cu")
		(hatch none 0.5)
		(connect_pads
			(clearance 0)
		)
		(min_thickness 0.25)
		(keepout
			(tracks not_allowed)
			(vias allowed)
			(pads allowed)
			(copperpour not_allowed)
			(footprints allowed)
		)
		(placement
			(enabled no)
			(sheetname "")
		)
		(fill yes
			(thermal_gap 0.5)
			(thermal_bridge_width 0.5)
			(island_removal_mode 0)
		)
		(polygon
			(pts
				(arc
					(start 421.090598 -259.57149)
					(mid 421.105477 -259.607411)
					(end 421.141398 -259.62229)
				)
				(arc
					(start 422.540938 -259.62229)
					(mid 422.576859 -259.607411)
					(end 422.591738 -259.57149)
				)
				(arc
					(start 422.591738 -259.16255)
					(mid 422.576859 -259.126629)
					(end 422.540938 -259.11175)
				)
				(arc
					(start 421.141398 -259.11175)
					(mid 421.105477 -259.126629)
					(end 421.090598 -259.16255)
				)
			)
		)
	)
	(zone
		(layers "In1.Cu" "In2.Cu")
		(hatch none 0.5)
		(connect_pads
			(clearance 0)
		)
		(min_thickness 0.25)
		(keepout
			(tracks not_allowed)
			(vias allowed)
			(pads allowed)
			(copperpour not_allowed)
			(footprints allowed)
		)
		(placement
			(enabled no)
			(sheetname "")
		)
		(fill yes
			(thermal_gap 0.5)
			(thermal_bridge_width 0.5)
			(island_removal_mode 0)
		)
		(polygon
			(pts
				(arc
					(start 410.103066 -229.821486)
					(mid 410.117945 -229.857407)
					(end 410.153866 -229.872286)
				)
				(arc
					(start 411.553406 -229.872286)
					(mid 411.589327 -229.857407)
					(end 411.604206 -229.821486)
				)
				(arc
					(start 411.604206 -229.412546)
					(mid 411.589327 -229.376625)
					(end 411.553406 -229.361746)
				)
				(arc
					(start 410.153866 -229.361746)
					(mid 410.117945 -229.376625)
					(end 410.103066 -229.412546)
				)
			)
		)
	)
	(zone
		(layers "In1.Cu" "In2.Cu")
		(hatch none 0.5)
		(connect_pads
			(clearance 0)
		)
		(min_thickness 0.25)
		(keepout
			(tracks not_allowed)
			(vias allowed)
			(pads allowed)
			(copperpour not_allowed)
			(footprints allowed)
		)
		(placement
			(enabled no)
			(sheetname "")
		)
		(fill yes
			(thermal_gap 0.5)
			(thermal_bridge_width 0.5)
			(island_removal_mode 0)
		)
		(polygon
			(pts
				(arc
					(start 266.974066 -267.221462)
					(mid 266.988945 -267.257383)
					(end 267.024866 -267.272262)
				)
				(arc
					(start 268.424406 -267.272262)
					(mid 268.460327 -267.257383)
					(end 268.475206 -267.221462)
				)
				(arc
					(start 268.475206 -266.812522)
					(mid 268.460327 -266.776601)
					(end 268.424406 -266.761722)
				)
				(arc
					(start 267.024866 -266.761722)
					(mid 266.988945 -266.776601)
					(end 266.974066 -266.812522)
				)
			)
		)
	)
	(zone
		(layers "In1.Cu" "In2.Cu")
		(hatch none 0.5)
		(connect_pads
			(clearance 0)
		)
		(min_thickness 0.25)
		(keepout
			(tracks not_allowed)
			(vias allowed)
			(pads allowed)
			(copperpour not_allowed)
			(footprints allowed)
		)
		(placement
			(enabled no)
			(sheetname "")
		)
		(fill yes
			(thermal_gap 0.5)
			(thermal_bridge_width 0.5)
			(island_removal_mode 0)
		)
		(polygon
			(pts
				(arc
					(start 195.78193 -290.171378)
					(mid 195.796809 -290.207299)
					(end 195.83273 -290.222178)
				)
				(arc
					(start 197.23227 -290.222178)
					(mid 197.268191 -290.207299)
					(end 197.28307 -290.171378)
				)
				(arc
					(start 197.28307 -289.762438)
					(mid 197.268191 -289.726517)
					(end 197.23227 -289.711638)
				)
				(arc
					(start 195.83273 -289.711638)
					(mid 195.796809 -289.726517)
					(end 195.78193 -289.762438)
				)
			)
		)
	)
	(zone
		(layers "In1.Cu" "In2.Cu")
		(hatch none 0.5)
		(connect_pads
			(clearance 0)
		)
		(min_thickness 0.25)
		(keepout
			(tracks not_allowed)
			(vias allowed)
			(pads allowed)
			(copperpour not_allowed)
			(footprints allowed)
		)
		(placement
			(enabled no)
			(sheetname "")
		)
		(fill yes
			(thermal_gap 0.5)
			(thermal_bridge_width 0.5)
			(island_removal_mode 0)
		)
		(polygon
			(pts
				(arc
					(start 458.809598 -241.721386)
					(mid 458.824477 -241.757307)
					(end 458.860398 -241.772186)
				)
				(arc
					(start 460.259938 -241.772186)
					(mid 460.295859 -241.757307)
					(end 460.310738 -241.721386)
				)
				(arc
					(start 460.310738 -241.312446)
					(mid 460.295859 -241.276525)
					(end 460.259938 -241.261646)
				)
				(arc
					(start 458.860398 -241.261646)
					(mid 458.824477 -241.276525)
					(end 458.809598 -241.312446)
				)
			)
		)
	)
	(zone
		(layers "In1.Cu" "In2.Cu")
		(hatch none 0.5)
		(connect_pads
			(clearance 0)
		)
		(min_thickness 0.25)
		(keepout
			(tracks not_allowed)
			(vias allowed)
			(pads allowed)
			(copperpour not_allowed)
			(footprints allowed)
		)
		(placement
			(enabled no)
			(sheetname "")
		)
		(fill yes
			(thermal_gap 0.5)
			(thermal_bridge_width 0.5)
			(island_removal_mode 0)
		)
		(polygon
			(pts
				(arc
					(start 56.752998 -306.32146)
					(mid 56.767877 -306.357381)
					(end 56.803798 -306.37226)
				)
				(arc
					(start 58.203338 -306.37226)
					(mid 58.239259 -306.357381)
					(end 58.254138 -306.32146)
				)
				(arc
					(start 58.254138 -305.91252)
					(mid 58.239259 -305.876599)
					(end 58.203338 -305.86172)
				)
				(arc
					(start 56.803798 -305.86172)
					(mid 56.767877 -305.876599)
					(end 56.752998 -305.91252)
				)
			)
		)
	)
	(zone
		(layers "In1.Cu" "In2.Cu")
		(hatch none 0.5)
		(connect_pads
			(clearance 0)
		)
		(min_thickness 0.25)
		(keepout
			(tracks not_allowed)
			(vias allowed)
			(pads allowed)
			(copperpour not_allowed)
			(footprints allowed)
		)
		(placement
			(enabled no)
			(sheetname "")
		)
		(fill yes
			(thermal_gap 0.5)
			(thermal_bridge_width 0.5)
			(island_removal_mode 0)
		)
		(polygon
			(pts
				(arc
					(start 56.752998 -276.571456)
					(mid 56.767877 -276.607377)
					(end 56.803798 -276.622256)
				)
				(arc
					(start 58.203338 -276.622256)
					(mid 58.239259 -276.607377)
					(end 58.254138 -276.571456)
				)
				(arc
					(start 58.254138 -276.162516)
					(mid 58.239259 -276.126595)
					(end 58.203338 -276.111716)
				)
				(arc
					(start 56.803798 -276.111716)
					(mid 56.767877 -276.126595)
					(end 56.752998 -276.162516)
				)
			)
		)
	)
	(zone
		(layers "In1.Cu" "In2.Cu")
		(hatch none 0.5)
		(connect_pads
			(clearance 0)
		)
		(min_thickness 0.25)
		(keepout
			(tracks not_allowed)
			(vias allowed)
			(pads allowed)
			(copperpour not_allowed)
			(footprints allowed)
		)
		(placement
			(enabled no)
			(sheetname "")
		)
		(fill yes
			(thermal_gap 0.5)
			(thermal_bridge_width 0.5)
			(island_removal_mode 0)
		)
		(polygon
			(pts
				(arc
					(start 458.809598 -202.621388)
					(mid 458.824477 -202.657309)
					(end 458.860398 -202.672188)
				)
				(arc
					(start 460.259938 -202.672188)
					(mid 460.295859 -202.657309)
					(end 460.310738 -202.621388)
				)
				(arc
					(start 460.310738 -202.212448)
					(mid 460.295859 -202.176527)
					(end 460.259938 -202.161648)
				)
				(arc
					(start 458.860398 -202.161648)
					(mid 458.824477 -202.176527)
					(end 458.809598 -202.212448)
				)
			)
		)
	)
	(zone
		(layers "In1.Cu" "In2.Cu")
		(hatch none 0.5)
		(connect_pads
			(clearance 0)
		)
		(min_thickness 0.25)
		(keepout
			(tracks not_allowed)
			(vias allowed)
			(pads allowed)
			(copperpour not_allowed)
			(footprints allowed)
		)
		(placement
			(enabled no)
			(sheetname "")
		)
		(fill yes
			(thermal_gap 0.5)
			(thermal_bridge_width 0.5)
			(island_removal_mode 0)
		)
		(polygon
			(pts
				(arc
					(start 425.190666 -222.171514)
					(mid 425.205545 -222.207435)
					(end 425.241466 -222.222314)
				)
				(arc
					(start 426.641006 -222.222314)
					(mid 426.676927 -222.207435)
					(end 426.691806 -222.171514)
				)
				(arc
					(start 426.691806 -221.762574)
					(mid 426.676927 -221.726653)
					(end 426.641006 -221.711774)
				)
				(arc
					(start 425.241466 -221.711774)
					(mid 425.205545 -221.726653)
					(end 425.190666 -221.762574)
				)
			)
		)
	)
	(zone
		(layers "In1.Cu" "In2.Cu")
		(hatch none 0.5)
		(connect_pads
			(clearance 0)
		)
		(min_thickness 0.25)
		(keepout
			(tracks not_allowed)
			(vias allowed)
			(pads allowed)
			(copperpour not_allowed)
			(footprints allowed)
		)
		(placement
			(enabled no)
			(sheetname "")
		)
		(fill yes
			(thermal_gap 0.5)
			(thermal_bridge_width 0.5)
			(island_removal_mode 0)
		)
		(polygon
			(pts
				(arc
					(start 162.162998 -302.921416)
					(mid 162.177877 -302.957337)
					(end 162.213798 -302.972216)
				)
				(arc
					(start 163.613338 -302.972216)
					(mid 163.649259 -302.957337)
					(end 163.664138 -302.921416)
				)
				(arc
					(start 163.664138 -302.512476)
					(mid 163.649259 -302.476555)
					(end 163.613338 -302.461676)
				)
				(arc
					(start 162.213798 -302.461676)
					(mid 162.177877 -302.476555)
					(end 162.162998 -302.512476)
				)
			)
		)
	)
	(zone
		(layers "In1.Cu" "In2.Cu")
		(hatch none 0.5)
		(connect_pads
			(clearance 0)
		)
		(min_thickness 0.25)
		(keepout
			(tracks not_allowed)
			(vias allowed)
			(pads allowed)
			(copperpour not_allowed)
			(footprints allowed)
		)
		(placement
			(enabled no)
			(sheetname "")
		)
		(fill yes
			(thermal_gap 0.5)
			(thermal_bridge_width 0.5)
			(island_removal_mode 0)
		)
		(polygon
			(pts
				(arc
					(start 428.634398 -207.721454)
					(mid 428.649277 -207.757375)
					(end 428.685198 -207.772254)
				)
				(arc
					(start 430.084738 -207.772254)
					(mid 430.120659 -207.757375)
					(end 430.135538 -207.721454)
				)
				(arc
					(start 430.135538 -207.312514)
					(mid 430.120659 -207.276593)
					(end 430.084738 -207.261714)
				)
				(arc
					(start 428.685198 -207.261714)
					(mid 428.649277 -207.276593)
					(end 428.634398 -207.312514)
				)
			)
		)
	)
	(zone
		(layers "In1.Cu" "In2.Cu")
		(hatch none 0.5)
		(connect_pads
			(clearance 0)
		)
		(min_thickness 0.25)
		(keepout
			(tracks not_allowed)
			(vias allowed)
			(pads allowed)
			(copperpour not_allowed)
			(footprints allowed)
		)
		(placement
			(enabled no)
			(sheetname "")
		)
		(fill yes
			(thermal_gap 0.5)
			(thermal_bridge_width 0.5)
			(island_removal_mode 0)
		)
		(polygon
			(pts
				(arc
					(start 285.505398 -262.971534)
					(mid 285.520277 -263.007455)
					(end 285.556198 -263.022334)
				)
				(arc
					(start 286.955738 -263.022334)
					(mid 286.991659 -263.007455)
					(end 287.006538 -262.971534)
				)
				(arc
					(start 287.006538 -262.562594)
					(mid 286.991659 -262.526673)
					(end 286.955738 -262.511794)
				)
				(arc
					(start 285.556198 -262.511794)
					(mid 285.520277 -262.526673)
					(end 285.505398 -262.562594)
				)
			)
		)
	)
	(zone
		(layers "In1.Cu" "In2.Cu")
		(hatch none 0.5)
		(connect_pads
			(clearance 0)
		)
		(min_thickness 0.25)
		(keepout
			(tracks not_allowed)
			(vias allowed)
			(pads allowed)
			(copperpour not_allowed)
			(footprints allowed)
		)
		(placement
			(enabled no)
			(sheetname "")
		)
		(fill yes
			(thermal_gap 0.5)
			(thermal_bridge_width 0.5)
			(island_removal_mode 0)
		)
		(polygon
			(pts
				(arc
					(start 262.873998 -202.621388)
					(mid 262.888877 -202.657309)
					(end 262.924798 -202.672188)
				)
				(arc
					(start 264.324338 -202.672188)
					(mid 264.360259 -202.657309)
					(end 264.375138 -202.621388)
				)
				(arc
					(start 264.375138 -202.212448)
					(mid 264.360259 -202.176527)
					(end 264.324338 -202.161648)
				)
				(arc
					(start 262.924798 -202.161648)
					(mid 262.888877 -202.176527)
					(end 262.873998 -202.212448)
				)
			)
		)
	)
	(zone
		(layers "In1.Cu" "In2.Cu")
		(hatch none 0.5)
		(connect_pads
			(clearance 0)
		)
		(min_thickness 0.25)
		(keepout
			(tracks not_allowed)
			(vias allowed)
			(pads allowed)
			(copperpour not_allowed)
			(footprints allowed)
		)
		(placement
			(enabled no)
			(sheetname "")
		)
		(fill yes
			(thermal_gap 0.5)
			(thermal_bridge_width 0.5)
			(island_removal_mode 0)
		)
		(polygon
			(pts
				(arc
					(start 406.002998 -307.171344)
					(mid 406.017877 -307.207265)
					(end 406.053798 -307.222144)
				)
				(arc
					(start 407.453338 -307.222144)
					(mid 407.489259 -307.207265)
					(end 407.504138 -307.171344)
				)
				(arc
					(start 407.504138 -306.762404)
					(mid 407.489259 -306.726483)
					(end 407.453338 -306.711604)
				)
				(arc
					(start 406.053798 -306.711604)
					(mid 406.017877 -306.726483)
					(end 406.002998 -306.762404)
				)
			)
		)
	)
	(zone
		(layers "In1.Cu" "In2.Cu")
		(hatch none 0.5)
		(connect_pads
			(clearance 0)
		)
		(min_thickness 0.25)
		(keepout
			(tracks not_allowed)
			(vias allowed)
			(pads allowed)
			(copperpour not_allowed)
			(footprints allowed)
		)
		(placement
			(enabled no)
			(sheetname "")
		)
		(fill yes
			(thermal_gap 0.5)
			(thermal_bridge_width 0.5)
			(island_removal_mode 0)
		)
		(polygon
			(pts
				(arc
					(start 428.634398 -277.42134)
					(mid 428.649277 -277.457261)
					(end 428.685198 -277.47214)
				)
				(arc
					(start 430.084738 -277.47214)
					(mid 430.120659 -277.457261)
					(end 430.135538 -277.42134)
				)
				(arc
					(start 430.135538 -277.0124)
					(mid 430.120659 -276.976479)
					(end 430.084738 -276.9616)
				)
				(arc
					(start 428.685198 -276.9616)
					(mid 428.649277 -276.976479)
					(end 428.634398 -277.0124)
				)
			)
		)
	)
	(zone
		(layers "In1.Cu" "In2.Cu")
		(hatch none 0.5)
		(connect_pads
			(clearance 0)
		)
		(min_thickness 0.25)
		(keepout
			(tracks not_allowed)
			(vias allowed)
			(pads allowed)
			(copperpour not_allowed)
			(footprints allowed)
		)
		(placement
			(enabled no)
			(sheetname "")
		)
		(fill yes
			(thermal_gap 0.5)
			(thermal_bridge_width 0.5)
			(island_removal_mode 0)
		)
		(polygon
			(pts
				(arc
					(start 199.881998 -212.82152)
					(mid 199.896877 -212.857441)
					(end 199.932798 -212.87232)
				)
				(arc
					(start 201.332338 -212.87232)
					(mid 201.368259 -212.857441)
					(end 201.383138 -212.82152)
				)
				(arc
					(start 201.383138 -212.41258)
					(mid 201.368259 -212.376659)
					(end 201.332338 -212.36178)
				)
				(arc
					(start 199.932798 -212.36178)
					(mid 199.896877 -212.376659)
					(end 199.881998 -212.41258)
				)
			)
		)
	)
	(zone
		(layers "In1.Cu" "In2.Cu")
		(hatch none 0.5)
		(connect_pads
			(clearance 0)
		)
		(min_thickness 0.25)
		(keepout
			(tracks not_allowed)
			(vias allowed)
			(pads allowed)
			(copperpour not_allowed)
			(footprints allowed)
		)
		(placement
			(enabled no)
			(sheetname "")
		)
		(fill yes
			(thermal_gap 0.5)
			(thermal_bridge_width 0.5)
			(island_removal_mode 0)
		)
		(polygon
			(pts
				(arc
					(start 458.809598 -230.67137)
					(mid 458.824477 -230.707291)
					(end 458.860398 -230.72217)
				)
				(arc
					(start 460.259938 -230.72217)
					(mid 460.295859 -230.707291)
					(end 460.310738 -230.67137)
				)
				(arc
					(start 460.310738 -230.26243)
					(mid 460.295859 -230.226509)
					(end 460.259938 -230.21163)
				)
				(arc
					(start 458.860398 -230.21163)
					(mid 458.824477 -230.226509)
					(end 458.809598 -230.26243)
				)
			)
		)
	)
	(zone
		(layers "In1.Cu" "In2.Cu")
		(hatch none 0.5)
		(connect_pads
			(clearance 0)
		)
		(min_thickness 0.25)
		(keepout
			(tracks not_allowed)
			(vias allowed)
			(pads allowed)
			(copperpour not_allowed)
			(footprints allowed)
		)
		(placement
			(enabled no)
			(sheetname "")
		)
		(fill yes
			(thermal_gap 0.5)
			(thermal_bridge_width 0.5)
			(island_removal_mode 0)
		)
		(polygon
			(pts
				(arc
					(start 274.517866 -274.871434)
					(mid 274.532745 -274.907355)
					(end 274.568666 -274.922234)
				)
				(arc
					(start 275.968206 -274.922234)
					(mid 276.004127 -274.907355)
					(end 276.019006 -274.871434)
				)
				(arc
					(start 276.019006 -274.462494)
					(mid 276.004127 -274.426573)
					(end 275.968206 -274.411694)
				)
				(arc
					(start 274.568666 -274.411694)
					(mid 274.532745 -274.426573)
					(end 274.517866 -274.462494)
				)
			)
		)
	)
	(zone
		(layers "In1.Cu" "In2.Cu")
		(hatch none 0.5)
		(connect_pads
			(clearance 0)
		)
		(min_thickness 0.25)
		(keepout
			(tracks not_allowed)
			(vias allowed)
			(pads allowed)
			(copperpour not_allowed)
			(footprints allowed)
		)
		(placement
			(enabled no)
			(sheetname "")
		)
		(fill yes
			(thermal_gap 0.5)
			(thermal_bridge_width 0.5)
			(island_removal_mode 0)
		)
		(polygon
			(pts
				(arc
					(start 7.39013 -290.171378)
					(mid 7.405009 -290.207299)
					(end 7.44093 -290.222178)
				)
				(arc
					(start 8.84047 -290.222178)
					(mid 8.876391 -290.207299)
					(end 8.89127 -290.171378)
				)
				(arc
					(start 8.89127 -289.762438)
					(mid 8.876391 -289.726517)
					(end 8.84047 -289.711638)
				)
				(arc
					(start 7.44093 -289.711638)
					(mid 7.405009 -289.726517)
					(end 7.39013 -289.762438)
				)
			)
		)
	)
	(zone
		(layers "In1.Cu" "In2.Cu")
		(hatch none 0.5)
		(connect_pads
			(clearance 0)
		)
		(min_thickness 0.25)
		(keepout
			(tracks not_allowed)
			(vias allowed)
			(pads allowed)
			(copperpour not_allowed)
			(footprints allowed)
		)
		(placement
			(enabled no)
			(sheetname "")
		)
		(fill yes
			(thermal_gap 0.5)
			(thermal_bridge_width 0.5)
			(island_removal_mode 0)
		)
		(polygon
			(pts
				(arc
					(start 56.752998 -300.37151)
					(mid 56.767877 -300.407431)
					(end 56.803798 -300.42231)
				)
				(arc
					(start 58.203338 -300.42231)
					(mid 58.239259 -300.407431)
					(end 58.254138 -300.37151)
				)
				(arc
					(start 58.254138 -299.96257)
					(mid 58.239259 -299.926649)
					(end 58.203338 -299.91177)
				)
				(arc
					(start 56.803798 -299.91177)
					(mid 56.767877 -299.926649)
					(end 56.752998 -299.96257)
				)
			)
		)
	)
	(zone
		(layers "In1.Cu" "In2.Cu")
		(hatch none 0.5)
		(connect_pads
			(clearance 0)
		)
		(min_thickness 0.25)
		(keepout
			(tracks not_allowed)
			(vias allowed)
			(pads allowed)
			(copperpour not_allowed)
			(footprints allowed)
		)
		(placement
			(enabled no)
			(sheetname "")
		)
		(fill yes
			(thermal_gap 0.5)
			(thermal_bridge_width 0.5)
			(island_removal_mode 0)
		)
		(polygon
			(pts
				(arc
					(start 34.121598 -298.671488)
					(mid 34.136477 -298.707409)
					(end 34.172398 -298.722288)
				)
				(arc
					(start 35.571938 -298.722288)
					(mid 35.607859 -298.707409)
					(end 35.622738 -298.671488)
				)
				(arc
					(start 35.622738 -298.262548)
					(mid 35.607859 -298.226627)
					(end 35.571938 -298.211748)
				)
				(arc
					(start 34.172398 -298.211748)
					(mid 34.136477 -298.226627)
					(end 34.121598 -298.262548)
				)
			)
		)
	)
	(zone
		(layers "In1.Cu" "In2.Cu")
		(hatch none 0.5)
		(connect_pads
			(clearance 0)
		)
		(min_thickness 0.25)
		(keepout
			(tracks not_allowed)
			(vias allowed)
			(pads allowed)
			(copperpour not_allowed)
			(footprints allowed)
		)
		(placement
			(enabled no)
			(sheetname "")
		)
		(fill yes
			(thermal_gap 0.5)
			(thermal_bridge_width 0.5)
			(island_removal_mode 0)
		)
		(polygon
			(pts
				(arc
					(start 308.136798 -294.421306)
					(mid 308.151677 -294.457227)
					(end 308.187598 -294.472106)
				)
				(arc
					(start 309.587138 -294.472106)
					(mid 309.623059 -294.457227)
					(end 309.637938 -294.421306)
				)
				(arc
					(start 309.637938 -294.012366)
					(mid 309.623059 -293.976445)
					(end 309.587138 -293.961566)
				)
				(arc
					(start 308.187598 -293.961566)
					(mid 308.151677 -293.976445)
					(end 308.136798 -294.012366)
				)
			)
		)
	)
	(zone
		(layers "In1.Cu" "In2.Cu")
		(hatch none 0.5)
		(connect_pads
			(clearance 0)
		)
		(min_thickness 0.25)
		(keepout
			(tracks not_allowed)
			(vias allowed)
			(pads allowed)
			(copperpour not_allowed)
			(footprints allowed)
		)
		(placement
			(enabled no)
			(sheetname "")
		)
		(fill yes
			(thermal_gap 0.5)
			(thermal_bridge_width 0.5)
			(island_removal_mode 0)
		)
		(polygon
			(pts
				(arc
					(start 421.090598 -240.021364)
					(mid 421.105477 -240.057285)
					(end 421.141398 -240.072164)
				)
				(arc
					(start 422.540938 -240.072164)
					(mid 422.576859 -240.057285)
					(end 422.591738 -240.021364)
				)
				(arc
					(start 422.591738 -239.612424)
					(mid 422.576859 -239.576503)
					(end 422.540938 -239.561624)
				)
				(arc
					(start 421.141398 -239.561624)
					(mid 421.105477 -239.576503)
					(end 421.090598 -239.612424)
				)
			)
		)
	)
	(zone
		(layers "In1.Cu" "In2.Cu")
		(hatch none 0.5)
		(connect_pads
			(clearance 0)
		)
		(min_thickness 0.25)
		(keepout
			(tracks not_allowed)
			(vias allowed)
			(pads allowed)
			(copperpour not_allowed)
			(footprints allowed)
		)
		(placement
			(enabled no)
			(sheetname "")
		)
		(fill yes
			(thermal_gap 0.5)
			(thermal_bridge_width 0.5)
			(island_removal_mode 0)
		)
		(polygon
			(pts
				(arc
					(start 425.190666 -293.571422)
					(mid 425.205545 -293.607343)
					(end 425.241466 -293.622222)
				)
				(arc
					(start 426.641006 -293.622222)
					(mid 426.676927 -293.607343)
					(end 426.691806 -293.571422)
				)
				(arc
					(start 426.691806 -293.162482)
					(mid 426.676927 -293.126561)
					(end 426.641006 -293.111682)
				)
				(arc
					(start 425.241466 -293.111682)
					(mid 425.205545 -293.126561)
					(end 425.190666 -293.162482)
				)
			)
		)
	)
	(zone
		(layers "In1.Cu" "In2.Cu")
		(hatch none 0.5)
		(connect_pads
			(clearance 0)
		)
		(min_thickness 0.25)
		(keepout
			(tracks not_allowed)
			(vias allowed)
			(pads allowed)
			(copperpour not_allowed)
			(footprints allowed)
		)
		(placement
			(enabled no)
			(sheetname "")
		)
		(fill yes
			(thermal_gap 0.5)
			(thermal_bridge_width 0.5)
			(island_removal_mode 0)
		)
		(polygon
			(pts
				(arc
					(start 41.665398 -268.921484)
					(mid 41.680277 -268.957405)
					(end 41.716198 -268.972284)
				)
				(arc
					(start 43.115738 -268.972284)
					(mid 43.151659 -268.957405)
					(end 43.166538 -268.921484)
				)
				(arc
					(start 43.166538 -268.512544)
					(mid 43.151659 -268.476623)
					(end 43.115738 -268.461744)
				)
				(arc
					(start 41.716198 -268.461744)
					(mid 41.680277 -268.476623)
					(end 41.665398 -268.512544)
				)
			)
		)
	)
	(zone
		(layers "In1.Cu" "In2.Cu")
		(hatch none 0.5)
		(connect_pads
			(clearance 0)
		)
		(min_thickness 0.25)
		(keepout
			(tracks not_allowed)
			(vias allowed)
			(pads allowed)
			(copperpour not_allowed)
			(footprints allowed)
		)
		(placement
			(enabled no)
			(sheetname "")
		)
		(fill yes
			(thermal_gap 0.5)
			(thermal_bridge_width 0.5)
			(island_removal_mode 0)
		)
		(polygon
			(pts
				(arc
					(start 270.417798 -259.57149)
					(mid 270.432677 -259.607411)
					(end 270.468598 -259.62229)
				)
				(arc
					(start 271.868138 -259.62229)
					(mid 271.904059 -259.607411)
					(end 271.918938 -259.57149)
				)
				(arc
					(start 271.918938 -259.16255)
					(mid 271.904059 -259.126629)
					(end 271.868138 -259.11175)
				)
				(arc
					(start 270.468598 -259.11175)
					(mid 270.432677 -259.126629)
					(end 270.417798 -259.16255)
				)
			)
		)
	)
	(zone
		(layers "In1.Cu" "In2.Cu")
		(hatch none 0.5)
		(connect_pads
			(clearance 0)
		)
		(min_thickness 0.25)
		(keepout
			(tracks not_allowed)
			(vias allowed)
			(pads allowed)
			(copperpour not_allowed)
			(footprints allowed)
		)
		(placement
			(enabled no)
			(sheetname "")
		)
		(fill yes
			(thermal_gap 0.5)
			(thermal_bridge_width 0.5)
			(island_removal_mode 0)
		)
		(polygon
			(pts
				(arc
					(start 22.47773 -251.07138)
					(mid 22.492609 -251.107301)
					(end 22.52853 -251.12218)
				)
				(arc
					(start 23.92807 -251.12218)
					(mid 23.963991 -251.107301)
					(end 23.97887 -251.07138)
				)
				(arc
					(start 23.97887 -250.66244)
					(mid 23.963991 -250.626519)
					(end 23.92807 -250.61164)
				)
				(arc
					(start 22.52853 -250.61164)
					(mid 22.492609 -250.626519)
					(end 22.47773 -250.66244)
				)
			)
		)
	)
	(zone
		(layers "In1.Cu" "In2.Cu")
		(hatch none 0.5)
		(connect_pads
			(clearance 0)
		)
		(min_thickness 0.25)
		(keepout
			(tracks not_allowed)
			(vias allowed)
			(pads allowed)
			(copperpour not_allowed)
			(footprints allowed)
		)
		(placement
			(enabled no)
			(sheetname "")
		)
		(fill yes
			(thermal_gap 0.5)
			(thermal_bridge_width 0.5)
			(island_removal_mode 0)
		)
		(polygon
			(pts
				(arc
					(start 282.061666 -218.77147)
					(mid 282.076545 -218.807391)
					(end 282.112466 -218.82227)
				)
				(arc
					(start 283.512006 -218.82227)
					(mid 283.547927 -218.807391)
					(end 283.562806 -218.77147)
				)
				(arc
					(start 283.562806 -218.36253)
					(mid 283.547927 -218.326609)
					(end 283.512006 -218.31173)
				)
				(arc
					(start 282.112466 -218.31173)
					(mid 282.076545 -218.326609)
					(end 282.061666 -218.36253)
				)
			)
		)
	)
	(zone
		(layers "In1.Cu" "In2.Cu")
		(hatch none 0.5)
		(connect_pads
			(clearance 0)
		)
		(min_thickness 0.25)
		(keepout
			(tracks not_allowed)
			(vias allowed)
			(pads allowed)
			(copperpour not_allowed)
			(footprints allowed)
		)
		(placement
			(enabled no)
			(sheetname "")
		)
		(fill yes
			(thermal_gap 0.5)
			(thermal_bridge_width 0.5)
			(island_removal_mode 0)
		)
		(polygon
			(pts
				(arc
					(start 19.033998 -284.221428)
					(mid 19.048877 -284.257349)
					(end 19.084798 -284.272228)
				)
				(arc
					(start 20.484338 -284.272228)
					(mid 20.520259 -284.257349)
					(end 20.535138 -284.221428)
				)
				(arc
					(start 20.535138 -283.812488)
					(mid 20.520259 -283.776567)
					(end 20.484338 -283.761688)
				)
				(arc
					(start 19.084798 -283.761688)
					(mid 19.048877 -283.776567)
					(end 19.033998 -283.812488)
				)
			)
		)
	)
	(zone
		(layers "In1.Cu" "In2.Cu")
		(hatch none 0.5)
		(connect_pads
			(clearance 0)
		)
		(min_thickness 0.25)
		(keepout
			(tracks not_allowed)
			(vias allowed)
			(pads allowed)
			(copperpour not_allowed)
			(footprints allowed)
		)
		(placement
			(enabled no)
			(sheetname "")
		)
		(fill yes
			(thermal_gap 0.5)
			(thermal_bridge_width 0.5)
			(island_removal_mode 0)
		)
		(polygon
			(pts
				(arc
					(start 462.909666 -293.571422)
					(mid 462.924545 -293.607343)
					(end 462.960466 -293.622222)
				)
				(arc
					(start 464.360006 -293.622222)
					(mid 464.395927 -293.607343)
					(end 464.410806 -293.571422)
				)
				(arc
					(start 464.410806 -293.162482)
					(mid 464.395927 -293.126561)
					(end 464.360006 -293.111682)
				)
				(arc
					(start 462.960466 -293.111682)
					(mid 462.924545 -293.126561)
					(end 462.909666 -293.162482)
				)
			)
		)
	)
	(zone
		(layers "In1.Cu" "In2.Cu")
		(hatch none 0.5)
		(connect_pads
			(clearance 0)
		)
		(min_thickness 0.25)
		(keepout
			(tracks not_allowed)
			(vias allowed)
			(pads allowed)
			(copperpour not_allowed)
			(footprints allowed)
		)
		(placement
			(enabled no)
			(sheetname "")
		)
		(fill yes
			(thermal_gap 0.5)
			(thermal_bridge_width 0.5)
			(island_removal_mode 0)
		)
		(polygon
			(pts
				(arc
					(start 22.47773 -207.721454)
					(mid 22.492609 -207.757375)
					(end 22.52853 -207.772254)
				)
				(arc
					(start 23.92807 -207.772254)
					(mid 23.963991 -207.757375)
					(end 23.97887 -207.721454)
				)
				(arc
					(start 23.97887 -207.312514)
					(mid 23.963991 -207.276593)
					(end 23.92807 -207.261714)
				)
				(arc
					(start 22.52853 -207.261714)
					(mid 22.492609 -207.276593)
					(end 22.47773 -207.312514)
				)
			)
		)
	)
	(zone
		(layers "In1.Cu" "In2.Cu")
		(hatch none 0.5)
		(connect_pads
			(clearance 0)
		)
		(min_thickness 0.25)
		(keepout
			(tracks not_allowed)
			(vias allowed)
			(pads allowed)
			(copperpour not_allowed)
			(footprints allowed)
		)
		(placement
			(enabled no)
			(sheetname "")
		)
		(fill yes
			(thermal_gap 0.5)
			(thermal_bridge_width 0.5)
			(island_removal_mode 0)
		)
		(polygon
			(pts
				(arc
					(start 49.209198 -211.121498)
					(mid 49.224077 -211.157419)
					(end 49.259998 -211.172298)
				)
				(arc
					(start 50.659538 -211.172298)
					(mid 50.695459 -211.157419)
					(end 50.710338 -211.121498)
				)
				(arc
					(start 50.710338 -210.712558)
					(mid 50.695459 -210.676637)
					(end 50.659538 -210.661758)
				)
				(arc
					(start 49.259998 -210.661758)
					(mid 49.224077 -210.676637)
					(end 49.209198 -210.712558)
				)
			)
		)
	)
	(zone
		(layers "In1.Cu" "In2.Cu")
		(hatch none 0.5)
		(connect_pads
			(clearance 0)
		)
		(min_thickness 0.25)
		(keepout
			(tracks not_allowed)
			(vias allowed)
			(pads allowed)
			(copperpour not_allowed)
			(footprints allowed)
		)
		(placement
			(enabled no)
			(sheetname "")
		)
		(fill yes
			(thermal_gap 0.5)
			(thermal_bridge_width 0.5)
			(island_removal_mode 0)
		)
		(polygon
			(pts
				(arc
					(start 451.265798 -204.32141)
					(mid 451.280677 -204.357331)
					(end 451.316598 -204.37221)
				)
				(arc
					(start 452.716138 -204.37221)
					(mid 452.752059 -204.357331)
					(end 452.766938 -204.32141)
				)
				(arc
					(start 452.766938 -203.91247)
					(mid 452.752059 -203.876549)
					(end 452.716138 -203.86167)
				)
				(arc
					(start 451.316598 -203.86167)
					(mid 451.280677 -203.876549)
					(end 451.265798 -203.91247)
				)
			)
		)
	)
	(zone
		(layers "In1.Cu" "In2.Cu")
		(hatch none 0.5)
		(connect_pads
			(clearance 0)
		)
		(min_thickness 0.25)
		(keepout
			(tracks not_allowed)
			(vias allowed)
			(pads allowed)
			(copperpour not_allowed)
			(footprints allowed)
		)
		(placement
			(enabled no)
			(sheetname "")
		)
		(fill yes
			(thermal_gap 0.5)
			(thermal_bridge_width 0.5)
			(island_removal_mode 0)
		)
		(polygon
			(pts
				(arc
					(start 14.93393 -200.071482)
					(mid 14.948809 -200.107403)
					(end 14.98473 -200.122282)
				)
				(arc
					(start 16.38427 -200.122282)
					(mid 16.420191 -200.107403)
					(end 16.43507 -200.071482)
				)
				(arc
					(start 16.43507 -199.662542)
					(mid 16.420191 -199.626621)
					(end 16.38427 -199.611742)
				)
				(arc
					(start 14.98473 -199.611742)
					(mid 14.948809 -199.626621)
					(end 14.93393 -199.662542)
				)
			)
		)
	)
	(zone
		(layers "In1.Cu" "In2.Cu")
		(hatch none 0.5)
		(connect_pads
			(clearance 0)
		)
		(min_thickness 0.25)
		(keepout
			(tracks not_allowed)
			(vias allowed)
			(pads allowed)
			(copperpour not_allowed)
			(footprints allowed)
		)
		(placement
			(enabled no)
			(sheetname "")
		)
		(fill yes
			(thermal_gap 0.5)
			(thermal_bridge_width 0.5)
			(island_removal_mode 0)
		)
		(polygon
			(pts
				(arc
					(start 417.646866 -259.57149)
					(mid 417.661745 -259.607411)
					(end 417.697666 -259.62229)
				)
				(arc
					(start 419.097206 -259.62229)
					(mid 419.133127 -259.607411)
					(end 419.148006 -259.57149)
				)
				(arc
					(start 419.148006 -259.16255)
					(mid 419.133127 -259.126629)
					(end 419.097206 -259.11175)
				)
				(arc
					(start 417.697666 -259.11175)
					(mid 417.661745 -259.126629)
					(end 417.646866 -259.16255)
				)
			)
		)
	)
	(zone
		(layers "In1.Cu" "In2.Cu")
		(hatch none 0.5)
		(connect_pads
			(clearance 0)
		)
		(min_thickness 0.25)
		(keepout
			(tracks not_allowed)
			(vias allowed)
			(pads allowed)
			(copperpour not_allowed)
			(footprints allowed)
		)
		(placement
			(enabled no)
			(sheetname "")
		)
		(fill yes
			(thermal_gap 0.5)
			(thermal_bridge_width 0.5)
			(island_removal_mode 0)
		)
		(polygon
			(pts
				(arc
					(start 195.78193 -200.921366)
					(mid 195.796809 -200.957287)
					(end 195.83273 -200.972166)
				)
				(arc
					(start 197.23227 -200.972166)
					(mid 197.268191 -200.957287)
					(end 197.28307 -200.921366)
				)
				(arc
					(start 197.28307 -200.512426)
					(mid 197.268191 -200.476505)
					(end 197.23227 -200.461626)
				)
				(arc
					(start 195.83273 -200.461626)
					(mid 195.796809 -200.476505)
					(end 195.78193 -200.512426)
				)
			)
		)
	)
	(zone
		(layers "In1.Cu" "In2.Cu")
		(hatch none 0.5)
		(connect_pads
			(clearance 0)
		)
		(min_thickness 0.25)
		(keepout
			(tracks not_allowed)
			(vias allowed)
			(pads allowed)
			(copperpour not_allowed)
			(footprints allowed)
		)
		(placement
			(enabled no)
			(sheetname "")
		)
		(fill yes
			(thermal_gap 0.5)
			(thermal_bridge_width 0.5)
			(island_removal_mode 0)
		)
		(polygon
			(pts
				(arc
					(start 52.65293 -297.82135)
					(mid 52.667809 -297.857271)
					(end 52.70373 -297.87215)
				)
				(arc
					(start 54.10327 -297.87215)
					(mid 54.139191 -297.857271)
					(end 54.15407 -297.82135)
				)
				(arc
					(start 54.15407 -297.41241)
					(mid 54.139191 -297.376489)
					(end 54.10327 -297.36161)
				)
				(arc
					(start 52.70373 -297.36161)
					(mid 52.667809 -297.376489)
					(end 52.65293 -297.41241)
				)
			)
		)
	)
	(zone
		(layers "In1.Cu" "In2.Cu")
		(hatch none 0.5)
		(connect_pads
			(clearance 0)
		)
		(min_thickness 0.25)
		(keepout
			(tracks not_allowed)
			(vias allowed)
			(pads allowed)
			(copperpour not_allowed)
			(footprints allowed)
		)
		(placement
			(enabled no)
			(sheetname "")
		)
		(fill yes
			(thermal_gap 0.5)
			(thermal_bridge_width 0.5)
			(island_removal_mode 0)
		)
		(polygon
			(pts
				(arc
					(start 173.15053 -238.321342)
					(mid 173.165409 -238.357263)
					(end 173.20133 -238.372142)
				)
				(arc
					(start 174.60087 -238.372142)
					(mid 174.636791 -238.357263)
					(end 174.65167 -238.321342)
				)
				(arc
					(start 174.65167 -237.912402)
					(mid 174.636791 -237.876481)
					(end 174.60087 -237.861602)
				)
				(arc
					(start 173.20133 -237.861602)
					(mid 173.165409 -237.876481)
					(end 173.15053 -237.912402)
				)
			)
		)
	)
	(zone
		(layers "In1.Cu" "In2.Cu")
		(hatch none 0.5)
		(connect_pads
			(clearance 0)
		)
		(min_thickness 0.25)
		(keepout
			(tracks not_allowed)
			(vias allowed)
			(pads allowed)
			(copperpour not_allowed)
			(footprints allowed)
		)
		(placement
			(enabled no)
			(sheetname "")
		)
		(fill yes
			(thermal_gap 0.5)
			(thermal_bridge_width 0.5)
			(island_removal_mode 0)
		)
		(polygon
			(pts
				(arc
					(start 300.592998 -230.67137)
					(mid 300.607877 -230.707291)
					(end 300.643798 -230.72217)
				)
				(arc
					(start 302.043338 -230.72217)
					(mid 302.079259 -230.707291)
					(end 302.094138 -230.67137)
				)
				(arc
					(start 302.094138 -230.26243)
					(mid 302.079259 -230.226509)
					(end 302.043338 -230.21163)
				)
				(arc
					(start 300.643798 -230.21163)
					(mid 300.607877 -230.226509)
					(end 300.592998 -230.26243)
				)
			)
		)
	)
	(zone
		(layers "In1.Cu" "In2.Cu")
		(hatch none 0.5)
		(connect_pads
			(clearance 0)
		)
		(min_thickness 0.25)
		(keepout
			(tracks not_allowed)
			(vias allowed)
			(pads allowed)
			(copperpour not_allowed)
			(footprints allowed)
		)
		(placement
			(enabled no)
			(sheetname "")
		)
		(fill yes
			(thermal_gap 0.5)
			(thermal_bridge_width 0.5)
			(island_removal_mode 0)
		)
		(polygon
			(pts
				(arc
					(start 199.881998 -274.02155)
					(mid 199.896877 -274.057471)
					(end 199.932798 -274.07235)
				)
				(arc
					(start 201.332338 -274.07235)
					(mid 201.368259 -274.057471)
					(end 201.383138 -274.02155)
				)
				(arc
					(start 201.383138 -273.61261)
					(mid 201.368259 -273.576689)
					(end 201.332338 -273.56181)
				)
				(arc
					(start 199.932798 -273.56181)
					(mid 199.896877 -273.576689)
					(end 199.881998 -273.61261)
				)
			)
		)
	)
	(zone
		(layers "In1.Cu" "In2.Cu")
		(hatch none 0.5)
		(connect_pads
			(clearance 0)
		)
		(min_thickness 0.25)
		(keepout
			(tracks not_allowed)
			(vias allowed)
			(pads allowed)
			(copperpour not_allowed)
			(footprints allowed)
		)
		(placement
			(enabled no)
			(sheetname "")
		)
		(fill yes
			(thermal_gap 0.5)
			(thermal_bridge_width 0.5)
			(island_removal_mode 0)
		)
		(polygon
			(pts
				(arc
					(start 210.86953 -226.421442)
					(mid 210.884409 -226.457363)
					(end 210.92033 -226.472242)
				)
				(arc
					(start 212.31987 -226.472242)
					(mid 212.355791 -226.457363)
					(end 212.37067 -226.421442)
				)
				(arc
					(start 212.37067 -226.012502)
					(mid 212.355791 -225.976581)
					(end 212.31987 -225.961702)
				)
				(arc
					(start 210.92033 -225.961702)
					(mid 210.884409 -225.976581)
					(end 210.86953 -226.012502)
				)
			)
		)
	)
	(zone
		(layers "In1.Cu" "In2.Cu")
		(hatch none 0.5)
		(connect_pads
			(clearance 0)
		)
		(min_thickness 0.25)
		(keepout
			(tracks not_allowed)
			(vias allowed)
			(pads allowed)
			(copperpour not_allowed)
			(footprints allowed)
		)
		(placement
			(enabled no)
			(sheetname "")
		)
		(fill yes
			(thermal_gap 0.5)
			(thermal_bridge_width 0.5)
			(island_removal_mode 0)
		)
		(polygon
			(pts
				(arc
					(start 162.162998 -240.871502)
					(mid 162.177877 -240.907423)
					(end 162.213798 -240.922302)
				)
				(arc
					(start 163.613338 -240.922302)
					(mid 163.649259 -240.907423)
					(end 163.664138 -240.871502)
				)
				(arc
					(start 163.664138 -240.462562)
					(mid 163.649259 -240.426641)
					(end 163.613338 -240.411762)
				)
				(arc
					(start 162.213798 -240.411762)
					(mid 162.177877 -240.426641)
					(end 162.162998 -240.462562)
				)
			)
		)
	)
	(zone
		(layers "In1.Cu" "In2.Cu")
		(hatch none 0.5)
		(connect_pads
			(clearance 0)
		)
		(min_thickness 0.25)
		(keepout
			(tracks not_allowed)
			(vias allowed)
			(pads allowed)
			(copperpour not_allowed)
			(footprints allowed)
		)
		(placement
			(enabled no)
			(sheetname "")
		)
		(fill yes
			(thermal_gap 0.5)
			(thermal_bridge_width 0.5)
			(island_removal_mode 0)
		)
		(polygon
			(pts
				(arc
					(start 49.209198 -240.871502)
					(mid 49.224077 -240.907423)
					(end 49.259998 -240.922302)
				)
				(arc
					(start 50.659538 -240.922302)
					(mid 50.695459 -240.907423)
					(end 50.710338 -240.871502)
				)
				(arc
					(start 50.710338 -240.462562)
					(mid 50.695459 -240.426641)
					(end 50.659538 -240.411762)
				)
				(arc
					(start 49.259998 -240.411762)
					(mid 49.224077 -240.426641)
					(end 49.209198 -240.462562)
				)
			)
		)
	)
	(zone
		(layers "In1.Cu" "In2.Cu")
		(hatch none 0.5)
		(connect_pads
			(clearance 0)
		)
		(min_thickness 0.25)
		(keepout
			(tracks not_allowed)
			(vias allowed)
			(pads allowed)
			(copperpour not_allowed)
			(footprints allowed)
		)
		(placement
			(enabled no)
			(sheetname "")
		)
		(fill yes
			(thermal_gap 0.5)
			(thermal_bridge_width 0.5)
			(island_removal_mode 0)
		)
		(polygon
			(pts
				(arc
					(start 289.605466 -263.821418)
					(mid 289.620345 -263.857339)
					(end 289.656266 -263.872218)
				)
				(arc
					(start 291.055806 -263.872218)
					(mid 291.091727 -263.857339)
					(end 291.106606 -263.821418)
				)
				(arc
					(start 291.106606 -263.412478)
					(mid 291.091727 -263.376557)
					(end 291.055806 -263.361678)
				)
				(arc
					(start 289.656266 -263.361678)
					(mid 289.620345 -263.376557)
					(end 289.605466 -263.412478)
				)
			)
		)
	)
	(zone
		(layers "In1.Cu" "In2.Cu")
		(hatch none 0.5)
		(connect_pads
			(clearance 0)
		)
		(min_thickness 0.25)
		(keepout
			(tracks not_allowed)
			(vias allowed)
			(pads allowed)
			(copperpour not_allowed)
			(footprints allowed)
		)
		(placement
			(enabled no)
			(sheetname "")
		)
		(fill yes
			(thermal_gap 0.5)
			(thermal_bridge_width 0.5)
			(island_removal_mode 0)
		)
		(polygon
			(pts
				(arc
					(start 462.909666 -236.62132)
					(mid 462.924545 -236.657241)
					(end 462.960466 -236.67212)
				)
				(arc
					(start 464.360006 -236.67212)
					(mid 464.395927 -236.657241)
					(end 464.410806 -236.62132)
				)
				(arc
					(start 464.410806 -236.21238)
					(mid 464.395927 -236.176459)
					(end 464.360006 -236.16158)
				)
				(arc
					(start 462.960466 -236.16158)
					(mid 462.924545 -236.176459)
					(end 462.909666 -236.21238)
				)
			)
		)
	)
	(zone
		(layers "In1.Cu" "In2.Cu")
		(hatch none 0.5)
		(connect_pads
			(clearance 0)
		)
		(min_thickness 0.25)
		(keepout
			(tracks not_allowed)
			(vias allowed)
			(pads allowed)
			(copperpour not_allowed)
			(footprints allowed)
		)
		(placement
			(enabled no)
			(sheetname "")
		)
		(fill yes
			(thermal_gap 0.5)
			(thermal_bridge_width 0.5)
			(island_removal_mode 0)
		)
		(polygon
			(pts
				(arc
					(start 195.78193 -196.671438)
					(mid 195.796809 -196.707359)
					(end 195.83273 -196.722238)
				)
				(arc
					(start 197.23227 -196.722238)
					(mid 197.268191 -196.707359)
					(end 197.28307 -196.671438)
				)
				(arc
					(start 197.28307 -196.262498)
					(mid 197.268191 -196.226577)
					(end 197.23227 -196.211698)
				)
				(arc
					(start 195.83273 -196.211698)
					(mid 195.796809 -196.226577)
					(end 195.78193 -196.262498)
				)
			)
		)
	)
	(zone
		(layers "In1.Cu" "In2.Cu")
		(hatch none 0.5)
		(connect_pads
			(clearance 0)
		)
		(min_thickness 0.25)
		(keepout
			(tracks not_allowed)
			(vias allowed)
			(pads allowed)
			(copperpour not_allowed)
			(footprints allowed)
		)
		(placement
			(enabled no)
			(sheetname "")
		)
		(fill yes
			(thermal_gap 0.5)
			(thermal_bridge_width 0.5)
			(island_removal_mode 0)
		)
		(polygon
			(pts
				(arc
					(start 285.505398 -299.521372)
					(mid 285.520277 -299.557293)
					(end 285.556198 -299.572172)
				)
				(arc
					(start 286.955738 -299.572172)
					(mid 286.991659 -299.557293)
					(end 287.006538 -299.521372)
				)
				(arc
					(start 287.006538 -299.112432)
					(mid 286.991659 -299.076511)
					(end 286.955738 -299.061632)
				)
				(arc
					(start 285.556198 -299.061632)
					(mid 285.520277 -299.076511)
					(end 285.505398 -299.112432)
				)
			)
		)
	)
	(zone
		(layers "In1.Cu" "In2.Cu")
		(hatch none 0.5)
		(connect_pads
			(clearance 0)
		)
		(min_thickness 0.25)
		(keepout
			(tracks not_allowed)
			(vias allowed)
			(pads allowed)
			(copperpour not_allowed)
			(footprints allowed)
		)
		(placement
			(enabled no)
			(sheetname "")
		)
		(fill yes
			(thermal_gap 0.5)
			(thermal_bridge_width 0.5)
			(island_removal_mode 0)
		)
		(polygon
			(pts
				(arc
					(start 297.149266 -231.521508)
					(mid 297.164145 -231.557429)
					(end 297.200066 -231.572308)
				)
				(arc
					(start 298.599606 -231.572308)
					(mid 298.635527 -231.557429)
					(end 298.650406 -231.521508)
				)
				(arc
					(start 298.650406 -231.112568)
					(mid 298.635527 -231.076647)
					(end 298.599606 -231.061768)
				)
				(arc
					(start 297.200066 -231.061768)
					(mid 297.164145 -231.076647)
					(end 297.149266 -231.112568)
				)
			)
		)
	)
	(zone
		(layers "In1.Cu" "In2.Cu")
		(hatch none 0.5)
		(connect_pads
			(clearance 0)
		)
		(min_thickness 0.25)
		(keepout
			(tracks not_allowed)
			(vias allowed)
			(pads allowed)
			(copperpour not_allowed)
			(footprints allowed)
		)
		(placement
			(enabled no)
			(sheetname "")
		)
		(fill yes
			(thermal_gap 0.5)
			(thermal_bridge_width 0.5)
			(island_removal_mode 0)
		)
		(polygon
			(pts
				(arc
					(start 173.15053 -303.7713)
					(mid 173.165409 -303.807221)
					(end 173.20133 -303.8221)
				)
				(arc
					(start 174.60087 -303.8221)
					(mid 174.636791 -303.807221)
					(end 174.65167 -303.7713)
				)
				(arc
					(start 174.65167 -303.36236)
					(mid 174.636791 -303.326439)
					(end 174.60087 -303.31156)
				)
				(arc
					(start 173.20133 -303.31156)
					(mid 173.165409 -303.326439)
					(end 173.15053 -303.36236)
				)
			)
		)
	)
	(zone
		(layers "In1.Cu" "In2.Cu")
		(hatch none 0.5)
		(connect_pads
			(clearance 0)
		)
		(min_thickness 0.25)
		(keepout
			(tracks not_allowed)
			(vias allowed)
			(pads allowed)
			(copperpour not_allowed)
			(footprints allowed)
		)
		(placement
			(enabled no)
			(sheetname "")
		)
		(fill yes
			(thermal_gap 0.5)
			(thermal_bridge_width 0.5)
			(island_removal_mode 0)
		)
		(polygon
			(pts
				(arc
					(start 428.634398 -218.77147)
					(mid 428.649277 -218.807391)
					(end 428.685198 -218.82227)
				)
				(arc
					(start 430.084738 -218.82227)
					(mid 430.120659 -218.807391)
					(end 430.135538 -218.77147)
				)
				(arc
					(start 430.135538 -218.36253)
					(mid 430.120659 -218.326609)
					(end 430.084738 -218.31173)
				)
				(arc
					(start 428.685198 -218.31173)
					(mid 428.649277 -218.326609)
					(end 428.634398 -218.36253)
				)
			)
		)
	)
	(zone
		(layers "In1.Cu" "In2.Cu")
		(hatch none 0.5)
		(connect_pads
			(clearance 0)
		)
		(min_thickness 0.25)
		(keepout
			(tracks not_allowed)
			(vias allowed)
			(pads allowed)
			(copperpour not_allowed)
			(footprints allowed)
		)
		(placement
			(enabled no)
			(sheetname "")
		)
		(fill yes
			(thermal_gap 0.5)
			(thermal_bridge_width 0.5)
			(island_removal_mode 0)
		)
		(polygon
			(pts
				(arc
					(start 425.190666 -309.721504)
					(mid 425.205545 -309.757425)
					(end 425.241466 -309.772304)
				)
				(arc
					(start 426.641006 -309.772304)
					(mid 426.676927 -309.757425)
					(end 426.691806 -309.721504)
				)
				(arc
					(start 426.691806 -309.312564)
					(mid 426.676927 -309.276643)
					(end 426.641006 -309.261764)
				)
				(arc
					(start 425.241466 -309.261764)
					(mid 425.205545 -309.276643)
					(end 425.190666 -309.312564)
				)
			)
		)
	)
	(zone
		(layers "In1.Cu" "In2.Cu")
		(hatch none 0.5)
		(connect_pads
			(clearance 0)
		)
		(min_thickness 0.25)
		(keepout
			(tracks not_allowed)
			(vias allowed)
			(pads allowed)
			(copperpour not_allowed)
			(footprints allowed)
		)
		(placement
			(enabled no)
			(sheetname "")
		)
		(fill yes
			(thermal_gap 0.5)
			(thermal_bridge_width 0.5)
			(island_removal_mode 0)
		)
		(polygon
			(pts
				(arc
					(start 34.121598 -201.771504)
					(mid 34.136477 -201.807425)
					(end 34.172398 -201.822304)
				)
				(arc
					(start 35.571938 -201.822304)
					(mid 35.607859 -201.807425)
					(end 35.622738 -201.771504)
				)
				(arc
					(start 35.622738 -201.362564)
					(mid 35.607859 -201.326643)
					(end 35.571938 -201.311764)
				)
				(arc
					(start 34.172398 -201.311764)
					(mid 34.136477 -201.326643)
					(end 34.121598 -201.362564)
				)
			)
		)
	)
	(zone
		(layers "In1.Cu" "In2.Cu")
		(hatch none 0.5)
		(connect_pads
			(clearance 0)
		)
		(min_thickness 0.25)
		(keepout
			(tracks not_allowed)
			(vias allowed)
			(pads allowed)
			(copperpour not_allowed)
			(footprints allowed)
		)
		(placement
			(enabled no)
			(sheetname "")
		)
		(fill yes
			(thermal_gap 0.5)
			(thermal_bridge_width 0.5)
			(island_removal_mode 0)
		)
		(polygon
			(pts
				(arc
					(start 443.721998 -245.971314)
					(mid 443.736877 -246.007235)
					(end 443.772798 -246.022114)
				)
				(arc
					(start 445.172338 -246.022114)
					(mid 445.208259 -246.007235)
					(end 445.223138 -245.971314)
				)
				(arc
					(start 445.223138 -245.562374)
					(mid 445.208259 -245.526453)
					(end 445.172338 -245.511574)
				)
				(arc
					(start 443.772798 -245.511574)
					(mid 443.736877 -245.526453)
					(end 443.721998 -245.562374)
				)
			)
		)
	)
	(zone
		(layers "In1.Cu" "In2.Cu")
		(hatch none 0.5)
		(connect_pads
			(clearance 0)
		)
		(min_thickness 0.25)
		(keepout
			(tracks not_allowed)
			(vias allowed)
			(pads allowed)
			(copperpour not_allowed)
			(footprints allowed)
		)
		(placement
			(enabled no)
			(sheetname "")
		)
		(fill yes
			(thermal_gap 0.5)
			(thermal_bridge_width 0.5)
			(island_removal_mode 0)
		)
		(polygon
			(pts
				(arc
					(start 180.69433 -207.721454)
					(mid 180.709209 -207.757375)
					(end 180.74513 -207.772254)
				)
				(arc
					(start 182.14467 -207.772254)
					(mid 182.180591 -207.757375)
					(end 182.19547 -207.721454)
				)
				(arc
					(start 182.19547 -207.312514)
					(mid 182.180591 -207.276593)
					(end 182.14467 -207.261714)
				)
				(arc
					(start 180.74513 -207.261714)
					(mid 180.709209 -207.276593)
					(end 180.69433 -207.312514)
				)
			)
		)
	)
	(zone
		(layers "In1.Cu" "In2.Cu")
		(hatch none 0.5)
		(connect_pads
			(clearance 0)
		)
		(min_thickness 0.25)
		(keepout
			(tracks not_allowed)
			(vias allowed)
			(pads allowed)
			(copperpour not_allowed)
			(footprints allowed)
		)
		(placement
			(enabled no)
			(sheetname "")
		)
		(fill yes
			(thermal_gap 0.5)
			(thermal_bridge_width 0.5)
			(island_removal_mode 0)
		)
		(polygon
			(pts
				(arc
					(start 304.693066 -222.171514)
					(mid 304.707945 -222.207435)
					(end 304.743866 -222.222314)
				)
				(arc
					(start 306.143406 -222.222314)
					(mid 306.179327 -222.207435)
					(end 306.194206 -222.171514)
				)
				(arc
					(start 306.194206 -221.762574)
					(mid 306.179327 -221.726653)
					(end 306.143406 -221.711774)
				)
				(arc
					(start 304.743866 -221.711774)
					(mid 304.707945 -221.726653)
					(end 304.693066 -221.762574)
				)
			)
		)
	)
	(zone
		(layers "In1.Cu" "In2.Cu")
		(hatch none 0.5)
		(connect_pads
			(clearance 0)
		)
		(min_thickness 0.25)
		(keepout
			(tracks not_allowed)
			(vias allowed)
			(pads allowed)
			(copperpour not_allowed)
			(footprints allowed)
		)
		(placement
			(enabled no)
			(sheetname "")
		)
		(fill yes
			(thermal_gap 0.5)
			(thermal_bridge_width 0.5)
			(island_removal_mode 0)
		)
		(polygon
			(pts
				(arc
					(start 406.002998 -234.071414)
					(mid 406.017877 -234.107335)
					(end 406.053798 -234.122214)
				)
				(arc
					(start 407.453338 -234.122214)
					(mid 407.489259 -234.107335)
					(end 407.504138 -234.071414)
				)
				(arc
					(start 407.504138 -233.662474)
					(mid 407.489259 -233.626553)
					(end 407.453338 -233.611674)
				)
				(arc
					(start 406.053798 -233.611674)
					(mid 406.017877 -233.626553)
					(end 406.002998 -233.662474)
				)
			)
		)
	)
	(zone
		(layers "In1.Cu" "In2.Cu")
		(hatch none 0.5)
		(connect_pads
			(clearance 0)
		)
		(min_thickness 0.25)
		(keepout
			(tracks not_allowed)
			(vias allowed)
			(pads allowed)
			(copperpour not_allowed)
			(footprints allowed)
		)
		(placement
			(enabled no)
			(sheetname "")
		)
		(fill yes
			(thermal_gap 0.5)
			(thermal_bridge_width 0.5)
			(island_removal_mode 0)
		)
		(polygon
			(pts
				(arc
					(start 41.665398 -293.571422)
					(mid 41.680277 -293.607343)
					(end 41.716198 -293.622222)
				)
				(arc
					(start 43.115738 -293.622222)
					(mid 43.151659 -293.607343)
					(end 43.166538 -293.571422)
				)
				(arc
					(start 43.166538 -293.162482)
					(mid 43.151659 -293.126561)
					(end 43.115738 -293.111682)
				)
				(arc
					(start 41.716198 -293.111682)
					(mid 41.680277 -293.126561)
					(end 41.665398 -293.162482)
				)
			)
		)
	)
	(zone
		(layers "In1.Cu" "In2.Cu")
		(hatch none 0.5)
		(connect_pads
			(clearance 0)
		)
		(min_thickness 0.25)
		(keepout
			(tracks not_allowed)
			(vias allowed)
			(pads allowed)
			(copperpour not_allowed)
			(footprints allowed)
		)
		(placement
			(enabled no)
			(sheetname "")
		)
		(fill yes
			(thermal_gap 0.5)
			(thermal_bridge_width 0.5)
			(island_removal_mode 0)
		)
		(polygon
			(pts
				(arc
					(start 410.103066 -285.92145)
					(mid 410.117945 -285.957371)
					(end 410.153866 -285.97225)
				)
				(arc
					(start 411.553406 -285.97225)
					(mid 411.589327 -285.957371)
					(end 411.604206 -285.92145)
				)
				(arc
					(start 411.604206 -285.51251)
					(mid 411.589327 -285.476589)
					(end 411.553406 -285.46171)
				)
				(arc
					(start 410.153866 -285.46171)
					(mid 410.117945 -285.476589)
					(end 410.103066 -285.51251)
				)
			)
		)
	)
	(zone
		(layers "In1.Cu" "In2.Cu")
		(hatch none 0.5)
		(connect_pads
			(clearance 0)
		)
		(min_thickness 0.25)
		(keepout
			(tracks not_allowed)
			(vias allowed)
			(pads allowed)
			(copperpour not_allowed)
			(footprints allowed)
		)
		(placement
			(enabled no)
			(sheetname "")
		)
		(fill yes
			(thermal_gap 0.5)
			(thermal_bridge_width 0.5)
			(island_removal_mode 0)
		)
		(polygon
			(pts
				(arc
					(start 417.646866 -274.02155)
					(mid 417.661745 -274.057471)
					(end 417.697666 -274.07235)
				)
				(arc
					(start 419.097206 -274.07235)
					(mid 419.133127 -274.057471)
					(end 419.148006 -274.02155)
				)
				(arc
					(start 419.148006 -273.61261)
					(mid 419.133127 -273.576689)
					(end 419.097206 -273.56181)
				)
				(arc
					(start 417.697666 -273.56181)
					(mid 417.661745 -273.576689)
					(end 417.646866 -273.61261)
				)
			)
		)
	)
	(zone
		(layers "In1.Cu" "In2.Cu")
		(hatch none 0.5)
		(connect_pads
			(clearance 0)
		)
		(min_thickness 0.25)
		(keepout
			(tracks not_allowed)
			(vias allowed)
			(pads allowed)
			(copperpour not_allowed)
			(footprints allowed)
		)
		(placement
			(enabled no)
			(sheetname "")
		)
		(fill yes
			(thermal_gap 0.5)
			(thermal_bridge_width 0.5)
			(island_removal_mode 0)
		)
		(polygon
			(pts
				(arc
					(start 455.365866 -274.02155)
					(mid 455.380745 -274.057471)
					(end 455.416666 -274.07235)
				)
				(arc
					(start 456.816206 -274.07235)
					(mid 456.852127 -274.057471)
					(end 456.867006 -274.02155)
				)
				(arc
					(start 456.867006 -273.61261)
					(mid 456.852127 -273.576689)
					(end 456.816206 -273.56181)
				)
				(arc
					(start 455.416666 -273.56181)
					(mid 455.380745 -273.576689)
					(end 455.365866 -273.61261)
				)
			)
		)
	)
	(zone
		(layers "In1.Cu" "In2.Cu")
		(hatch none 0.5)
		(connect_pads
			(clearance 0)
		)
		(min_thickness 0.25)
		(keepout
			(tracks not_allowed)
			(vias allowed)
			(pads allowed)
			(copperpour not_allowed)
			(footprints allowed)
		)
		(placement
			(enabled no)
			(sheetname "")
		)
		(fill yes
			(thermal_gap 0.5)
			(thermal_bridge_width 0.5)
			(island_removal_mode 0)
		)
		(polygon
			(pts
				(arc
					(start 56.752998 -239.17148)
					(mid 56.767877 -239.207401)
					(end 56.803798 -239.22228)
				)
				(arc
					(start 58.203338 -239.22228)
					(mid 58.239259 -239.207401)
					(end 58.254138 -239.17148)
				)
				(arc
					(start 58.254138 -238.76254)
					(mid 58.239259 -238.726619)
					(end 58.203338 -238.71174)
				)
				(arc
					(start 56.803798 -238.71174)
					(mid 56.767877 -238.726619)
					(end 56.752998 -238.76254)
				)
			)
		)
	)
	(zone
		(layers "In1.Cu" "In2.Cu")
		(hatch none 0.5)
		(connect_pads
			(clearance 0)
		)
		(min_thickness 0.25)
		(keepout
			(tracks not_allowed)
			(vias allowed)
			(pads allowed)
			(copperpour not_allowed)
			(footprints allowed)
		)
		(placement
			(enabled no)
			(sheetname "")
		)
		(fill yes
			(thermal_gap 0.5)
			(thermal_bridge_width 0.5)
			(island_removal_mode 0)
		)
		(polygon
			(pts
				(arc
					(start 410.103066 -283.371544)
					(mid 410.117945 -283.407465)
					(end 410.153866 -283.422344)
				)
				(arc
					(start 411.553406 -283.422344)
					(mid 411.589327 -283.407465)
					(end 411.604206 -283.371544)
				)
				(arc
					(start 411.604206 -282.962604)
					(mid 411.589327 -282.926683)
					(end 411.553406 -282.911804)
				)
				(arc
					(start 410.153866 -282.911804)
					(mid 410.117945 -282.926683)
					(end 410.103066 -282.962604)
				)
			)
		)
	)
	(zone
		(layers "In1.Cu" "In2.Cu")
		(hatch none 0.5)
		(connect_pads
			(clearance 0)
		)
		(min_thickness 0.25)
		(keepout
			(tracks not_allowed)
			(vias allowed)
			(pads allowed)
			(copperpour not_allowed)
			(footprints allowed)
		)
		(placement
			(enabled no)
			(sheetname "")
		)
		(fill yes
			(thermal_gap 0.5)
			(thermal_bridge_width 0.5)
			(island_removal_mode 0)
		)
		(polygon
			(pts
				(arc
					(start 308.136798 -213.671404)
					(mid 308.151677 -213.707325)
					(end 308.187598 -213.722204)
				)
				(arc
					(start 309.587138 -213.722204)
					(mid 309.623059 -213.707325)
					(end 309.637938 -213.671404)
				)
				(arc
					(start 309.637938 -213.262464)
					(mid 309.623059 -213.226543)
					(end 309.587138 -213.211664)
				)
				(arc
					(start 308.187598 -213.211664)
					(mid 308.151677 -213.226543)
					(end 308.136798 -213.262464)
				)
			)
		)
	)
	(zone
		(layers "In1.Cu" "In2.Cu")
		(hatch none 0.5)
		(connect_pads
			(clearance 0)
		)
		(min_thickness 0.25)
		(keepout
			(tracks not_allowed)
			(vias allowed)
			(pads allowed)
			(copperpour not_allowed)
			(footprints allowed)
		)
		(placement
			(enabled no)
			(sheetname "")
		)
		(fill yes
			(thermal_gap 0.5)
			(thermal_bridge_width 0.5)
			(island_removal_mode 0)
		)
		(polygon
			(pts
				(arc
					(start 7.39013 -312.27141)
					(mid 7.405009 -312.307331)
					(end 7.44093 -312.32221)
				)
				(arc
					(start 8.84047 -312.32221)
					(mid 8.876391 -312.307331)
					(end 8.89127 -312.27141)
				)
				(arc
					(start 8.89127 -311.86247)
					(mid 8.876391 -311.826549)
					(end 8.84047 -311.81167)
				)
				(arc
					(start 7.44093 -311.81167)
					(mid 7.405009 -311.826549)
					(end 7.39013 -311.86247)
				)
			)
		)
	)
	(zone
		(layers "In1.Cu" "In2.Cu")
		(hatch none 0.5)
		(connect_pads
			(clearance 0)
		)
		(min_thickness 0.25)
		(keepout
			(tracks not_allowed)
			(vias allowed)
			(pads allowed)
			(copperpour not_allowed)
			(footprints allowed)
		)
		(placement
			(enabled no)
			(sheetname "")
		)
		(fill yes
			(thermal_gap 0.5)
			(thermal_bridge_width 0.5)
			(island_removal_mode 0)
		)
		(polygon
			(pts
				(arc
					(start 173.15053 -259.57149)
					(mid 173.165409 -259.607411)
					(end 173.20133 -259.62229)
				)
				(arc
					(start 174.60087 -259.62229)
					(mid 174.636791 -259.607411)
					(end 174.65167 -259.57149)
				)
				(arc
					(start 174.65167 -259.16255)
					(mid 174.636791 -259.126629)
					(end 174.60087 -259.11175)
				)
				(arc
					(start 173.20133 -259.11175)
					(mid 173.165409 -259.126629)
					(end 173.15053 -259.16255)
				)
			)
		)
	)
	(zone
		(layers "In1.Cu" "In2.Cu")
		(hatch none 0.5)
		(connect_pads
			(clearance 0)
		)
		(min_thickness 0.25)
		(keepout
			(tracks not_allowed)
			(vias allowed)
			(pads allowed)
			(copperpour not_allowed)
			(footprints allowed)
		)
		(placement
			(enabled no)
			(sheetname "")
		)
		(fill yes
			(thermal_gap 0.5)
			(thermal_bridge_width 0.5)
			(island_removal_mode 0)
		)
		(polygon
			(pts
				(arc
					(start 304.693066 -281.671522)
					(mid 304.707945 -281.707443)
					(end 304.743866 -281.722322)
				)
				(arc
					(start 306.143406 -281.722322)
					(mid 306.179327 -281.707443)
					(end 306.194206 -281.671522)
				)
				(arc
					(start 306.194206 -281.262582)
					(mid 306.179327 -281.226661)
					(end 306.143406 -281.211782)
				)
				(arc
					(start 304.743866 -281.211782)
					(mid 304.707945 -281.226661)
					(end 304.693066 -281.262582)
				)
			)
		)
	)
	(zone
		(layers "In1.Cu" "In2.Cu")
		(hatch none 0.5)
		(connect_pads
			(clearance 0)
		)
		(min_thickness 0.25)
		(keepout
			(tracks not_allowed)
			(vias allowed)
			(pads allowed)
			(copperpour not_allowed)
			(footprints allowed)
		)
		(placement
			(enabled no)
			(sheetname "")
		)
		(fill yes
			(thermal_gap 0.5)
			(thermal_bridge_width 0.5)
			(island_removal_mode 0)
		)
		(polygon
			(pts
				(arc
					(start 184.794398 -217.921332)
					(mid 184.809277 -217.957253)
					(end 184.845198 -217.972132)
				)
				(arc
					(start 186.244738 -217.972132)
					(mid 186.280659 -217.957253)
					(end 186.295538 -217.921332)
				)
				(arc
					(start 186.295538 -217.512392)
					(mid 186.280659 -217.476471)
					(end 186.244738 -217.461592)
				)
				(arc
					(start 184.845198 -217.461592)
					(mid 184.809277 -217.476471)
					(end 184.794398 -217.512392)
				)
			)
		)
	)
	(zone
		(layers "In1.Cu" "In2.Cu")
		(hatch none 0.5)
		(connect_pads
			(clearance 0)
		)
		(min_thickness 0.25)
		(keepout
			(tracks not_allowed)
			(vias allowed)
			(pads allowed)
			(copperpour not_allowed)
			(footprints allowed)
		)
		(placement
			(enabled no)
			(sheetname "")
		)
		(fill yes
			(thermal_gap 0.5)
			(thermal_bridge_width 0.5)
			(island_removal_mode 0)
		)
		(polygon
			(pts
				(arc
					(start 188.23813 -291.8714)
					(mid 188.253009 -291.907321)
					(end 188.28893 -291.9222)
				)
				(arc
					(start 189.68847 -291.9222)
					(mid 189.724391 -291.907321)
					(end 189.73927 -291.8714)
				)
				(arc
					(start 189.73927 -291.46246)
					(mid 189.724391 -291.426539)
					(end 189.68847 -291.41166)
				)
				(arc
					(start 188.28893 -291.41166)
					(mid 188.253009 -291.426539)
					(end 188.23813 -291.46246)
				)
			)
		)
	)
	(zone
		(layers "In1.Cu" "In2.Cu")
		(hatch none 0.5)
		(connect_pads
			(clearance 0)
		)
		(min_thickness 0.25)
		(keepout
			(tracks not_allowed)
			(vias allowed)
			(pads allowed)
			(copperpour not_allowed)
			(footprints allowed)
		)
		(placement
			(enabled no)
			(sheetname "")
		)
		(fill yes
			(thermal_gap 0.5)
			(thermal_bridge_width 0.5)
			(island_removal_mode 0)
		)
		(polygon
			(pts
				(arc
					(start 270.417798 -264.671302)
					(mid 270.432677 -264.707223)
					(end 270.468598 -264.722102)
				)
				(arc
					(start 271.868138 -264.722102)
					(mid 271.904059 -264.707223)
					(end 271.918938 -264.671302)
				)
				(arc
					(start 271.918938 -264.262362)
					(mid 271.904059 -264.226441)
					(end 271.868138 -264.211562)
				)
				(arc
					(start 270.468598 -264.211562)
					(mid 270.432677 -264.226441)
					(end 270.417798 -264.262362)
				)
			)
		)
	)
	(zone
		(layers "In1.Cu" "In2.Cu")
		(hatch none 0.5)
		(connect_pads
			(clearance 0)
		)
		(min_thickness 0.25)
		(keepout
			(tracks not_allowed)
			(vias allowed)
			(pads allowed)
			(copperpour not_allowed)
			(footprints allowed)
		)
		(placement
			(enabled no)
			(sheetname "")
		)
		(fill yes
			(thermal_gap 0.5)
			(thermal_bridge_width 0.5)
			(island_removal_mode 0)
		)
		(polygon
			(pts
				(arc
					(start 180.69433 -261.271512)
					(mid 180.709209 -261.307433)
					(end 180.74513 -261.322312)
				)
				(arc
					(start 182.14467 -261.322312)
					(mid 182.180591 -261.307433)
					(end 182.19547 -261.271512)
				)
				(arc
					(start 182.19547 -260.862572)
					(mid 182.180591 -260.826651)
					(end 182.14467 -260.811772)
				)
				(arc
					(start 180.74513 -260.811772)
					(mid 180.709209 -260.826651)
					(end 180.69433 -260.862572)
				)
			)
		)
	)
	(zone
		(layers "In1.Cu" "In2.Cu")
		(hatch none 0.5)
		(connect_pads
			(clearance 0)
		)
		(min_thickness 0.25)
		(keepout
			(tracks not_allowed)
			(vias allowed)
			(pads allowed)
			(copperpour not_allowed)
			(footprints allowed)
		)
		(placement
			(enabled no)
			(sheetname "")
		)
		(fill yes
			(thermal_gap 0.5)
			(thermal_bridge_width 0.5)
			(island_removal_mode 0)
		)
		(polygon
			(pts
				(arc
					(start 447.822066 -276.571456)
					(mid 447.836945 -276.607377)
					(end 447.872866 -276.622256)
				)
				(arc
					(start 449.272406 -276.622256)
					(mid 449.308327 -276.607377)
					(end 449.323206 -276.571456)
				)
				(arc
					(start 449.323206 -276.162516)
					(mid 449.308327 -276.126595)
					(end 449.272406 -276.111716)
				)
				(arc
					(start 447.872866 -276.111716)
					(mid 447.836945 -276.126595)
					(end 447.822066 -276.162516)
				)
			)
		)
	)
	(zone
		(layers "In1.Cu" "In2.Cu")
		(hatch none 0.5)
		(connect_pads
			(clearance 0)
		)
		(min_thickness 0.25)
		(keepout
			(tracks not_allowed)
			(vias allowed)
			(pads allowed)
			(copperpour not_allowed)
			(footprints allowed)
		)
		(placement
			(enabled no)
			(sheetname "")
		)
		(fill yes
			(thermal_gap 0.5)
			(thermal_bridge_width 0.5)
			(island_removal_mode 0)
		)
		(polygon
			(pts
				(arc
					(start 262.873998 -277.42134)
					(mid 262.888877 -277.457261)
					(end 262.924798 -277.47214)
				)
				(arc
					(start 264.324338 -277.47214)
					(mid 264.360259 -277.457261)
					(end 264.375138 -277.42134)
				)
				(arc
					(start 264.375138 -277.0124)
					(mid 264.360259 -276.976479)
					(end 264.324338 -276.9616)
				)
				(arc
					(start 262.924798 -276.9616)
					(mid 262.888877 -276.976479)
					(end 262.873998 -277.0124)
				)
			)
		)
	)
	(zone
		(layers "In1.Cu" "In2.Cu")
		(hatch none 0.5)
		(connect_pads
			(clearance 0)
		)
		(min_thickness 0.25)
		(keepout
			(tracks not_allowed)
			(vias allowed)
			(pads allowed)
			(copperpour not_allowed)
			(footprints allowed)
		)
		(placement
			(enabled no)
			(sheetname "")
		)
		(fill yes
			(thermal_gap 0.5)
			(thermal_bridge_width 0.5)
			(island_removal_mode 0)
		)
		(polygon
			(pts
				(arc
					(start 41.665398 -306.32146)
					(mid 41.680277 -306.357381)
					(end 41.716198 -306.37226)
				)
				(arc
					(start 43.115738 -306.37226)
					(mid 43.151659 -306.357381)
					(end 43.166538 -306.32146)
				)
				(arc
					(start 43.166538 -305.91252)
					(mid 43.151659 -305.876599)
					(end 43.115738 -305.86172)
				)
				(arc
					(start 41.716198 -305.86172)
					(mid 41.680277 -305.876599)
					(end 41.665398 -305.91252)
				)
			)
		)
	)
	(zone
		(layers "In1.Cu" "In2.Cu")
		(hatch none 0.5)
		(connect_pads
			(clearance 0)
		)
		(min_thickness 0.25)
		(keepout
			(tracks not_allowed)
			(vias allowed)
			(pads allowed)
			(copperpour not_allowed)
			(footprints allowed)
		)
		(placement
			(enabled no)
			(sheetname "")
		)
		(fill yes
			(thermal_gap 0.5)
			(thermal_bridge_width 0.5)
			(island_removal_mode 0)
		)
		(polygon
			(pts
				(arc
					(start 64.296798 -313.971432)
					(mid 64.311677 -314.007353)
					(end 64.347598 -314.022232)
				)
				(arc
					(start 65.747138 -314.022232)
					(mid 65.783059 -314.007353)
					(end 65.797938 -313.971432)
				)
				(arc
					(start 65.797938 -313.562492)
					(mid 65.783059 -313.526571)
					(end 65.747138 -313.511692)
				)
				(arc
					(start 64.347598 -313.511692)
					(mid 64.311677 -313.526571)
					(end 64.296798 -313.562492)
				)
			)
		)
	)
	(zone
		(layers "In1.Cu" "In2.Cu")
		(hatch none 0.5)
		(connect_pads
			(clearance 0)
		)
		(min_thickness 0.25)
		(keepout
			(tracks not_allowed)
			(vias allowed)
			(pads allowed)
			(copperpour not_allowed)
			(footprints allowed)
		)
		(placement
			(enabled no)
			(sheetname "")
		)
		(fill yes
			(thermal_gap 0.5)
			(thermal_bridge_width 0.5)
			(island_removal_mode 0)
		)
		(polygon
			(pts
				(arc
					(start 210.86953 -241.721386)
					(mid 210.884409 -241.757307)
					(end 210.92033 -241.772186)
				)
				(arc
					(start 212.31987 -241.772186)
					(mid 212.355791 -241.757307)
					(end 212.37067 -241.721386)
				)
				(arc
					(start 212.37067 -241.312446)
					(mid 212.355791 -241.276525)
					(end 212.31987 -241.261646)
				)
				(arc
					(start 210.92033 -241.261646)
					(mid 210.884409 -241.276525)
					(end 210.86953 -241.312446)
				)
			)
		)
	)
	(zone
		(layers "In1.Cu" "In2.Cu")
		(hatch none 0.5)
		(connect_pads
			(clearance 0)
		)
		(min_thickness 0.25)
		(keepout
			(tracks not_allowed)
			(vias allowed)
			(pads allowed)
			(copperpour not_allowed)
			(footprints allowed)
		)
		(placement
			(enabled no)
			(sheetname "")
		)
		(fill yes
			(thermal_gap 0.5)
			(thermal_bridge_width 0.5)
			(island_removal_mode 0)
		)
		(polygon
			(pts
				(arc
					(start 304.693066 -284.221428)
					(mid 304.707945 -284.257349)
					(end 304.743866 -284.272228)
				)
				(arc
					(start 306.143406 -284.272228)
					(mid 306.179327 -284.257349)
					(end 306.194206 -284.221428)
				)
				(arc
					(start 306.194206 -283.812488)
					(mid 306.179327 -283.776567)
					(end 306.143406 -283.761688)
				)
				(arc
					(start 304.743866 -283.761688)
					(mid 304.707945 -283.776567)
					(end 304.693066 -283.812488)
				)
			)
		)
	)
	(zone
		(layers "In1.Cu" "In2.Cu")
		(hatch none 0.5)
		(connect_pads
			(clearance 0)
		)
		(min_thickness 0.25)
		(keepout
			(tracks not_allowed)
			(vias allowed)
			(pads allowed)
			(copperpour not_allowed)
			(footprints allowed)
		)
		(placement
			(enabled no)
			(sheetname "")
		)
		(fill yes
			(thermal_gap 0.5)
			(thermal_bridge_width 0.5)
			(island_removal_mode 0)
		)
		(polygon
			(pts
				(arc
					(start 289.605466 -223.871536)
					(mid 289.620345 -223.907457)
					(end 289.656266 -223.922336)
				)
				(arc
					(start 291.055806 -223.922336)
					(mid 291.091727 -223.907457)
					(end 291.106606 -223.871536)
				)
				(arc
					(start 291.106606 -223.462596)
					(mid 291.091727 -223.426675)
					(end 291.055806 -223.411796)
				)
				(arc
					(start 289.656266 -223.411796)
					(mid 289.620345 -223.426675)
					(end 289.605466 -223.462596)
				)
			)
		)
	)
	(zone
		(layers "In1.Cu" "In2.Cu")
		(hatch none 0.5)
		(connect_pads
			(clearance 0)
		)
		(min_thickness 0.25)
		(keepout
			(tracks not_allowed)
			(vias allowed)
			(pads allowed)
			(copperpour not_allowed)
			(footprints allowed)
		)
		(placement
			(enabled no)
			(sheetname "")
		)
		(fill yes
			(thermal_gap 0.5)
			(thermal_bridge_width 0.5)
			(island_removal_mode 0)
		)
		(polygon
			(pts
				(arc
					(start 289.605466 -239.17148)
					(mid 289.620345 -239.207401)
					(end 289.656266 -239.22228)
				)
				(arc
					(start 291.055806 -239.22228)
					(mid 291.091727 -239.207401)
					(end 291.106606 -239.17148)
				)
				(arc
					(start 291.106606 -238.76254)
					(mid 291.091727 -238.726619)
					(end 291.055806 -238.71174)
				)
				(arc
					(start 289.656266 -238.71174)
					(mid 289.620345 -238.726619)
					(end 289.605466 -238.76254)
				)
			)
		)
	)
	(zone
		(layers "In1.Cu" "In2.Cu")
		(hatch none 0.5)
		(connect_pads
			(clearance 0)
		)
		(min_thickness 0.25)
		(keepout
			(tracks not_allowed)
			(vias allowed)
			(pads allowed)
			(copperpour not_allowed)
			(footprints allowed)
		)
		(placement
			(enabled no)
			(sheetname "")
		)
		(fill yes
			(thermal_gap 0.5)
			(thermal_bridge_width 0.5)
			(island_removal_mode 0)
		)
		(polygon
			(pts
				(arc
					(start 285.505398 -228.121464)
					(mid 285.520277 -228.157385)
					(end 285.556198 -228.172264)
				)
				(arc
					(start 286.955738 -228.172264)
					(mid 286.991659 -228.157385)
					(end 287.006538 -228.121464)
				)
				(arc
					(start 287.006538 -227.712524)
					(mid 286.991659 -227.676603)
					(end 286.955738 -227.661724)
				)
				(arc
					(start 285.556198 -227.661724)
					(mid 285.520277 -227.676603)
					(end 285.505398 -227.712524)
				)
			)
		)
	)
	(zone
		(layers "In1.Cu" "In2.Cu")
		(hatch none 0.5)
		(connect_pads
			(clearance 0)
		)
		(min_thickness 0.25)
		(keepout
			(tracks not_allowed)
			(vias allowed)
			(pads allowed)
			(copperpour not_allowed)
			(footprints allowed)
		)
		(placement
			(enabled no)
			(sheetname "")
		)
		(fill yes
			(thermal_gap 0.5)
			(thermal_bridge_width 0.5)
			(island_removal_mode 0)
		)
		(polygon
			(pts
				(arc
					(start 262.873998 -221.321376)
					(mid 262.888877 -221.357297)
					(end 262.924798 -221.372176)
				)
				(arc
					(start 264.324338 -221.372176)
					(mid 264.360259 -221.357297)
					(end 264.375138 -221.321376)
				)
				(arc
					(start 264.375138 -220.912436)
					(mid 264.360259 -220.876515)
					(end 264.324338 -220.861636)
				)
				(arc
					(start 262.924798 -220.861636)
					(mid 262.888877 -220.876515)
					(end 262.873998 -220.912436)
				)
			)
		)
	)
	(zone
		(layers "In1.Cu" "In2.Cu")
		(hatch none 0.5)
		(connect_pads
			(clearance 0)
		)
		(min_thickness 0.25)
		(keepout
			(tracks not_allowed)
			(vias allowed)
			(pads allowed)
			(copperpour not_allowed)
			(footprints allowed)
		)
		(placement
			(enabled no)
			(sheetname "")
		)
		(fill yes
			(thermal_gap 0.5)
			(thermal_bridge_width 0.5)
			(island_removal_mode 0)
		)
		(polygon
			(pts
				(arc
					(start 447.822066 -212.82152)
					(mid 447.836945 -212.857441)
					(end 447.872866 -212.87232)
				)
				(arc
					(start 449.272406 -212.87232)
					(mid 449.308327 -212.857441)
					(end 449.323206 -212.82152)
				)
				(arc
					(start 449.323206 -212.41258)
					(mid 449.308327 -212.376659)
					(end 449.272406 -212.36178)
				)
				(arc
					(start 447.872866 -212.36178)
					(mid 447.836945 -212.376659)
					(end 447.822066 -212.41258)
				)
			)
		)
	)
	(zone
		(layers "In1.Cu" "In2.Cu")
		(hatch none 0.5)
		(connect_pads
			(clearance 0)
		)
		(min_thickness 0.25)
		(keepout
			(tracks not_allowed)
			(vias allowed)
			(pads allowed)
			(copperpour not_allowed)
			(footprints allowed)
		)
		(placement
			(enabled no)
			(sheetname "")
		)
		(fill yes
			(thermal_gap 0.5)
			(thermal_bridge_width 0.5)
			(island_removal_mode 0)
		)
		(polygon
			(pts
				(arc
					(start 158.06293 -268.071346)
					(mid 158.077809 -268.107267)
					(end 158.11373 -268.122146)
				)
				(arc
					(start 159.51327 -268.122146)
					(mid 159.549191 -268.107267)
					(end 159.56407 -268.071346)
				)
				(arc
					(start 159.56407 -267.662406)
					(mid 159.549191 -267.626485)
					(end 159.51327 -267.611606)
				)
				(arc
					(start 158.11373 -267.611606)
					(mid 158.077809 -267.626485)
					(end 158.06293 -267.662406)
				)
			)
		)
	)
	(zone
		(layers "In1.Cu" "In2.Cu")
		(hatch none 0.5)
		(connect_pads
			(clearance 0)
		)
		(min_thickness 0.25)
		(keepout
			(tracks not_allowed)
			(vias allowed)
			(pads allowed)
			(copperpour not_allowed)
			(footprints allowed)
		)
		(placement
			(enabled no)
			(sheetname "")
		)
		(fill yes
			(thermal_gap 0.5)
			(thermal_bridge_width 0.5)
			(island_removal_mode 0)
		)
		(polygon
			(pts
				(arc
					(start 180.69433 -247.671336)
					(mid 180.709209 -247.707257)
					(end 180.74513 -247.722136)
				)
				(arc
					(start 182.14467 -247.722136)
					(mid 182.180591 -247.707257)
					(end 182.19547 -247.671336)
				)
				(arc
					(start 182.19547 -247.262396)
					(mid 182.180591 -247.226475)
					(end 182.14467 -247.211596)
				)
				(arc
					(start 180.74513 -247.211596)
					(mid 180.709209 -247.226475)
					(end 180.69433 -247.262396)
				)
			)
		)
	)
	(zone
		(layers "In1.Cu" "In2.Cu")
		(hatch none 0.5)
		(connect_pads
			(clearance 0)
		)
		(min_thickness 0.25)
		(keepout
			(tracks not_allowed)
			(vias allowed)
			(pads allowed)
			(copperpour not_allowed)
			(footprints allowed)
		)
		(placement
			(enabled no)
			(sheetname "")
		)
		(fill yes
			(thermal_gap 0.5)
			(thermal_bridge_width 0.5)
			(island_removal_mode 0)
		)
		(polygon
			(pts
				(arc
					(start 417.646866 -195.821554)
					(mid 417.661745 -195.857475)
					(end 417.697666 -195.872354)
				)
				(arc
					(start 419.097206 -195.872354)
					(mid 419.133127 -195.857475)
					(end 419.148006 -195.821554)
				)
				(arc
					(start 419.148006 -195.412614)
					(mid 419.133127 -195.376693)
					(end 419.097206 -195.361814)
				)
				(arc
					(start 417.697666 -195.361814)
					(mid 417.661745 -195.376693)
					(end 417.646866 -195.412614)
				)
			)
		)
	)
	(zone
		(layers "In1.Cu" "In2.Cu")
		(hatch none 0.5)
		(connect_pads
			(clearance 0)
		)
		(min_thickness 0.25)
		(keepout
			(tracks not_allowed)
			(vias allowed)
			(pads allowed)
			(copperpour not_allowed)
			(footprints allowed)
		)
		(placement
			(enabled no)
			(sheetname "")
		)
		(fill yes
			(thermal_gap 0.5)
			(thermal_bridge_width 0.5)
			(island_removal_mode 0)
		)
		(polygon
			(pts
				(arc
					(start 421.090598 -235.771436)
					(mid 421.105477 -235.807357)
					(end 421.141398 -235.822236)
				)
				(arc
					(start 422.540938 -235.822236)
					(mid 422.576859 -235.807357)
					(end 422.591738 -235.771436)
				)
				(arc
					(start 422.591738 -235.362496)
					(mid 422.576859 -235.326575)
					(end 422.540938 -235.311696)
				)
				(arc
					(start 421.141398 -235.311696)
					(mid 421.105477 -235.326575)
					(end 421.090598 -235.362496)
				)
			)
		)
	)
	(zone
		(layers "In1.Cu" "In2.Cu")
		(hatch none 0.5)
		(connect_pads
			(clearance 0)
		)
		(min_thickness 0.25)
		(keepout
			(tracks not_allowed)
			(vias allowed)
			(pads allowed)
			(copperpour not_allowed)
			(footprints allowed)
		)
		(placement
			(enabled no)
			(sheetname "")
		)
		(fill yes
			(thermal_gap 0.5)
			(thermal_bridge_width 0.5)
			(island_removal_mode 0)
		)
		(polygon
			(pts
				(arc
					(start 165.60673 -302.921416)
					(mid 165.621609 -302.957337)
					(end 165.65753 -302.972216)
				)
				(arc
					(start 167.05707 -302.972216)
					(mid 167.092991 -302.957337)
					(end 167.10787 -302.921416)
				)
				(arc
					(start 167.10787 -302.512476)
					(mid 167.092991 -302.476555)
					(end 167.05707 -302.461676)
				)
				(arc
					(start 165.65753 -302.461676)
					(mid 165.621609 -302.476555)
					(end 165.60673 -302.512476)
				)
			)
		)
	)
	(zone
		(layers "In1.Cu" "In2.Cu")
		(hatch none 0.5)
		(connect_pads
			(clearance 0)
		)
		(min_thickness 0.25)
		(keepout
			(tracks not_allowed)
			(vias allowed)
			(pads allowed)
			(copperpour not_allowed)
			(footprints allowed)
		)
		(placement
			(enabled no)
			(sheetname "")
		)
		(fill yes
			(thermal_gap 0.5)
			(thermal_bridge_width 0.5)
			(island_removal_mode 0)
		)
		(polygon
			(pts
				(arc
					(start 270.417798 -226.421442)
					(mid 270.432677 -226.457363)
					(end 270.468598 -226.472242)
				)
				(arc
					(start 271.868138 -226.472242)
					(mid 271.904059 -226.457363)
					(end 271.918938 -226.421442)
				)
				(arc
					(start 271.918938 -226.012502)
					(mid 271.904059 -225.976581)
					(end 271.868138 -225.961702)
				)
				(arc
					(start 270.468598 -225.961702)
					(mid 270.432677 -225.976581)
					(end 270.417798 -226.012502)
				)
			)
		)
	)
	(zone
		(layers "In1.Cu" "In2.Cu")
		(hatch none 0.5)
		(connect_pads
			(clearance 0)
		)
		(min_thickness 0.25)
		(keepout
			(tracks not_allowed)
			(vias allowed)
			(pads allowed)
			(copperpour not_allowed)
			(footprints allowed)
		)
		(placement
			(enabled no)
			(sheetname "")
		)
		(fill yes
			(thermal_gap 0.5)
			(thermal_bridge_width 0.5)
			(island_removal_mode 0)
		)
		(polygon
			(pts
				(arc
					(start 266.974066 -212.82152)
					(mid 266.988945 -212.857441)
					(end 267.024866 -212.87232)
				)
				(arc
					(start 268.424406 -212.87232)
					(mid 268.460327 -212.857441)
					(end 268.475206 -212.82152)
				)
				(arc
					(start 268.475206 -212.41258)
					(mid 268.460327 -212.376659)
					(end 268.424406 -212.36178)
				)
				(arc
					(start 267.024866 -212.36178)
					(mid 266.988945 -212.376659)
					(end 266.974066 -212.41258)
				)
			)
		)
	)
	(zone
		(layers "In1.Cu" "In2.Cu")
		(hatch none 0.5)
		(connect_pads
			(clearance 0)
		)
		(min_thickness 0.25)
		(keepout
			(tracks not_allowed)
			(vias allowed)
			(pads allowed)
			(copperpour not_allowed)
			(footprints allowed)
		)
		(placement
			(enabled no)
			(sheetname "")
		)
		(fill yes
			(thermal_gap 0.5)
			(thermal_bridge_width 0.5)
			(island_removal_mode 0)
		)
		(polygon
			(pts
				(arc
					(start 447.822066 -268.921484)
					(mid 447.836945 -268.957405)
					(end 447.872866 -268.972284)
				)
				(arc
					(start 449.272406 -268.972284)
					(mid 449.308327 -268.957405)
					(end 449.323206 -268.921484)
				)
				(arc
					(start 449.323206 -268.512544)
					(mid 449.308327 -268.476623)
					(end 449.272406 -268.461744)
				)
				(arc
					(start 447.872866 -268.461744)
					(mid 447.836945 -268.476623)
					(end 447.822066 -268.512544)
				)
			)
		)
	)
	(zone
		(layers "In1.Cu" "In2.Cu")
		(hatch none 0.5)
		(connect_pads
			(clearance 0)
		)
		(min_thickness 0.25)
		(keepout
			(tracks not_allowed)
			(vias allowed)
			(pads allowed)
			(copperpour not_allowed)
			(footprints allowed)
		)
		(placement
			(enabled no)
			(sheetname "")
		)
		(fill yes
			(thermal_gap 0.5)
			(thermal_bridge_width 0.5)
			(island_removal_mode 0)
		)
		(polygon
			(pts
				(arc
					(start 255.330198 -249.371358)
					(mid 255.345077 -249.407279)
					(end 255.380998 -249.422158)
				)
				(arc
					(start 256.780538 -249.422158)
					(mid 256.816459 -249.407279)
					(end 256.831338 -249.371358)
				)
				(arc
					(start 256.831338 -248.962418)
					(mid 256.816459 -248.926497)
					(end 256.780538 -248.911618)
				)
				(arc
					(start 255.380998 -248.911618)
					(mid 255.345077 -248.926497)
					(end 255.330198 -248.962418)
				)
			)
		)
	)
	(zone
		(layers "In1.Cu" "In2.Cu")
		(hatch none 0.5)
		(connect_pads
			(clearance 0)
		)
		(min_thickness 0.25)
		(keepout
			(tracks not_allowed)
			(vias allowed)
			(pads allowed)
			(copperpour not_allowed)
			(footprints allowed)
		)
		(placement
			(enabled no)
			(sheetname "")
		)
		(fill yes
			(thermal_gap 0.5)
			(thermal_bridge_width 0.5)
			(island_removal_mode 0)
		)
		(polygon
			(pts
				(arc
					(start 462.909666 -284.221428)
					(mid 462.924545 -284.257349)
					(end 462.960466 -284.272228)
				)
				(arc
					(start 464.360006 -284.272228)
					(mid 464.395927 -284.257349)
					(end 464.410806 -284.221428)
				)
				(arc
					(start 464.410806 -283.812488)
					(mid 464.395927 -283.776567)
					(end 464.360006 -283.761688)
				)
				(arc
					(start 462.960466 -283.761688)
					(mid 462.924545 -283.776567)
					(end 462.909666 -283.812488)
				)
			)
		)
	)
	(zone
		(layers "In1.Cu" "In2.Cu")
		(hatch none 0.5)
		(connect_pads
			(clearance 0)
		)
		(min_thickness 0.25)
		(keepout
			(tracks not_allowed)
			(vias allowed)
			(pads allowed)
			(copperpour not_allowed)
			(footprints allowed)
		)
		(placement
			(enabled no)
			(sheetname "")
		)
		(fill yes
			(thermal_gap 0.5)
			(thermal_bridge_width 0.5)
			(island_removal_mode 0)
		)
		(polygon
			(pts
				(arc
					(start 207.425798 -278.271478)
					(mid 207.440677 -278.307399)
					(end 207.476598 -278.322278)
				)
				(arc
					(start 208.876138 -278.322278)
					(mid 208.912059 -278.307399)
					(end 208.926938 -278.271478)
				)
				(arc
					(start 208.926938 -277.862538)
					(mid 208.912059 -277.826617)
					(end 208.876138 -277.811738)
				)
				(arc
					(start 207.476598 -277.811738)
					(mid 207.440677 -277.826617)
					(end 207.425798 -277.862538)
				)
			)
		)
	)
	(zone
		(layers "In1.Cu" "In2.Cu")
		(hatch none 0.5)
		(connect_pads
			(clearance 0)
		)
		(min_thickness 0.25)
		(keepout
			(tracks not_allowed)
			(vias allowed)
			(pads allowed)
			(copperpour not_allowed)
			(footprints allowed)
		)
		(placement
			(enabled no)
			(sheetname "")
		)
		(fill yes
			(thermal_gap 0.5)
			(thermal_bridge_width 0.5)
			(island_removal_mode 0)
		)
		(polygon
			(pts
				(arc
					(start 34.121598 -304.621438)
					(mid 34.136477 -304.657359)
					(end 34.172398 -304.672238)
				)
				(arc
					(start 35.571938 -304.672238)
					(mid 35.607859 -304.657359)
					(end 35.622738 -304.621438)
				)
				(arc
					(start 35.622738 -304.212498)
					(mid 35.607859 -304.176577)
					(end 35.571938 -304.161698)
				)
				(arc
					(start 34.172398 -304.161698)
					(mid 34.136477 -304.176577)
					(end 34.121598 -304.212498)
				)
			)
		)
	)
	(zone
		(layers "In1.Cu" "In2.Cu")
		(hatch none 0.5)
		(connect_pads
			(clearance 0)
		)
		(min_thickness 0.25)
		(keepout
			(tracks not_allowed)
			(vias allowed)
			(pads allowed)
			(copperpour not_allowed)
			(footprints allowed)
		)
		(placement
			(enabled no)
			(sheetname "")
		)
		(fill yes
			(thermal_gap 0.5)
			(thermal_bridge_width 0.5)
			(island_removal_mode 0)
		)
		(polygon
			(pts
				(arc
					(start 304.693066 -216.22131)
					(mid 304.707945 -216.257231)
					(end 304.743866 -216.27211)
				)
				(arc
					(start 306.143406 -216.27211)
					(mid 306.179327 -216.257231)
					(end 306.194206 -216.22131)
				)
				(arc
					(start 306.194206 -215.81237)
					(mid 306.179327 -215.776449)
					(end 306.143406 -215.76157)
				)
				(arc
					(start 304.743866 -215.76157)
					(mid 304.707945 -215.776449)
					(end 304.693066 -215.81237)
				)
			)
		)
	)
	(zone
		(layers "In1.Cu" "In2.Cu")
		(hatch none 0.5)
		(connect_pads
			(clearance 0)
		)
		(min_thickness 0.25)
		(keepout
			(tracks not_allowed)
			(vias allowed)
			(pads allowed)
			(copperpour not_allowed)
			(footprints allowed)
		)
		(placement
			(enabled no)
			(sheetname "")
		)
		(fill yes
			(thermal_gap 0.5)
			(thermal_bridge_width 0.5)
			(island_removal_mode 0)
		)
		(polygon
			(pts
				(arc
					(start 297.149266 -272.321528)
					(mid 297.164145 -272.357449)
					(end 297.200066 -272.372328)
				)
				(arc
					(start 298.599606 -272.372328)
					(mid 298.635527 -272.357449)
					(end 298.650406 -272.321528)
				)
				(arc
					(start 298.650406 -271.912588)
					(mid 298.635527 -271.876667)
					(end 298.599606 -271.861788)
				)
				(arc
					(start 297.200066 -271.861788)
					(mid 297.164145 -271.876667)
					(end 297.149266 -271.912588)
				)
			)
		)
	)
	(zone
		(layers "In1.Cu" "In2.Cu")
		(hatch none 0.5)
		(connect_pads
			(clearance 0)
		)
		(min_thickness 0.25)
		(keepout
			(tracks not_allowed)
			(vias allowed)
			(pads allowed)
			(copperpour not_allowed)
			(footprints allowed)
		)
		(placement
			(enabled no)
			(sheetname "")
		)
		(fill yes
			(thermal_gap 0.5)
			(thermal_bridge_width 0.5)
			(island_removal_mode 0)
		)
		(polygon
			(pts
				(arc
					(start 56.752998 -214.521542)
					(mid 56.767877 -214.557463)
					(end 56.803798 -214.572342)
				)
				(arc
					(start 58.203338 -214.572342)
					(mid 58.239259 -214.557463)
					(end 58.254138 -214.521542)
				)
				(arc
					(start 58.254138 -214.112602)
					(mid 58.239259 -214.076681)
					(end 58.203338 -214.061802)
				)
				(arc
					(start 56.803798 -214.061802)
					(mid 56.767877 -214.076681)
					(end 56.752998 -214.112602)
				)
			)
		)
	)
	(zone
		(layers "In1.Cu" "In2.Cu")
		(hatch none 0.5)
		(connect_pads
			(clearance 0)
		)
		(min_thickness 0.25)
		(keepout
			(tracks not_allowed)
			(vias allowed)
			(pads allowed)
			(copperpour not_allowed)
			(footprints allowed)
		)
		(placement
			(enabled no)
			(sheetname "")
		)
		(fill yes
			(thermal_gap 0.5)
			(thermal_bridge_width 0.5)
			(island_removal_mode 0)
		)
		(polygon
			(pts
				(arc
					(start 52.65293 -245.971314)
					(mid 52.667809 -246.007235)
					(end 52.70373 -246.022114)
				)
				(arc
					(start 54.10327 -246.022114)
					(mid 54.139191 -246.007235)
					(end 54.15407 -245.971314)
				)
				(arc
					(start 54.15407 -245.562374)
					(mid 54.139191 -245.526453)
					(end 54.10327 -245.511574)
				)
				(arc
					(start 52.70373 -245.511574)
					(mid 52.667809 -245.526453)
					(end 52.65293 -245.562374)
				)
			)
		)
	)
	(zone
		(layers "In1.Cu" "In2.Cu")
		(hatch none 0.5)
		(connect_pads
			(clearance 0)
		)
		(min_thickness 0.25)
		(keepout
			(tracks not_allowed)
			(vias allowed)
			(pads allowed)
			(copperpour not_allowed)
			(footprints allowed)
		)
		(placement
			(enabled no)
			(sheetname "")
		)
		(fill yes
			(thermal_gap 0.5)
			(thermal_bridge_width 0.5)
			(island_removal_mode 0)
		)
		(polygon
			(pts
				(arc
					(start 262.873998 -262.971534)
					(mid 262.888877 -263.007455)
					(end 262.924798 -263.022334)
				)
				(arc
					(start 264.324338 -263.022334)
					(mid 264.360259 -263.007455)
					(end 264.375138 -262.971534)
				)
				(arc
					(start 264.375138 -262.562594)
					(mid 264.360259 -262.526673)
					(end 264.324338 -262.511794)
				)
				(arc
					(start 262.924798 -262.511794)
					(mid 262.888877 -262.526673)
					(end 262.873998 -262.562594)
				)
			)
		)
	)
	(zone
		(layers "In1.Cu" "In2.Cu")
		(hatch none 0.5)
		(connect_pads
			(clearance 0)
		)
		(min_thickness 0.25)
		(keepout
			(tracks not_allowed)
			(vias allowed)
			(pads allowed)
			(copperpour not_allowed)
			(footprints allowed)
		)
		(placement
			(enabled no)
			(sheetname "")
		)
		(fill yes
			(thermal_gap 0.5)
			(thermal_bridge_width 0.5)
			(island_removal_mode 0)
		)
		(polygon
			(pts
				(arc
					(start 312.236866 -214.521542)
					(mid 312.251745 -214.557463)
					(end 312.287666 -214.572342)
				)
				(arc
					(start 313.687206 -214.572342)
					(mid 313.723127 -214.557463)
					(end 313.738006 -214.521542)
				)
				(arc
					(start 313.738006 -214.112602)
					(mid 313.723127 -214.076681)
					(end 313.687206 -214.061802)
				)
				(arc
					(start 312.287666 -214.061802)
					(mid 312.251745 -214.076681)
					(end 312.236866 -214.112602)
				)
			)
		)
	)
	(zone
		(layers "In1.Cu" "In2.Cu")
		(hatch none 0.5)
		(connect_pads
			(clearance 0)
		)
		(min_thickness 0.25)
		(keepout
			(tracks not_allowed)
			(vias allowed)
			(pads allowed)
			(copperpour not_allowed)
			(footprints allowed)
		)
		(placement
			(enabled no)
			(sheetname "")
		)
		(fill yes
			(thermal_gap 0.5)
			(thermal_bridge_width 0.5)
			(island_removal_mode 0)
		)
		(polygon
			(pts
				(arc
					(start 19.033998 -296.971466)
					(mid 19.048877 -297.007387)
					(end 19.084798 -297.022266)
				)
				(arc
					(start 20.484338 -297.022266)
					(mid 20.520259 -297.007387)
					(end 20.535138 -296.971466)
				)
				(arc
					(start 20.535138 -296.562526)
					(mid 20.520259 -296.526605)
					(end 20.484338 -296.511726)
				)
				(arc
					(start 19.084798 -296.511726)
					(mid 19.048877 -296.526605)
					(end 19.033998 -296.562526)
				)
			)
		)
	)
	(zone
		(layers "In1.Cu" "In2.Cu")
		(hatch none 0.5)
		(connect_pads
			(clearance 0)
		)
		(min_thickness 0.25)
		(keepout
			(tracks not_allowed)
			(vias allowed)
			(pads allowed)
			(copperpour not_allowed)
			(footprints allowed)
		)
		(placement
			(enabled no)
			(sheetname "")
		)
		(fill yes
			(thermal_gap 0.5)
			(thermal_bridge_width 0.5)
			(island_removal_mode 0)
		)
		(polygon
			(pts
				(arc
					(start 458.809598 -206.021432)
					(mid 458.824477 -206.057353)
					(end 458.860398 -206.072232)
				)
				(arc
					(start 460.259938 -206.072232)
					(mid 460.295859 -206.057353)
					(end 460.310738 -206.021432)
				)
				(arc
					(start 460.310738 -205.612492)
					(mid 460.295859 -205.576571)
					(end 460.259938 -205.561692)
				)
				(arc
					(start 458.860398 -205.561692)
					(mid 458.824477 -205.576571)
					(end 458.809598 -205.612492)
				)
			)
		)
	)
	(zone
		(layers "In1.Cu" "In2.Cu")
		(hatch none 0.5)
		(connect_pads
			(clearance 0)
		)
		(min_thickness 0.25)
		(keepout
			(tracks not_allowed)
			(vias allowed)
			(pads allowed)
			(copperpour not_allowed)
			(footprints allowed)
		)
		(placement
			(enabled no)
			(sheetname "")
		)
		(fill yes
			(thermal_gap 0.5)
			(thermal_bridge_width 0.5)
			(island_removal_mode 0)
		)
		(polygon
			(pts
				(arc
					(start 203.32573 -284.221428)
					(mid 203.340609 -284.257349)
					(end 203.37653 -284.272228)
				)
				(arc
					(start 204.77607 -284.272228)
					(mid 204.811991 -284.257349)
					(end 204.82687 -284.221428)
				)
				(arc
					(start 204.82687 -283.812488)
					(mid 204.811991 -283.776567)
					(end 204.77607 -283.761688)
				)
				(arc
					(start 203.37653 -283.761688)
					(mid 203.340609 -283.776567)
					(end 203.32573 -283.812488)
				)
			)
		)
	)
	(zone
		(layers "In1.Cu" "In2.Cu")
		(hatch none 0.5)
		(connect_pads
			(clearance 0)
		)
		(min_thickness 0.25)
		(keepout
			(tracks not_allowed)
			(vias allowed)
			(pads allowed)
			(copperpour not_allowed)
			(footprints allowed)
		)
		(placement
			(enabled no)
			(sheetname "")
		)
		(fill yes
			(thermal_gap 0.5)
			(thermal_bridge_width 0.5)
			(island_removal_mode 0)
		)
		(polygon
			(pts
				(arc
					(start 64.296798 -206.871316)
					(mid 64.311677 -206.907237)
					(end 64.347598 -206.922116)
				)
				(arc
					(start 65.747138 -206.922116)
					(mid 65.783059 -206.907237)
					(end 65.797938 -206.871316)
				)
				(arc
					(start 65.797938 -206.462376)
					(mid 65.783059 -206.426455)
					(end 65.747138 -206.411576)
				)
				(arc
					(start 64.347598 -206.411576)
					(mid 64.311677 -206.426455)
					(end 64.296798 -206.462376)
				)
			)
		)
	)
	(zone
		(layers "In1.Cu" "In2.Cu")
		(hatch none 0.5)
		(connect_pads
			(clearance 0)
		)
		(min_thickness 0.25)
		(keepout
			(tracks not_allowed)
			(vias allowed)
			(pads allowed)
			(copperpour not_allowed)
			(footprints allowed)
		)
		(placement
			(enabled no)
			(sheetname "")
		)
		(fill yes
			(thermal_gap 0.5)
			(thermal_bridge_width 0.5)
			(island_removal_mode 0)
		)
		(polygon
			(pts
				(arc
					(start 14.93393 -204.32141)
					(mid 14.948809 -204.357331)
					(end 14.98473 -204.37221)
				)
				(arc
					(start 16.38427 -204.37221)
					(mid 16.420191 -204.357331)
					(end 16.43507 -204.32141)
				)
				(arc
					(start 16.43507 -203.91247)
					(mid 16.420191 -203.876549)
					(end 16.38427 -203.86167)
				)
				(arc
					(start 14.98473 -203.86167)
					(mid 14.948809 -203.876549)
					(end 14.93393 -203.91247)
				)
			)
		)
	)
	(zone
		(layers "In1.Cu" "In2.Cu")
		(hatch none 0.5)
		(connect_pads
			(clearance 0)
		)
		(min_thickness 0.25)
		(keepout
			(tracks not_allowed)
			(vias allowed)
			(pads allowed)
			(copperpour not_allowed)
			(footprints allowed)
		)
		(placement
			(enabled no)
			(sheetname "")
		)
		(fill yes
			(thermal_gap 0.5)
			(thermal_bridge_width 0.5)
			(island_removal_mode 0)
		)
		(polygon
			(pts
				(arc
					(start 417.646866 -289.321494)
					(mid 417.661745 -289.357415)
					(end 417.697666 -289.372294)
				)
				(arc
					(start 419.097206 -289.372294)
					(mid 419.133127 -289.357415)
					(end 419.148006 -289.321494)
				)
				(arc
					(start 419.148006 -288.912554)
					(mid 419.133127 -288.876633)
					(end 419.097206 -288.861754)
				)
				(arc
					(start 417.697666 -288.861754)
					(mid 417.661745 -288.876633)
					(end 417.646866 -288.912554)
				)
			)
		)
	)
	(zone
		(layers "In1.Cu" "In2.Cu")
		(hatch none 0.5)
		(connect_pads
			(clearance 0)
		)
		(min_thickness 0.25)
		(keepout
			(tracks not_allowed)
			(vias allowed)
			(pads allowed)
			(copperpour not_allowed)
			(footprints allowed)
		)
		(placement
			(enabled no)
			(sheetname "")
		)
		(fill yes
			(thermal_gap 0.5)
			(thermal_bridge_width 0.5)
			(island_removal_mode 0)
		)
		(polygon
			(pts
				(arc
					(start 447.822066 -315.671454)
					(mid 447.836945 -315.707375)
					(end 447.872866 -315.722254)
				)
				(arc
					(start 449.272406 -315.722254)
					(mid 449.308327 -315.707375)
					(end 449.323206 -315.671454)
				)
				(arc
					(start 449.323206 -315.262514)
					(mid 449.308327 -315.226593)
					(end 449.272406 -315.211714)
				)
				(arc
					(start 447.872866 -315.211714)
					(mid 447.836945 -315.226593)
					(end 447.822066 -315.262514)
				)
			)
		)
	)
	(zone
		(layers "In1.Cu" "In2.Cu")
		(hatch none 0.5)
		(connect_pads
			(clearance 0)
		)
		(min_thickness 0.25)
		(keepout
			(tracks not_allowed)
			(vias allowed)
			(pads allowed)
			(copperpour not_allowed)
			(footprints allowed)
		)
		(placement
			(enabled no)
			(sheetname "")
		)
		(fill yes
			(thermal_gap 0.5)
			(thermal_bridge_width 0.5)
			(island_removal_mode 0)
		)
		(polygon
			(pts
				(arc
					(start 64.296798 -278.271478)
					(mid 64.311677 -278.307399)
					(end 64.347598 -278.322278)
				)
				(arc
					(start 65.747138 -278.322278)
					(mid 65.783059 -278.307399)
					(end 65.797938 -278.271478)
				)
				(arc
					(start 65.797938 -277.862538)
					(mid 65.783059 -277.826617)
					(end 65.747138 -277.811738)
				)
				(arc
					(start 64.347598 -277.811738)
					(mid 64.311677 -277.826617)
					(end 64.296798 -277.862538)
				)
			)
		)
	)
	(zone
		(layers "In1.Cu" "In2.Cu")
		(hatch none 0.5)
		(connect_pads
			(clearance 0)
		)
		(min_thickness 0.25)
		(keepout
			(tracks not_allowed)
			(vias allowed)
			(pads allowed)
			(copperpour not_allowed)
			(footprints allowed)
		)
		(placement
			(enabled no)
			(sheetname "")
		)
		(fill yes
			(thermal_gap 0.5)
			(thermal_bridge_width 0.5)
			(island_removal_mode 0)
		)
		(polygon
			(pts
				(arc
					(start 270.417798 -202.621388)
					(mid 270.432677 -202.657309)
					(end 270.468598 -202.672188)
				)
				(arc
					(start 271.868138 -202.672188)
					(mid 271.904059 -202.657309)
					(end 271.918938 -202.621388)
				)
				(arc
					(start 271.918938 -202.212448)
					(mid 271.904059 -202.176527)
					(end 271.868138 -202.161648)
				)
				(arc
					(start 270.468598 -202.161648)
					(mid 270.432677 -202.176527)
					(end 270.417798 -202.212448)
				)
			)
		)
	)
	(zone
		(layers "In1.Cu" "In2.Cu")
		(hatch none 0.5)
		(connect_pads
			(clearance 0)
		)
		(min_thickness 0.25)
		(keepout
			(tracks not_allowed)
			(vias allowed)
			(pads allowed)
			(copperpour not_allowed)
			(footprints allowed)
		)
		(placement
			(enabled no)
			(sheetname "")
		)
		(fill yes
			(thermal_gap 0.5)
			(thermal_bridge_width 0.5)
			(island_removal_mode 0)
		)
		(polygon
			(pts
				(arc
					(start 26.577798 -289.321494)
					(mid 26.592677 -289.357415)
					(end 26.628598 -289.372294)
				)
				(arc
					(start 28.028138 -289.372294)
					(mid 28.064059 -289.357415)
					(end 28.078938 -289.321494)
				)
				(arc
					(start 28.078938 -288.912554)
					(mid 28.064059 -288.876633)
					(end 28.028138 -288.861754)
				)
				(arc
					(start 26.628598 -288.861754)
					(mid 26.592677 -288.876633)
					(end 26.577798 -288.912554)
				)
			)
		)
	)
	(zone
		(layers "In1.Cu" "In2.Cu")
		(hatch none 0.5)
		(connect_pads
			(clearance 0)
		)
		(min_thickness 0.25)
		(keepout
			(tracks not_allowed)
			(vias allowed)
			(pads allowed)
			(copperpour not_allowed)
			(footprints allowed)
		)
		(placement
			(enabled no)
			(sheetname "")
		)
		(fill yes
			(thermal_gap 0.5)
			(thermal_bridge_width 0.5)
			(island_removal_mode 0)
		)
		(polygon
			(pts
				(arc
					(start 293.049198 -232.371392)
					(mid 293.064077 -232.407313)
					(end 293.099998 -232.422192)
				)
				(arc
					(start 294.499538 -232.422192)
					(mid 294.535459 -232.407313)
					(end 294.550338 -232.371392)
				)
				(arc
					(start 294.550338 -231.962452)
					(mid 294.535459 -231.926531)
					(end 294.499538 -231.911652)
				)
				(arc
					(start 293.099998 -231.911652)
					(mid 293.064077 -231.926531)
					(end 293.049198 -231.962452)
				)
			)
		)
	)
	(zone
		(layers "In1.Cu" "In2.Cu")
		(hatch none 0.5)
		(connect_pads
			(clearance 0)
		)
		(min_thickness 0.25)
		(keepout
			(tracks not_allowed)
			(vias allowed)
			(pads allowed)
			(copperpour not_allowed)
			(footprints allowed)
		)
		(placement
			(enabled no)
			(sheetname "")
		)
		(fill yes
			(thermal_gap 0.5)
			(thermal_bridge_width 0.5)
			(island_removal_mode 0)
		)
		(polygon
			(pts
				(arc
					(start 177.250598 -276.571456)
					(mid 177.265477 -276.607377)
					(end 177.301398 -276.622256)
				)
				(arc
					(start 178.700938 -276.622256)
					(mid 178.736859 -276.607377)
					(end 178.751738 -276.571456)
				)
				(arc
					(start 178.751738 -276.162516)
					(mid 178.736859 -276.126595)
					(end 178.700938 -276.111716)
				)
				(arc
					(start 177.301398 -276.111716)
					(mid 177.265477 -276.126595)
					(end 177.250598 -276.162516)
				)
			)
		)
	)
	(zone
		(layers "In1.Cu" "In2.Cu")
		(hatch none 0.5)
		(connect_pads
			(clearance 0)
		)
		(min_thickness 0.25)
		(keepout
			(tracks not_allowed)
			(vias allowed)
			(pads allowed)
			(copperpour not_allowed)
			(footprints allowed)
		)
		(placement
			(enabled no)
			(sheetname "")
		)
		(fill yes
			(thermal_gap 0.5)
			(thermal_bridge_width 0.5)
			(island_removal_mode 0)
		)
		(polygon
			(pts
				(arc
					(start 274.517866 -227.271326)
					(mid 274.532745 -227.307247)
					(end 274.568666 -227.322126)
				)
				(arc
					(start 275.968206 -227.322126)
					(mid 276.004127 -227.307247)
					(end 276.019006 -227.271326)
				)
				(arc
					(start 276.019006 -226.862386)
					(mid 276.004127 -226.826465)
					(end 275.968206 -226.811586)
				)
				(arc
					(start 274.568666 -226.811586)
					(mid 274.532745 -226.826465)
					(end 274.517866 -226.862386)
				)
			)
		)
	)
	(zone
		(layers "In1.Cu" "In2.Cu")
		(hatch none 0.5)
		(connect_pads
			(clearance 0)
		)
		(min_thickness 0.25)
		(keepout
			(tracks not_allowed)
			(vias allowed)
			(pads allowed)
			(copperpour not_allowed)
			(footprints allowed)
		)
		(placement
			(enabled no)
			(sheetname "")
		)
		(fill yes
			(thermal_gap 0.5)
			(thermal_bridge_width 0.5)
			(island_removal_mode 0)
		)
		(polygon
			(pts
				(arc
					(start 203.32573 -303.7713)
					(mid 203.340609 -303.807221)
					(end 203.37653 -303.8221)
				)
				(arc
					(start 204.77607 -303.8221)
					(mid 204.811991 -303.807221)
					(end 204.82687 -303.7713)
				)
				(arc
					(start 204.82687 -303.36236)
					(mid 204.811991 -303.326439)
					(end 204.77607 -303.31156)
				)
				(arc
					(start 203.37653 -303.31156)
					(mid 203.340609 -303.326439)
					(end 203.32573 -303.36236)
				)
			)
		)
	)
	(zone
		(layers "In1.Cu" "In2.Cu")
		(hatch none 0.5)
		(connect_pads
			(clearance 0)
		)
		(min_thickness 0.25)
		(keepout
			(tracks not_allowed)
			(vias allowed)
			(pads allowed)
			(copperpour not_allowed)
			(footprints allowed)
		)
		(placement
			(enabled no)
			(sheetname "")
		)
		(fill yes
			(thermal_gap 0.5)
			(thermal_bridge_width 0.5)
			(island_removal_mode 0)
		)
		(polygon
			(pts
				(arc
					(start 259.430266 -311.421526)
					(mid 259.445145 -311.457447)
					(end 259.481066 -311.472326)
				)
				(arc
					(start 260.880606 -311.472326)
					(mid 260.916527 -311.457447)
					(end 260.931406 -311.421526)
				)
				(arc
					(start 260.931406 -311.012586)
					(mid 260.916527 -310.976665)
					(end 260.880606 -310.961786)
				)
				(arc
					(start 259.481066 -310.961786)
					(mid 259.445145 -310.976665)
					(end 259.430266 -311.012586)
				)
			)
		)
	)
	(zone
		(layers "In1.Cu" "In2.Cu")
		(hatch none 0.5)
		(connect_pads
			(clearance 0)
		)
		(min_thickness 0.25)
		(keepout
			(tracks not_allowed)
			(vias allowed)
			(pads allowed)
			(copperpour not_allowed)
			(footprints allowed)
		)
		(placement
			(enabled no)
			(sheetname "")
		)
		(fill yes
			(thermal_gap 0.5)
			(thermal_bridge_width 0.5)
			(island_removal_mode 0)
		)
		(polygon
			(pts
				(arc
					(start 274.517866 -268.921484)
					(mid 274.532745 -268.957405)
					(end 274.568666 -268.972284)
				)
				(arc
					(start 275.968206 -268.972284)
					(mid 276.004127 -268.957405)
					(end 276.019006 -268.921484)
				)
				(arc
					(start 276.019006 -268.512544)
					(mid 276.004127 -268.476623)
					(end 275.968206 -268.461744)
				)
				(arc
					(start 274.568666 -268.461744)
					(mid 274.532745 -268.476623)
					(end 274.517866 -268.512544)
				)
			)
		)
	)
	(zone
		(layers "In1.Cu" "In2.Cu")
		(hatch none 0.5)
		(connect_pads
			(clearance 0)
		)
		(min_thickness 0.25)
		(keepout
			(tracks not_allowed)
			(vias allowed)
			(pads allowed)
			(copperpour not_allowed)
			(footprints allowed)
		)
		(placement
			(enabled no)
			(sheetname "")
		)
		(fill yes
			(thermal_gap 0.5)
			(thermal_bridge_width 0.5)
			(island_removal_mode 0)
		)
		(polygon
			(pts
				(arc
					(start 165.60673 -277.42134)
					(mid 165.621609 -277.457261)
					(end 165.65753 -277.47214)
				)
				(arc
					(start 167.05707 -277.47214)
					(mid 167.092991 -277.457261)
					(end 167.10787 -277.42134)
				)
				(arc
					(start 167.10787 -277.0124)
					(mid 167.092991 -276.976479)
					(end 167.05707 -276.9616)
				)
				(arc
					(start 165.65753 -276.9616)
					(mid 165.621609 -276.976479)
					(end 165.60673 -277.0124)
				)
			)
		)
	)
	(zone
		(layers "In1.Cu" "In2.Cu")
		(hatch none 0.5)
		(connect_pads
			(clearance 0)
		)
		(min_thickness 0.25)
		(keepout
			(tracks not_allowed)
			(vias allowed)
			(pads allowed)
			(copperpour not_allowed)
			(footprints allowed)
		)
		(placement
			(enabled no)
			(sheetname "")
		)
		(fill yes
			(thermal_gap 0.5)
			(thermal_bridge_width 0.5)
			(island_removal_mode 0)
		)
		(polygon
			(pts
				(arc
					(start 282.061666 -274.02155)
					(mid 282.076545 -274.057471)
					(end 282.112466 -274.07235)
				)
				(arc
					(start 283.512006 -274.07235)
					(mid 283.547927 -274.057471)
					(end 283.562806 -274.02155)
				)
				(arc
					(start 283.562806 -273.61261)
					(mid 283.547927 -273.576689)
					(end 283.512006 -273.56181)
				)
				(arc
					(start 282.112466 -273.56181)
					(mid 282.076545 -273.576689)
					(end 282.061666 -273.61261)
				)
			)
		)
	)
	(zone
		(layers "In1.Cu" "In2.Cu")
		(hatch none 0.5)
		(connect_pads
			(clearance 0)
		)
		(min_thickness 0.25)
		(keepout
			(tracks not_allowed)
			(vias allowed)
			(pads allowed)
			(copperpour not_allowed)
			(footprints allowed)
		)
		(placement
			(enabled no)
			(sheetname "")
		)
		(fill yes
			(thermal_gap 0.5)
			(thermal_bridge_width 0.5)
			(island_removal_mode 0)
		)
		(polygon
			(pts
				(arc
					(start 458.809598 -308.871366)
					(mid 458.824477 -308.907287)
					(end 458.860398 -308.922166)
				)
				(arc
					(start 460.259938 -308.922166)
					(mid 460.295859 -308.907287)
					(end 460.310738 -308.871366)
				)
				(arc
					(start 460.310738 -308.462426)
					(mid 460.295859 -308.426505)
					(end 460.259938 -308.411626)
				)
				(arc
					(start 458.860398 -308.411626)
					(mid 458.824477 -308.426505)
					(end 458.809598 -308.462426)
				)
			)
		)
	)
	(zone
		(layers "In1.Cu" "In2.Cu")
		(hatch none 0.5)
		(connect_pads
			(clearance 0)
		)
		(min_thickness 0.25)
		(keepout
			(tracks not_allowed)
			(vias allowed)
			(pads allowed)
			(copperpour not_allowed)
			(footprints allowed)
		)
		(placement
			(enabled no)
			(sheetname "")
		)
		(fill yes
			(thermal_gap 0.5)
			(thermal_bridge_width 0.5)
			(island_removal_mode 0)
		)
		(polygon
			(pts
				(arc
					(start 19.033998 -214.521542)
					(mid 19.048877 -214.557463)
					(end 19.084798 -214.572342)
				)
				(arc
					(start 20.484338 -214.572342)
					(mid 20.520259 -214.557463)
					(end 20.535138 -214.521542)
				)
				(arc
					(start 20.535138 -214.112602)
					(mid 20.520259 -214.076681)
					(end 20.484338 -214.061802)
				)
				(arc
					(start 19.084798 -214.061802)
					(mid 19.048877 -214.076681)
					(end 19.033998 -214.112602)
				)
			)
		)
	)
	(zone
		(layers "In1.Cu" "In2.Cu")
		(hatch none 0.5)
		(connect_pads
			(clearance 0)
		)
		(min_thickness 0.25)
		(keepout
			(tracks not_allowed)
			(vias allowed)
			(pads allowed)
			(copperpour not_allowed)
			(footprints allowed)
		)
		(placement
			(enabled no)
			(sheetname "")
		)
		(fill yes
			(thermal_gap 0.5)
			(thermal_bridge_width 0.5)
			(island_removal_mode 0)
		)
		(polygon
			(pts
				(arc
					(start 52.65293 -204.32141)
					(mid 52.667809 -204.357331)
					(end 52.70373 -204.37221)
				)
				(arc
					(start 54.10327 -204.37221)
					(mid 54.139191 -204.357331)
					(end 54.15407 -204.32141)
				)
				(arc
					(start 54.15407 -203.91247)
					(mid 54.139191 -203.876549)
					(end 54.10327 -203.86167)
				)
				(arc
					(start 52.70373 -203.86167)
					(mid 52.667809 -203.876549)
					(end 52.65293 -203.91247)
				)
			)
		)
	)
	(zone
		(layers "In1.Cu" "In2.Cu")
		(hatch none 0.5)
		(connect_pads
			(clearance 0)
		)
		(min_thickness 0.25)
		(keepout
			(tracks not_allowed)
			(vias allowed)
			(pads allowed)
			(copperpour not_allowed)
			(footprints allowed)
		)
		(placement
			(enabled no)
			(sheetname "")
		)
		(fill yes
			(thermal_gap 0.5)
			(thermal_bridge_width 0.5)
			(island_removal_mode 0)
		)
		(polygon
			(pts
				(arc
					(start 207.425798 -304.621438)
					(mid 207.440677 -304.657359)
					(end 207.476598 -304.672238)
				)
				(arc
					(start 208.876138 -304.672238)
					(mid 208.912059 -304.657359)
					(end 208.926938 -304.621438)
				)
				(arc
					(start 208.926938 -304.212498)
					(mid 208.912059 -304.176577)
					(end 208.876138 -304.161698)
				)
				(arc
					(start 207.476598 -304.161698)
					(mid 207.440677 -304.176577)
					(end 207.425798 -304.212498)
				)
			)
		)
	)
	(zone
		(layers "In1.Cu" "In2.Cu")
		(hatch none 0.5)
		(connect_pads
			(clearance 0)
		)
		(min_thickness 0.25)
		(keepout
			(tracks not_allowed)
			(vias allowed)
			(pads allowed)
			(copperpour not_allowed)
			(footprints allowed)
		)
		(placement
			(enabled no)
			(sheetname "")
		)
		(fill yes
			(thermal_gap 0.5)
			(thermal_bridge_width 0.5)
			(island_removal_mode 0)
		)
		(polygon
			(pts
				(arc
					(start 169.706798 -240.871502)
					(mid 169.721677 -240.907423)
					(end 169.757598 -240.922302)
				)
				(arc
					(start 171.157138 -240.922302)
					(mid 171.193059 -240.907423)
					(end 171.207938 -240.871502)
				)
				(arc
					(start 171.207938 -240.462562)
					(mid 171.193059 -240.426641)
					(end 171.157138 -240.411762)
				)
				(arc
					(start 169.757598 -240.411762)
					(mid 169.721677 -240.426641)
					(end 169.706798 -240.462562)
				)
			)
		)
	)
	(zone
		(layers "In1.Cu" "In2.Cu")
		(hatch none 0.5)
		(connect_pads
			(clearance 0)
		)
		(min_thickness 0.25)
		(keepout
			(tracks not_allowed)
			(vias allowed)
			(pads allowed)
			(copperpour not_allowed)
			(footprints allowed)
		)
		(placement
			(enabled no)
			(sheetname "")
		)
		(fill yes
			(thermal_gap 0.5)
			(thermal_bridge_width 0.5)
			(island_removal_mode 0)
		)
		(polygon
			(pts
				(arc
					(start 56.752998 -227.271326)
					(mid 56.767877 -227.307247)
					(end 56.803798 -227.322126)
				)
				(arc
					(start 58.203338 -227.322126)
					(mid 58.239259 -227.307247)
					(end 58.254138 -227.271326)
				)
				(arc
					(start 58.254138 -226.862386)
					(mid 58.239259 -226.826465)
					(end 58.203338 -226.811586)
				)
				(arc
					(start 56.803798 -226.811586)
					(mid 56.767877 -226.826465)
					(end 56.752998 -226.862386)
				)
			)
		)
	)
	(zone
		(layers "In1.Cu" "In2.Cu")
		(hatch none 0.5)
		(connect_pads
			(clearance 0)
		)
		(min_thickness 0.25)
		(keepout
			(tracks not_allowed)
			(vias allowed)
			(pads allowed)
			(copperpour not_allowed)
			(footprints allowed)
		)
		(placement
			(enabled no)
			(sheetname "")
		)
		(fill yes
			(thermal_gap 0.5)
			(thermal_bridge_width 0.5)
			(island_removal_mode 0)
		)
		(polygon
			(pts
				(arc
					(start 285.505398 -274.871434)
					(mid 285.520277 -274.907355)
					(end 285.556198 -274.922234)
				)
				(arc
					(start 286.955738 -274.922234)
					(mid 286.991659 -274.907355)
					(end 287.006538 -274.871434)
				)
				(arc
					(start 287.006538 -274.462494)
					(mid 286.991659 -274.426573)
					(end 286.955738 -274.411694)
				)
				(arc
					(start 285.556198 -274.411694)
					(mid 285.520277 -274.426573)
					(end 285.505398 -274.462494)
				)
			)
		)
	)
	(zone
		(layers "In1.Cu" "In2.Cu")
		(hatch none 0.5)
		(connect_pads
			(clearance 0)
		)
		(min_thickness 0.25)
		(keepout
			(tracks not_allowed)
			(vias allowed)
			(pads allowed)
			(copperpour not_allowed)
			(footprints allowed)
		)
		(placement
			(enabled no)
			(sheetname "")
		)
		(fill yes
			(thermal_gap 0.5)
			(thermal_bridge_width 0.5)
			(island_removal_mode 0)
		)
		(polygon
			(pts
				(arc
					(start 428.634398 -305.471322)
					(mid 428.649277 -305.507243)
					(end 428.685198 -305.522122)
				)
				(arc
					(start 430.084738 -305.522122)
					(mid 430.120659 -305.507243)
					(end 430.135538 -305.471322)
				)
				(arc
					(start 430.135538 -305.062382)
					(mid 430.120659 -305.026461)
					(end 430.084738 -305.011582)
				)
				(arc
					(start 428.685198 -305.011582)
					(mid 428.649277 -305.026461)
					(end 428.634398 -305.062382)
				)
			)
		)
	)
	(zone
		(layers "In1.Cu" "In2.Cu")
		(hatch none 0.5)
		(connect_pads
			(clearance 0)
		)
		(min_thickness 0.25)
		(keepout
			(tracks not_allowed)
			(vias allowed)
			(pads allowed)
			(copperpour not_allowed)
			(footprints allowed)
		)
		(placement
			(enabled no)
			(sheetname "")
		)
		(fill yes
			(thermal_gap 0.5)
			(thermal_bridge_width 0.5)
			(island_removal_mode 0)
		)
		(polygon
			(pts
				(arc
					(start 207.425798 -274.871434)
					(mid 207.440677 -274.907355)
					(end 207.476598 -274.922234)
				)
				(arc
					(start 208.876138 -274.922234)
					(mid 208.912059 -274.907355)
					(end 208.926938 -274.871434)
				)
				(arc
					(start 208.926938 -274.462494)
					(mid 208.912059 -274.426573)
					(end 208.876138 -274.411694)
				)
				(arc
					(start 207.476598 -274.411694)
					(mid 207.440677 -274.426573)
					(end 207.425798 -274.462494)
				)
			)
		)
	)
	(zone
		(layers "In1.Cu" "In2.Cu")
		(hatch none 0.5)
		(connect_pads
			(clearance 0)
		)
		(min_thickness 0.25)
		(keepout
			(tracks not_allowed)
			(vias allowed)
			(pads allowed)
			(copperpour not_allowed)
			(footprints allowed)
		)
		(placement
			(enabled no)
			(sheetname "")
		)
		(fill yes
			(thermal_gap 0.5)
			(thermal_bridge_width 0.5)
			(island_removal_mode 0)
		)
		(polygon
			(pts
				(arc
					(start 165.60673 -291.8714)
					(mid 165.621609 -291.907321)
					(end 165.65753 -291.9222)
				)
				(arc
					(start 167.05707 -291.9222)
					(mid 167.092991 -291.907321)
					(end 167.10787 -291.8714)
				)
				(arc
					(start 167.10787 -291.46246)
					(mid 167.092991 -291.426539)
					(end 167.05707 -291.41166)
				)
				(arc
					(start 165.65753 -291.41166)
					(mid 165.621609 -291.426539)
					(end 165.60673 -291.46246)
				)
			)
		)
	)
	(zone
		(layers "In1.Cu" "In2.Cu")
		(hatch none 0.5)
		(connect_pads
			(clearance 0)
		)
		(min_thickness 0.25)
		(keepout
			(tracks not_allowed)
			(vias allowed)
			(pads allowed)
			(copperpour not_allowed)
			(footprints allowed)
		)
		(placement
			(enabled no)
			(sheetname "")
		)
		(fill yes
			(thermal_gap 0.5)
			(thermal_bridge_width 0.5)
			(island_removal_mode 0)
		)
		(polygon
			(pts
				(arc
					(start 203.32573 -252.771402)
					(mid 203.340609 -252.807323)
					(end 203.37653 -252.822202)
				)
				(arc
					(start 204.77607 -252.822202)
					(mid 204.811991 -252.807323)
					(end 204.82687 -252.771402)
				)
				(arc
					(start 204.82687 -252.362462)
					(mid 204.811991 -252.326541)
					(end 204.77607 -252.311662)
				)
				(arc
					(start 203.37653 -252.311662)
					(mid 203.340609 -252.326541)
					(end 203.32573 -252.362462)
				)
			)
		)
	)
	(zone
		(layers "In1.Cu" "In2.Cu")
		(hatch none 0.5)
		(connect_pads
			(clearance 0)
		)
		(min_thickness 0.25)
		(keepout
			(tracks not_allowed)
			(vias allowed)
			(pads allowed)
			(copperpour not_allowed)
			(footprints allowed)
		)
		(placement
			(enabled no)
			(sheetname "")
		)
		(fill yes
			(thermal_gap 0.5)
			(thermal_bridge_width 0.5)
			(island_removal_mode 0)
		)
		(polygon
			(pts
				(arc
					(start 56.752998 -311.421526)
					(mid 56.767877 -311.457447)
					(end 56.803798 -311.472326)
				)
				(arc
					(start 58.203338 -311.472326)
					(mid 58.239259 -311.457447)
					(end 58.254138 -311.421526)
				)
				(arc
					(start 58.254138 -311.012586)
					(mid 58.239259 -310.976665)
					(end 58.203338 -310.961786)
				)
				(arc
					(start 56.803798 -310.961786)
					(mid 56.767877 -310.976665)
					(end 56.752998 -311.012586)
				)
			)
		)
	)
	(zone
		(layers "In1.Cu" "In2.Cu")
		(hatch none 0.5)
		(connect_pads
			(clearance 0)
		)
		(min_thickness 0.25)
		(keepout
			(tracks not_allowed)
			(vias allowed)
			(pads allowed)
			(copperpour not_allowed)
			(footprints allowed)
		)
		(placement
			(enabled no)
			(sheetname "")
		)
		(fill yes
			(thermal_gap 0.5)
			(thermal_bridge_width 0.5)
			(island_removal_mode 0)
		)
		(polygon
			(pts
				(arc
					(start 425.190666 -218.77147)
					(mid 425.205545 -218.807391)
					(end 425.241466 -218.82227)
				)
				(arc
					(start 426.641006 -218.82227)
					(mid 426.676927 -218.807391)
					(end 426.691806 -218.77147)
				)
				(arc
					(start 426.691806 -218.36253)
					(mid 426.676927 -218.326609)
					(end 426.641006 -218.31173)
				)
				(arc
					(start 425.241466 -218.31173)
					(mid 425.205545 -218.326609)
					(end 425.190666 -218.36253)
				)
			)
		)
	)
	(zone
		(layers "In1.Cu" "In2.Cu")
		(hatch none 0.5)
		(connect_pads
			(clearance 0)
		)
		(min_thickness 0.25)
		(keepout
			(tracks not_allowed)
			(vias allowed)
			(pads allowed)
			(copperpour not_allowed)
			(footprints allowed)
		)
		(placement
			(enabled no)
			(sheetname "")
		)
		(fill yes
			(thermal_gap 0.5)
			(thermal_bridge_width 0.5)
			(island_removal_mode 0)
		)
		(polygon
			(pts
				(arc
					(start 14.93393 -243.421408)
					(mid 14.948809 -243.457329)
					(end 14.98473 -243.472208)
				)
				(arc
					(start 16.38427 -243.472208)
					(mid 16.420191 -243.457329)
					(end 16.43507 -243.421408)
				)
				(arc
					(start 16.43507 -243.012468)
					(mid 16.420191 -242.976547)
					(end 16.38427 -242.961668)
				)
				(arc
					(start 14.98473 -242.961668)
					(mid 14.948809 -242.976547)
					(end 14.93393 -243.012468)
				)
			)
		)
	)
	(zone
		(layers "In1.Cu" "In2.Cu")
		(hatch none 0.5)
		(connect_pads
			(clearance 0)
		)
		(min_thickness 0.25)
		(keepout
			(tracks not_allowed)
			(vias allowed)
			(pads allowed)
			(copperpour not_allowed)
			(footprints allowed)
		)
		(placement
			(enabled no)
			(sheetname "")
		)
		(fill yes
			(thermal_gap 0.5)
			(thermal_bridge_width 0.5)
			(island_removal_mode 0)
		)
		(polygon
			(pts
				(arc
					(start 440.278266 -312.27141)
					(mid 440.293145 -312.307331)
					(end 440.329066 -312.32221)
				)
				(arc
					(start 441.728606 -312.32221)
					(mid 441.764527 -312.307331)
					(end 441.779406 -312.27141)
				)
				(arc
					(start 441.779406 -311.86247)
					(mid 441.764527 -311.826549)
					(end 441.728606 -311.81167)
				)
				(arc
					(start 440.329066 -311.81167)
					(mid 440.293145 -311.826549)
					(end 440.278266 -311.86247)
				)
			)
		)
	)
	(zone
		(layers "In1.Cu" "In2.Cu")
		(hatch none 0.5)
		(connect_pads
			(clearance 0)
		)
		(min_thickness 0.25)
		(keepout
			(tracks not_allowed)
			(vias allowed)
			(pads allowed)
			(copperpour not_allowed)
			(footprints allowed)
		)
		(placement
			(enabled no)
			(sheetname "")
		)
		(fill yes
			(thermal_gap 0.5)
			(thermal_bridge_width 0.5)
			(island_removal_mode 0)
		)
		(polygon
			(pts
				(arc
					(start 173.15053 -252.771402)
					(mid 173.165409 -252.807323)
					(end 173.20133 -252.822202)
				)
				(arc
					(start 174.60087 -252.822202)
					(mid 174.636791 -252.807323)
					(end 174.65167 -252.771402)
				)
				(arc
					(start 174.65167 -252.362462)
					(mid 174.636791 -252.326541)
					(end 174.60087 -252.311662)
				)
				(arc
					(start 173.20133 -252.311662)
					(mid 173.165409 -252.326541)
					(end 173.15053 -252.362462)
				)
			)
		)
	)
	(zone
		(layers "In1.Cu" "In2.Cu")
		(hatch none 0.5)
		(connect_pads
			(clearance 0)
		)
		(min_thickness 0.25)
		(keepout
			(tracks not_allowed)
			(vias allowed)
			(pads allowed)
			(copperpour not_allowed)
			(footprints allowed)
		)
		(placement
			(enabled no)
			(sheetname "")
		)
		(fill yes
			(thermal_gap 0.5)
			(thermal_bridge_width 0.5)
			(island_removal_mode 0)
		)
		(polygon
			(pts
				(arc
					(start 37.56533 -204.32141)
					(mid 37.580209 -204.357331)
					(end 37.61613 -204.37221)
				)
				(arc
					(start 39.01567 -204.37221)
					(mid 39.051591 -204.357331)
					(end 39.06647 -204.32141)
				)
				(arc
					(start 39.06647 -203.91247)
					(mid 39.051591 -203.876549)
					(end 39.01567 -203.86167)
				)
				(arc
					(start 37.61613 -203.86167)
					(mid 37.580209 -203.876549)
					(end 37.56533 -203.91247)
				)
			)
		)
	)
	(zone
		(layers "In1.Cu" "In2.Cu")
		(hatch none 0.5)
		(connect_pads
			(clearance 0)
		)
		(min_thickness 0.25)
		(keepout
			(tracks not_allowed)
			(vias allowed)
			(pads allowed)
			(copperpour not_allowed)
			(footprints allowed)
		)
		(placement
			(enabled no)
			(sheetname "")
		)
		(fill yes
			(thermal_gap 0.5)
			(thermal_bridge_width 0.5)
			(island_removal_mode 0)
		)
		(polygon
			(pts
				(arc
					(start 37.56533 -237.471458)
					(mid 37.580209 -237.507379)
					(end 37.61613 -237.522258)
				)
				(arc
					(start 39.01567 -237.522258)
					(mid 39.051591 -237.507379)
					(end 39.06647 -237.471458)
				)
				(arc
					(start 39.06647 -237.062518)
					(mid 39.051591 -237.026597)
					(end 39.01567 -237.011718)
				)
				(arc
					(start 37.61613 -237.011718)
					(mid 37.580209 -237.026597)
					(end 37.56533 -237.062518)
				)
			)
		)
	)
	(zone
		(layers "In1.Cu" "In2.Cu")
		(hatch none 0.5)
		(connect_pads
			(clearance 0)
		)
		(min_thickness 0.25)
		(keepout
			(tracks not_allowed)
			(vias allowed)
			(pads allowed)
			(copperpour not_allowed)
			(footprints allowed)
		)
		(placement
			(enabled no)
			(sheetname "")
		)
		(fill yes
			(thermal_gap 0.5)
			(thermal_bridge_width 0.5)
			(island_removal_mode 0)
		)
		(polygon
			(pts
				(arc
					(start 451.265798 -282.521406)
					(mid 451.280677 -282.557327)
					(end 451.316598 -282.572206)
				)
				(arc
					(start 452.716138 -282.572206)
					(mid 452.752059 -282.557327)
					(end 452.766938 -282.521406)
				)
				(arc
					(start 452.766938 -282.112466)
					(mid 452.752059 -282.076545)
					(end 452.716138 -282.061666)
				)
				(arc
					(start 451.316598 -282.061666)
					(mid 451.280677 -282.076545)
					(end 451.265798 -282.112466)
				)
			)
		)
	)
	(zone
		(layers "In1.Cu" "In2.Cu")
		(hatch none 0.5)
		(connect_pads
			(clearance 0)
		)
		(min_thickness 0.25)
		(keepout
			(tracks not_allowed)
			(vias allowed)
			(pads allowed)
			(copperpour not_allowed)
			(footprints allowed)
		)
		(placement
			(enabled no)
			(sheetname "")
		)
		(fill yes
			(thermal_gap 0.5)
			(thermal_bridge_width 0.5)
			(island_removal_mode 0)
		)
		(polygon
			(pts
				(arc
					(start 262.873998 -313.121294)
					(mid 262.888877 -313.157215)
					(end 262.924798 -313.172094)
				)
				(arc
					(start 264.324338 -313.172094)
					(mid 264.360259 -313.157215)
					(end 264.375138 -313.121294)
				)
				(arc
					(start 264.375138 -312.712354)
					(mid 264.360259 -312.676433)
					(end 264.324338 -312.661554)
				)
				(arc
					(start 262.924798 -312.661554)
					(mid 262.888877 -312.676433)
					(end 262.873998 -312.712354)
				)
			)
		)
	)
	(zone
		(layers "In1.Cu" "In2.Cu")
		(hatch none 0.5)
		(connect_pads
			(clearance 0)
		)
		(min_thickness 0.25)
		(keepout
			(tracks not_allowed)
			(vias allowed)
			(pads allowed)
			(copperpour not_allowed)
			(footprints allowed)
		)
		(placement
			(enabled no)
			(sheetname "")
		)
		(fill yes
			(thermal_gap 0.5)
			(thermal_bridge_width 0.5)
			(island_removal_mode 0)
		)
		(polygon
			(pts
				(arc
					(start 195.78193 -252.771402)
					(mid 195.796809 -252.807323)
					(end 195.83273 -252.822202)
				)
				(arc
					(start 197.23227 -252.822202)
					(mid 197.268191 -252.807323)
					(end 197.28307 -252.771402)
				)
				(arc
					(start 197.28307 -252.362462)
					(mid 197.268191 -252.326541)
					(end 197.23227 -252.311662)
				)
				(arc
					(start 195.83273 -252.311662)
					(mid 195.796809 -252.326541)
					(end 195.78193 -252.362462)
				)
			)
		)
	)
	(zone
		(layers "In1.Cu" "In2.Cu")
		(hatch none 0.5)
		(connect_pads
			(clearance 0)
		)
		(min_thickness 0.25)
		(keepout
			(tracks not_allowed)
			(vias allowed)
			(pads allowed)
			(copperpour not_allowed)
			(footprints allowed)
		)
		(placement
			(enabled no)
			(sheetname "")
		)
		(fill yes
			(thermal_gap 0.5)
			(thermal_bridge_width 0.5)
			(island_removal_mode 0)
		)
		(polygon
			(pts
				(arc
					(start 447.822066 -289.321494)
					(mid 447.836945 -289.357415)
					(end 447.872866 -289.372294)
				)
				(arc
					(start 449.272406 -289.372294)
					(mid 449.308327 -289.357415)
					(end 449.323206 -289.321494)
				)
				(arc
					(start 449.323206 -288.912554)
					(mid 449.308327 -288.876633)
					(end 449.272406 -288.861754)
				)
				(arc
					(start 447.872866 -288.861754)
					(mid 447.836945 -288.876633)
					(end 447.822066 -288.912554)
				)
			)
		)
	)
	(zone
		(layers "In1.Cu" "In2.Cu")
		(hatch none 0.5)
		(connect_pads
			(clearance 0)
		)
		(min_thickness 0.25)
		(keepout
			(tracks not_allowed)
			(vias allowed)
			(pads allowed)
			(copperpour not_allowed)
			(footprints allowed)
		)
		(placement
			(enabled no)
			(sheetname "")
		)
		(fill yes
			(thermal_gap 0.5)
			(thermal_bridge_width 0.5)
			(island_removal_mode 0)
		)
		(polygon
			(pts
				(arc
					(start 37.56533 -200.071482)
					(mid 37.580209 -200.107403)
					(end 37.61613 -200.122282)
				)
				(arc
					(start 39.01567 -200.122282)
					(mid 39.051591 -200.107403)
					(end 39.06647 -200.071482)
				)
				(arc
					(start 39.06647 -199.662542)
					(mid 39.051591 -199.626621)
					(end 39.01567 -199.611742)
				)
				(arc
					(start 37.61613 -199.611742)
					(mid 37.580209 -199.626621)
					(end 37.56533 -199.662542)
				)
			)
		)
	)
	(zone
		(layers "In1.Cu" "In2.Cu")
		(hatch none 0.5)
		(connect_pads
			(clearance 0)
		)
		(min_thickness 0.25)
		(keepout
			(tracks not_allowed)
			(vias allowed)
			(pads allowed)
			(copperpour not_allowed)
			(footprints allowed)
		)
		(placement
			(enabled no)
			(sheetname "")
		)
		(fill yes
			(thermal_gap 0.5)
			(thermal_bridge_width 0.5)
			(island_removal_mode 0)
		)
		(polygon
			(pts
				(arc
					(start 282.061666 -231.521508)
					(mid 282.076545 -231.557429)
					(end 282.112466 -231.572308)
				)
				(arc
					(start 283.512006 -231.572308)
					(mid 283.547927 -231.557429)
					(end 283.562806 -231.521508)
				)
				(arc
					(start 283.562806 -231.112568)
					(mid 283.547927 -231.076647)
					(end 283.512006 -231.061768)
				)
				(arc
					(start 282.112466 -231.061768)
					(mid 282.076545 -231.076647)
					(end 282.061666 -231.112568)
				)
			)
		)
	)
	(zone
		(layers "In1.Cu" "In2.Cu")
		(hatch none 0.5)
		(connect_pads
			(clearance 0)
		)
		(min_thickness 0.25)
		(keepout
			(tracks not_allowed)
			(vias allowed)
			(pads allowed)
			(copperpour not_allowed)
			(footprints allowed)
		)
		(placement
			(enabled no)
			(sheetname "")
		)
		(fill yes
			(thermal_gap 0.5)
			(thermal_bridge_width 0.5)
			(island_removal_mode 0)
		)
		(polygon
			(pts
				(arc
					(start 451.265798 -219.621354)
					(mid 451.280677 -219.657275)
					(end 451.316598 -219.672154)
				)
				(arc
					(start 452.716138 -219.672154)
					(mid 452.752059 -219.657275)
					(end 452.766938 -219.621354)
				)
				(arc
					(start 452.766938 -219.212414)
					(mid 452.752059 -219.176493)
					(end 452.716138 -219.161614)
				)
				(arc
					(start 451.316598 -219.161614)
					(mid 451.280677 -219.176493)
					(end 451.265798 -219.212414)
				)
			)
		)
	)
	(zone
		(layers "In1.Cu" "In2.Cu")
		(hatch none 0.5)
		(connect_pads
			(clearance 0)
		)
		(min_thickness 0.25)
		(keepout
			(tracks not_allowed)
			(vias allowed)
			(pads allowed)
			(copperpour not_allowed)
			(footprints allowed)
		)
		(placement
			(enabled no)
			(sheetname "")
		)
		(fill yes
			(thermal_gap 0.5)
			(thermal_bridge_width 0.5)
			(island_removal_mode 0)
		)
		(polygon
			(pts
				(arc
					(start 417.646866 -276.571456)
					(mid 417.661745 -276.607377)
					(end 417.697666 -276.622256)
				)
				(arc
					(start 419.097206 -276.622256)
					(mid 419.133127 -276.607377)
					(end 419.148006 -276.571456)
				)
				(arc
					(start 419.148006 -276.162516)
					(mid 419.133127 -276.126595)
					(end 419.097206 -276.111716)
				)
				(arc
					(start 417.697666 -276.111716)
					(mid 417.661745 -276.126595)
					(end 417.646866 -276.162516)
				)
			)
		)
	)
	(zone
		(layers "In1.Cu" "In2.Cu")
		(hatch none 0.5)
		(connect_pads
			(clearance 0)
		)
		(min_thickness 0.25)
		(keepout
			(tracks not_allowed)
			(vias allowed)
			(pads allowed)
			(copperpour not_allowed)
			(footprints allowed)
		)
		(placement
			(enabled no)
			(sheetname "")
		)
		(fill yes
			(thermal_gap 0.5)
			(thermal_bridge_width 0.5)
			(island_removal_mode 0)
		)
		(polygon
			(pts
				(arc
					(start 192.338198 -205.171548)
					(mid 192.353077 -205.207469)
					(end 192.388998 -205.222348)
				)
				(arc
					(start 193.788538 -205.222348)
					(mid 193.824459 -205.207469)
					(end 193.839338 -205.171548)
				)
				(arc
					(start 193.839338 -204.762608)
					(mid 193.824459 -204.726687)
					(end 193.788538 -204.711808)
				)
				(arc
					(start 192.388998 -204.711808)
					(mid 192.353077 -204.726687)
					(end 192.338198 -204.762608)
				)
			)
		)
	)
	(zone
		(layers "In1.Cu" "In2.Cu")
		(hatch none 0.5)
		(connect_pads
			(clearance 0)
		)
		(min_thickness 0.25)
		(keepout
			(tracks not_allowed)
			(vias allowed)
			(pads allowed)
			(copperpour not_allowed)
			(footprints allowed)
		)
		(placement
			(enabled no)
			(sheetname "")
		)
		(fill yes
			(thermal_gap 0.5)
			(thermal_bridge_width 0.5)
			(island_removal_mode 0)
		)
		(polygon
			(pts
				(arc
					(start 60.19673 -209.421476)
					(mid 60.211609 -209.457397)
					(end 60.24753 -209.472276)
				)
				(arc
					(start 61.64707 -209.472276)
					(mid 61.682991 -209.457397)
					(end 61.69787 -209.421476)
				)
				(arc
					(start 61.69787 -209.012536)
					(mid 61.682991 -208.976615)
					(end 61.64707 -208.961736)
				)
				(arc
					(start 60.24753 -208.961736)
					(mid 60.211609 -208.976615)
					(end 60.19673 -209.012536)
				)
			)
		)
	)
	(zone
		(layers "In1.Cu" "In2.Cu")
		(hatch none 0.5)
		(connect_pads
			(clearance 0)
		)
		(min_thickness 0.25)
		(keepout
			(tracks not_allowed)
			(vias allowed)
			(pads allowed)
			(copperpour not_allowed)
			(footprints allowed)
		)
		(placement
			(enabled no)
			(sheetname "")
		)
		(fill yes
			(thermal_gap 0.5)
			(thermal_bridge_width 0.5)
			(island_removal_mode 0)
		)
		(polygon
			(pts
				(arc
					(start 158.06293 -244.271292)
					(mid 158.077809 -244.307213)
					(end 158.11373 -244.322092)
				)
				(arc
					(start 159.51327 -244.322092)
					(mid 159.549191 -244.307213)
					(end 159.56407 -244.271292)
				)
				(arc
					(start 159.56407 -243.862352)
					(mid 159.549191 -243.826431)
					(end 159.51327 -243.811552)
				)
				(arc
					(start 158.11373 -243.811552)
					(mid 158.077809 -243.826431)
					(end 158.06293 -243.862352)
				)
			)
		)
	)
	(zone
		(layers "In1.Cu" "In2.Cu")
		(hatch none 0.5)
		(connect_pads
			(clearance 0)
		)
		(min_thickness 0.25)
		(keepout
			(tracks not_allowed)
			(vias allowed)
			(pads allowed)
			(copperpour not_allowed)
			(footprints allowed)
		)
		(placement
			(enabled no)
			(sheetname "")
		)
		(fill yes
			(thermal_gap 0.5)
			(thermal_bridge_width 0.5)
			(island_removal_mode 0)
		)
		(polygon
			(pts
				(arc
					(start 60.19673 -230.67137)
					(mid 60.211609 -230.707291)
					(end 60.24753 -230.72217)
				)
				(arc
					(start 61.64707 -230.72217)
					(mid 61.682991 -230.707291)
					(end 61.69787 -230.67137)
				)
				(arc
					(start 61.69787 -230.26243)
					(mid 61.682991 -230.226509)
					(end 61.64707 -230.21163)
				)
				(arc
					(start 60.24753 -230.21163)
					(mid 60.211609 -230.226509)
					(end 60.19673 -230.26243)
				)
			)
		)
	)
	(zone
		(layers "In1.Cu" "In2.Cu")
		(hatch none 0.5)
		(connect_pads
			(clearance 0)
		)
		(min_thickness 0.25)
		(keepout
			(tracks not_allowed)
			(vias allowed)
			(pads allowed)
			(copperpour not_allowed)
			(footprints allowed)
		)
		(placement
			(enabled no)
			(sheetname "")
		)
		(fill yes
			(thermal_gap 0.5)
			(thermal_bridge_width 0.5)
			(island_removal_mode 0)
		)
		(polygon
			(pts
				(arc
					(start 192.338198 -214.521542)
					(mid 192.353077 -214.557463)
					(end 192.388998 -214.572342)
				)
				(arc
					(start 193.788538 -214.572342)
					(mid 193.824459 -214.557463)
					(end 193.839338 -214.521542)
				)
				(arc
					(start 193.839338 -214.112602)
					(mid 193.824459 -214.076681)
					(end 193.788538 -214.061802)
				)
				(arc
					(start 192.388998 -214.061802)
					(mid 192.353077 -214.076681)
					(end 192.338198 -214.112602)
				)
			)
		)
	)
	(zone
		(layers "In1.Cu" "In2.Cu")
		(hatch none 0.5)
		(connect_pads
			(clearance 0)
		)
		(min_thickness 0.25)
		(keepout
			(tracks not_allowed)
			(vias allowed)
			(pads allowed)
			(copperpour not_allowed)
			(footprints allowed)
		)
		(placement
			(enabled no)
			(sheetname "")
		)
		(fill yes
			(thermal_gap 0.5)
			(thermal_bridge_width 0.5)
			(island_removal_mode 0)
		)
		(polygon
			(pts
				(arc
					(start 41.665398 -195.821554)
					(mid 41.680277 -195.857475)
					(end 41.716198 -195.872354)
				)
				(arc
					(start 43.115738 -195.872354)
					(mid 43.151659 -195.857475)
					(end 43.166538 -195.821554)
				)
				(arc
					(start 43.166538 -195.412614)
					(mid 43.151659 -195.376693)
					(end 43.115738 -195.361814)
				)
				(arc
					(start 41.716198 -195.361814)
					(mid 41.680277 -195.376693)
					(end 41.665398 -195.412614)
				)
			)
		)
	)
	(zone
		(layers "In1.Cu" "In2.Cu")
		(hatch none 0.5)
		(connect_pads
			(clearance 0)
		)
		(min_thickness 0.25)
		(keepout
			(tracks not_allowed)
			(vias allowed)
			(pads allowed)
			(copperpour not_allowed)
			(footprints allowed)
		)
		(placement
			(enabled no)
			(sheetname "")
		)
		(fill yes
			(thermal_gap 0.5)
			(thermal_bridge_width 0.5)
			(island_removal_mode 0)
		)
		(polygon
			(pts
				(arc
					(start 285.505398 -273.171412)
					(mid 285.520277 -273.207333)
					(end 285.556198 -273.222212)
				)
				(arc
					(start 286.955738 -273.222212)
					(mid 286.991659 -273.207333)
					(end 287.006538 -273.171412)
				)
				(arc
					(start 287.006538 -272.762472)
					(mid 286.991659 -272.726551)
					(end 286.955738 -272.711672)
				)
				(arc
					(start 285.556198 -272.711672)
					(mid 285.520277 -272.726551)
					(end 285.505398 -272.762472)
				)
			)
		)
	)
	(zone
		(layers "In1.Cu" "In2.Cu")
		(hatch none 0.5)
		(connect_pads
			(clearance 0)
		)
		(min_thickness 0.25)
		(keepout
			(tracks not_allowed)
			(vias allowed)
			(pads allowed)
			(copperpour not_allowed)
			(footprints allowed)
		)
		(placement
			(enabled no)
			(sheetname "")
		)
		(fill yes
			(thermal_gap 0.5)
			(thermal_bridge_width 0.5)
			(island_removal_mode 0)
		)
		(polygon
			(pts
				(arc
					(start 207.425798 -248.521474)
					(mid 207.440677 -248.557395)
					(end 207.476598 -248.572274)
				)
				(arc
					(start 208.876138 -248.572274)
					(mid 208.912059 -248.557395)
					(end 208.926938 -248.521474)
				)
				(arc
					(start 208.926938 -248.112534)
					(mid 208.912059 -248.076613)
					(end 208.876138 -248.061734)
				)
				(arc
					(start 207.476598 -248.061734)
					(mid 207.440677 -248.076613)
					(end 207.425798 -248.112534)
				)
			)
		)
	)
	(zone
		(layers "In1.Cu" "In2.Cu")
		(hatch none 0.5)
		(connect_pads
			(clearance 0)
		)
		(min_thickness 0.25)
		(keepout
			(tracks not_allowed)
			(vias allowed)
			(pads allowed)
			(copperpour not_allowed)
			(footprints allowed)
		)
		(placement
			(enabled no)
			(sheetname "")
		)
		(fill yes
			(thermal_gap 0.5)
			(thermal_bridge_width 0.5)
			(island_removal_mode 0)
		)
		(polygon
			(pts
				(arc
					(start 447.822066 -287.621472)
					(mid 447.836945 -287.657393)
					(end 447.872866 -287.672272)
				)
				(arc
					(start 449.272406 -287.672272)
					(mid 449.308327 -287.657393)
					(end 449.323206 -287.621472)
				)
				(arc
					(start 449.323206 -287.212532)
					(mid 449.308327 -287.176611)
					(end 449.272406 -287.161732)
				)
				(arc
					(start 447.872866 -287.161732)
					(mid 447.836945 -287.176611)
					(end 447.822066 -287.212532)
				)
			)
		)
	)
	(zone
		(layers "In1.Cu" "In2.Cu")
		(hatch none 0.5)
		(connect_pads
			(clearance 0)
		)
		(min_thickness 0.25)
		(keepout
			(tracks not_allowed)
			(vias allowed)
			(pads allowed)
			(copperpour not_allowed)
			(footprints allowed)
		)
		(placement
			(enabled no)
			(sheetname "")
		)
		(fill yes
			(thermal_gap 0.5)
			(thermal_bridge_width 0.5)
			(island_removal_mode 0)
		)
		(polygon
			(pts
				(arc
					(start 421.090598 -307.171344)
					(mid 421.105477 -307.207265)
					(end 421.141398 -307.222144)
				)
				(arc
					(start 422.540938 -307.222144)
					(mid 422.576859 -307.207265)
					(end 422.591738 -307.171344)
				)
				(arc
					(start 422.591738 -306.762404)
					(mid 422.576859 -306.726483)
					(end 422.540938 -306.711604)
				)
				(arc
					(start 421.141398 -306.711604)
					(mid 421.105477 -306.726483)
					(end 421.090598 -306.762404)
				)
			)
		)
	)
	(zone
		(layers "In1.Cu" "In2.Cu")
		(hatch none 0.5)
		(connect_pads
			(clearance 0)
		)
		(min_thickness 0.25)
		(keepout
			(tracks not_allowed)
			(vias allowed)
			(pads allowed)
			(copperpour not_allowed)
			(footprints allowed)
		)
		(placement
			(enabled no)
			(sheetname "")
		)
		(fill yes
			(thermal_gap 0.5)
			(thermal_bridge_width 0.5)
			(island_removal_mode 0)
		)
		(polygon
			(pts
				(arc
					(start 52.65293 -302.921416)
					(mid 52.667809 -302.957337)
					(end 52.70373 -302.972216)
				)
				(arc
					(start 54.10327 -302.972216)
					(mid 54.139191 -302.957337)
					(end 54.15407 -302.921416)
				)
				(arc
					(start 54.15407 -302.512476)
					(mid 54.139191 -302.476555)
					(end 54.10327 -302.461676)
				)
				(arc
					(start 52.70373 -302.461676)
					(mid 52.667809 -302.476555)
					(end 52.65293 -302.512476)
				)
			)
		)
	)
	(zone
		(layers "In1.Cu" "In2.Cu")
		(hatch none 0.5)
		(connect_pads
			(clearance 0)
		)
		(min_thickness 0.25)
		(keepout
			(tracks not_allowed)
			(vias allowed)
			(pads allowed)
			(copperpour not_allowed)
			(footprints allowed)
		)
		(placement
			(enabled no)
			(sheetname "")
		)
		(fill yes
			(thermal_gap 0.5)
			(thermal_bridge_width 0.5)
			(island_removal_mode 0)
		)
		(polygon
			(pts
				(arc
					(start 436.178198 -275.721318)
					(mid 436.193077 -275.757239)
					(end 436.228998 -275.772118)
				)
				(arc
					(start 437.628538 -275.772118)
					(mid 437.664459 -275.757239)
					(end 437.679338 -275.721318)
				)
				(arc
					(start 437.679338 -275.312378)
					(mid 437.664459 -275.276457)
					(end 437.628538 -275.261578)
				)
				(arc
					(start 436.228998 -275.261578)
					(mid 436.193077 -275.276457)
					(end 436.178198 -275.312378)
				)
			)
		)
	)
	(zone
		(layers "In1.Cu" "In2.Cu")
		(hatch none 0.5)
		(connect_pads
			(clearance 0)
		)
		(min_thickness 0.25)
		(keepout
			(tracks not_allowed)
			(vias allowed)
			(pads allowed)
			(copperpour not_allowed)
			(footprints allowed)
		)
		(placement
			(enabled no)
			(sheetname "")
		)
		(fill yes
			(thermal_gap 0.5)
			(thermal_bridge_width 0.5)
			(island_removal_mode 0)
		)
		(polygon
			(pts
				(arc
					(start 49.209198 -312.27141)
					(mid 49.224077 -312.307331)
					(end 49.259998 -312.32221)
				)
				(arc
					(start 50.659538 -312.32221)
					(mid 50.695459 -312.307331)
					(end 50.710338 -312.27141)
				)
				(arc
					(start 50.710338 -311.86247)
					(mid 50.695459 -311.826549)
					(end 50.659538 -311.81167)
				)
				(arc
					(start 49.259998 -311.81167)
					(mid 49.224077 -311.826549)
					(end 49.209198 -311.86247)
				)
			)
		)
	)
	(zone
		(layers "In1.Cu" "In2.Cu")
		(hatch none 0.5)
		(connect_pads
			(clearance 0)
		)
		(min_thickness 0.25)
		(keepout
			(tracks not_allowed)
			(vias allowed)
			(pads allowed)
			(copperpour not_allowed)
			(footprints allowed)
		)
		(placement
			(enabled no)
			(sheetname "")
		)
		(fill yes
			(thermal_gap 0.5)
			(thermal_bridge_width 0.5)
			(island_removal_mode 0)
		)
		(polygon
			(pts
				(arc
					(start 308.136798 -245.971314)
					(mid 308.151677 -246.007235)
					(end 308.187598 -246.022114)
				)
				(arc
					(start 309.587138 -246.022114)
					(mid 309.623059 -246.007235)
					(end 309.637938 -245.971314)
				)
				(arc
					(start 309.637938 -245.562374)
					(mid 309.623059 -245.526453)
					(end 309.587138 -245.511574)
				)
				(arc
					(start 308.187598 -245.511574)
					(mid 308.151677 -245.526453)
					(end 308.136798 -245.562374)
				)
			)
		)
	)
	(zone
		(layers "In1.Cu" "In2.Cu")
		(hatch none 0.5)
		(connect_pads
			(clearance 0)
		)
		(min_thickness 0.25)
		(keepout
			(tracks not_allowed)
			(vias allowed)
			(pads allowed)
			(copperpour not_allowed)
			(footprints allowed)
		)
		(placement
			(enabled no)
			(sheetname "")
		)
		(fill yes
			(thermal_gap 0.5)
			(thermal_bridge_width 0.5)
			(island_removal_mode 0)
		)
		(polygon
			(pts
				(arc
					(start 270.417798 -247.671336)
					(mid 270.432677 -247.707257)
					(end 270.468598 -247.722136)
				)
				(arc
					(start 271.868138 -247.722136)
					(mid 271.904059 -247.707257)
					(end 271.918938 -247.671336)
				)
				(arc
					(start 271.918938 -247.262396)
					(mid 271.904059 -247.226475)
					(end 271.868138 -247.211596)
				)
				(arc
					(start 270.468598 -247.211596)
					(mid 270.432677 -247.226475)
					(end 270.417798 -247.262396)
				)
			)
		)
	)
	(zone
		(layers "In1.Cu" "In2.Cu")
		(hatch none 0.5)
		(connect_pads
			(clearance 0)
		)
		(min_thickness 0.25)
		(keepout
			(tracks not_allowed)
			(vias allowed)
			(pads allowed)
			(copperpour not_allowed)
			(footprints allowed)
		)
		(placement
			(enabled no)
			(sheetname "")
		)
		(fill yes
			(thermal_gap 0.5)
			(thermal_bridge_width 0.5)
			(island_removal_mode 0)
		)
		(polygon
			(pts
				(arc
					(start 300.592998 -228.971348)
					(mid 300.607877 -229.007269)
					(end 300.643798 -229.022148)
				)
				(arc
					(start 302.043338 -229.022148)
					(mid 302.079259 -229.007269)
					(end 302.094138 -228.971348)
				)
				(arc
					(start 302.094138 -228.562408)
					(mid 302.079259 -228.526487)
					(end 302.043338 -228.511608)
				)
				(arc
					(start 300.643798 -228.511608)
					(mid 300.607877 -228.526487)
					(end 300.592998 -228.562408)
				)
			)
		)
	)
	(zone
		(layers "In1.Cu" "In2.Cu")
		(hatch none 0.5)
		(connect_pads
			(clearance 0)
		)
		(min_thickness 0.25)
		(keepout
			(tracks not_allowed)
			(vias allowed)
			(pads allowed)
			(copperpour not_allowed)
			(footprints allowed)
		)
		(placement
			(enabled no)
			(sheetname "")
		)
		(fill yes
			(thermal_gap 0.5)
			(thermal_bridge_width 0.5)
			(island_removal_mode 0)
		)
		(polygon
			(pts
				(arc
					(start 64.296798 -262.121396)
					(mid 64.311677 -262.157317)
					(end 64.347598 -262.172196)
				)
				(arc
					(start 65.747138 -262.172196)
					(mid 65.783059 -262.157317)
					(end 65.797938 -262.121396)
				)
				(arc
					(start 65.797938 -261.712456)
					(mid 65.783059 -261.676535)
					(end 65.747138 -261.661656)
				)
				(arc
					(start 64.347598 -261.661656)
					(mid 64.311677 -261.676535)
					(end 64.296798 -261.712456)
				)
			)
		)
	)
	(zone
		(layers "In1.Cu" "In2.Cu")
		(hatch none 0.5)
		(connect_pads
			(clearance 0)
		)
		(min_thickness 0.25)
		(keepout
			(tracks not_allowed)
			(vias allowed)
			(pads allowed)
			(copperpour not_allowed)
			(footprints allowed)
		)
		(placement
			(enabled no)
			(sheetname "")
		)
		(fill yes
			(thermal_gap 0.5)
			(thermal_bridge_width 0.5)
			(island_removal_mode 0)
		)
		(polygon
			(pts
				(arc
					(start 41.665398 -302.071532)
					(mid 41.680277 -302.107453)
					(end 41.716198 -302.122332)
				)
				(arc
					(start 43.115738 -302.122332)
					(mid 43.151659 -302.107453)
					(end 43.166538 -302.071532)
				)
				(arc
					(start 43.166538 -301.662592)
					(mid 43.151659 -301.626671)
					(end 43.115738 -301.611792)
				)
				(arc
					(start 41.716198 -301.611792)
					(mid 41.680277 -301.626671)
					(end 41.665398 -301.662592)
				)
			)
		)
	)
	(zone
		(layers "In1.Cu" "In2.Cu")
		(hatch none 0.5)
		(connect_pads
			(clearance 0)
		)
		(min_thickness 0.25)
		(keepout
			(tracks not_allowed)
			(vias allowed)
			(pads allowed)
			(copperpour not_allowed)
			(footprints allowed)
		)
		(placement
			(enabled no)
			(sheetname "")
		)
		(fill yes
			(thermal_gap 0.5)
			(thermal_bridge_width 0.5)
			(island_removal_mode 0)
		)
		(polygon
			(pts
				(arc
					(start 421.090598 -237.471458)
					(mid 421.105477 -237.507379)
					(end 421.141398 -237.522258)
				)
				(arc
					(start 422.540938 -237.522258)
					(mid 422.576859 -237.507379)
					(end 422.591738 -237.471458)
				)
				(arc
					(start 422.591738 -237.062518)
					(mid 422.576859 -237.026597)
					(end 422.540938 -237.011718)
				)
				(arc
					(start 421.141398 -237.011718)
					(mid 421.105477 -237.026597)
					(end 421.090598 -237.062518)
				)
			)
		)
	)
	(zone
		(layers "In1.Cu" "In2.Cu")
		(hatch none 0.5)
		(connect_pads
			(clearance 0)
		)
		(min_thickness 0.25)
		(keepout
			(tracks not_allowed)
			(vias allowed)
			(pads allowed)
			(copperpour not_allowed)
			(footprints allowed)
		)
		(placement
			(enabled no)
			(sheetname "")
		)
		(fill yes
			(thermal_gap 0.5)
			(thermal_bridge_width 0.5)
			(island_removal_mode 0)
		)
		(polygon
			(pts
				(arc
					(start 421.090598 -269.771368)
					(mid 421.105477 -269.807289)
					(end 421.141398 -269.822168)
				)
				(arc
					(start 422.540938 -269.822168)
					(mid 422.576859 -269.807289)
					(end 422.591738 -269.771368)
				)
				(arc
					(start 422.591738 -269.362428)
					(mid 422.576859 -269.326507)
					(end 422.540938 -269.311628)
				)
				(arc
					(start 421.141398 -269.311628)
					(mid 421.105477 -269.326507)
					(end 421.090598 -269.362428)
				)
			)
		)
	)
	(zone
		(layers "In1.Cu" "In2.Cu")
		(hatch none 0.5)
		(connect_pads
			(clearance 0)
		)
		(min_thickness 0.25)
		(keepout
			(tracks not_allowed)
			(vias allowed)
			(pads allowed)
			(copperpour not_allowed)
			(footprints allowed)
		)
		(placement
			(enabled no)
			(sheetname "")
		)
		(fill yes
			(thermal_gap 0.5)
			(thermal_bridge_width 0.5)
			(island_removal_mode 0)
		)
		(polygon
			(pts
				(arc
					(start 56.752998 -304.621438)
					(mid 56.767877 -304.657359)
					(end 56.803798 -304.672238)
				)
				(arc
					(start 58.203338 -304.672238)
					(mid 58.239259 -304.657359)
					(end 58.254138 -304.621438)
				)
				(arc
					(start 58.254138 -304.212498)
					(mid 58.239259 -304.176577)
					(end 58.203338 -304.161698)
				)
				(arc
					(start 56.803798 -304.161698)
					(mid 56.767877 -304.176577)
					(end 56.752998 -304.212498)
				)
			)
		)
	)
	(zone
		(layers "In1.Cu" "In2.Cu")
		(hatch none 0.5)
		(connect_pads
			(clearance 0)
		)
		(min_thickness 0.25)
		(keepout
			(tracks not_allowed)
			(vias allowed)
			(pads allowed)
			(copperpour not_allowed)
			(footprints allowed)
		)
		(placement
			(enabled no)
			(sheetname "")
		)
		(fill yes
			(thermal_gap 0.5)
			(thermal_bridge_width 0.5)
			(island_removal_mode 0)
		)
		(polygon
			(pts
				(arc
					(start 406.002998 -313.121294)
					(mid 406.017877 -313.157215)
					(end 406.053798 -313.172094)
				)
				(arc
					(start 407.453338 -313.172094)
					(mid 407.489259 -313.157215)
					(end 407.504138 -313.121294)
				)
				(arc
					(start 407.504138 -312.712354)
					(mid 407.489259 -312.676433)
					(end 407.453338 -312.661554)
				)
				(arc
					(start 406.053798 -312.661554)
					(mid 406.017877 -312.676433)
					(end 406.002998 -312.712354)
				)
			)
		)
	)
	(zone
		(layers "In1.Cu" "In2.Cu")
		(hatch none 0.5)
		(connect_pads
			(clearance 0)
		)
		(min_thickness 0.25)
		(keepout
			(tracks not_allowed)
			(vias allowed)
			(pads allowed)
			(copperpour not_allowed)
			(footprints allowed)
		)
		(placement
			(enabled no)
			(sheetname "")
		)
		(fill yes
			(thermal_gap 0.5)
			(thermal_bridge_width 0.5)
			(island_removal_mode 0)
		)
		(polygon
			(pts
				(arc
					(start 188.23813 -202.621388)
					(mid 188.253009 -202.657309)
					(end 188.28893 -202.672188)
				)
				(arc
					(start 189.68847 -202.672188)
					(mid 189.724391 -202.657309)
					(end 189.73927 -202.621388)
				)
				(arc
					(start 189.73927 -202.212448)
					(mid 189.724391 -202.176527)
					(end 189.68847 -202.161648)
				)
				(arc
					(start 188.28893 -202.161648)
					(mid 188.253009 -202.176527)
					(end 188.23813 -202.212448)
				)
			)
		)
	)
	(zone
		(layers "In1.Cu" "In2.Cu")
		(hatch none 0.5)
		(connect_pads
			(clearance 0)
		)
		(min_thickness 0.25)
		(keepout
			(tracks not_allowed)
			(vias allowed)
			(pads allowed)
			(copperpour not_allowed)
			(footprints allowed)
		)
		(placement
			(enabled no)
			(sheetname "")
		)
		(fill yes
			(thermal_gap 0.5)
			(thermal_bridge_width 0.5)
			(island_removal_mode 0)
		)
		(polygon
			(pts
				(arc
					(start 188.23813 -286.771334)
					(mid 188.253009 -286.807255)
					(end 188.28893 -286.822134)
				)
				(arc
					(start 189.68847 -286.822134)
					(mid 189.724391 -286.807255)
					(end 189.73927 -286.771334)
				)
				(arc
					(start 189.73927 -286.362394)
					(mid 189.724391 -286.326473)
					(end 189.68847 -286.311594)
				)
				(arc
					(start 188.28893 -286.311594)
					(mid 188.253009 -286.326473)
					(end 188.23813 -286.362394)
				)
			)
		)
	)
	(zone
		(layers "In1.Cu" "In2.Cu")
		(hatch none 0.5)
		(connect_pads
			(clearance 0)
		)
		(min_thickness 0.25)
		(keepout
			(tracks not_allowed)
			(vias allowed)
			(pads allowed)
			(copperpour not_allowed)
			(footprints allowed)
		)
		(placement
			(enabled no)
			(sheetname "")
		)
		(fill yes
			(thermal_gap 0.5)
			(thermal_bridge_width 0.5)
			(island_removal_mode 0)
		)
		(polygon
			(pts
				(arc
					(start 308.136798 -251.07138)
					(mid 308.151677 -251.107301)
					(end 308.187598 -251.12218)
				)
				(arc
					(start 309.587138 -251.12218)
					(mid 309.623059 -251.107301)
					(end 309.637938 -251.07138)
				)
				(arc
					(start 309.637938 -250.66244)
					(mid 309.623059 -250.626519)
					(end 309.587138 -250.61164)
				)
				(arc
					(start 308.187598 -250.61164)
					(mid 308.151677 -250.626519)
					(end 308.136798 -250.66244)
				)
			)
		)
	)
	(zone
		(layers "In1.Cu" "In2.Cu")
		(hatch none 0.5)
		(connect_pads
			(clearance 0)
		)
		(min_thickness 0.25)
		(keepout
			(tracks not_allowed)
			(vias allowed)
			(pads allowed)
			(copperpour not_allowed)
			(footprints allowed)
		)
		(placement
			(enabled no)
			(sheetname "")
		)
		(fill yes
			(thermal_gap 0.5)
			(thermal_bridge_width 0.5)
			(island_removal_mode 0)
		)
		(polygon
			(pts
				(arc
					(start 297.149266 -223.871536)
					(mid 297.164145 -223.907457)
					(end 297.200066 -223.922336)
				)
				(arc
					(start 298.599606 -223.922336)
					(mid 298.635527 -223.907457)
					(end 298.650406 -223.871536)
				)
				(arc
					(start 298.650406 -223.462596)
					(mid 298.635527 -223.426675)
					(end 298.599606 -223.411796)
				)
				(arc
					(start 297.200066 -223.411796)
					(mid 297.164145 -223.426675)
					(end 297.149266 -223.462596)
				)
			)
		)
	)
	(zone
		(layers "In1.Cu" "In2.Cu")
		(hatch none 0.5)
		(connect_pads
			(clearance 0)
		)
		(min_thickness 0.25)
		(keepout
			(tracks not_allowed)
			(vias allowed)
			(pads allowed)
			(copperpour not_allowed)
			(footprints allowed)
		)
		(placement
			(enabled no)
			(sheetname "")
		)
		(fill yes
			(thermal_gap 0.5)
			(thermal_bridge_width 0.5)
			(island_removal_mode 0)
		)
		(polygon
			(pts
				(arc
					(start 300.592998 -228.121464)
					(mid 300.607877 -228.157385)
					(end 300.643798 -228.172264)
				)
				(arc
					(start 302.043338 -228.172264)
					(mid 302.079259 -228.157385)
					(end 302.094138 -228.121464)
				)
				(arc
					(start 302.094138 -227.712524)
					(mid 302.079259 -227.676603)
					(end 302.043338 -227.661724)
				)
				(arc
					(start 300.643798 -227.661724)
					(mid 300.607877 -227.676603)
					(end 300.592998 -227.712524)
				)
			)
		)
	)
	(zone
		(layers "In1.Cu" "In2.Cu")
		(hatch none 0.5)
		(connect_pads
			(clearance 0)
		)
		(min_thickness 0.25)
		(keepout
			(tracks not_allowed)
			(vias allowed)
			(pads allowed)
			(copperpour not_allowed)
			(footprints allowed)
		)
		(placement
			(enabled no)
			(sheetname "")
		)
		(fill yes
			(thermal_gap 0.5)
			(thermal_bridge_width 0.5)
			(island_removal_mode 0)
		)
		(polygon
			(pts
				(arc
					(start 297.149266 -304.621438)
					(mid 297.164145 -304.657359)
					(end 297.200066 -304.672238)
				)
				(arc
					(start 298.599606 -304.672238)
					(mid 298.635527 -304.657359)
					(end 298.650406 -304.621438)
				)
				(arc
					(start 298.650406 -304.212498)
					(mid 298.635527 -304.176577)
					(end 298.599606 -304.161698)
				)
				(arc
					(start 297.200066 -304.161698)
					(mid 297.164145 -304.176577)
					(end 297.149266 -304.212498)
				)
			)
		)
	)
	(zone
		(layers "In1.Cu" "In2.Cu")
		(hatch none 0.5)
		(connect_pads
			(clearance 0)
		)
		(min_thickness 0.25)
		(keepout
			(tracks not_allowed)
			(vias allowed)
			(pads allowed)
			(copperpour not_allowed)
			(footprints allowed)
		)
		(placement
			(enabled no)
			(sheetname "")
		)
		(fill yes
			(thermal_gap 0.5)
			(thermal_bridge_width 0.5)
			(island_removal_mode 0)
		)
		(polygon
			(pts
				(arc
					(start 7.39013 -204.32141)
					(mid 7.405009 -204.357331)
					(end 7.44093 -204.37221)
				)
				(arc
					(start 8.84047 -204.37221)
					(mid 8.876391 -204.357331)
					(end 8.89127 -204.32141)
				)
				(arc
					(start 8.89127 -203.91247)
					(mid 8.876391 -203.876549)
					(end 8.84047 -203.86167)
				)
				(arc
					(start 7.44093 -203.86167)
					(mid 7.405009 -203.876549)
					(end 7.39013 -203.91247)
				)
			)
		)
	)
	(zone
		(layers "In1.Cu" "In2.Cu")
		(hatch none 0.5)
		(connect_pads
			(clearance 0)
		)
		(min_thickness 0.25)
		(keepout
			(tracks not_allowed)
			(vias allowed)
			(pads allowed)
			(copperpour not_allowed)
			(footprints allowed)
		)
		(placement
			(enabled no)
			(sheetname "")
		)
		(fill yes
			(thermal_gap 0.5)
			(thermal_bridge_width 0.5)
			(island_removal_mode 0)
		)
		(polygon
			(pts
				(arc
					(start 421.090598 -277.42134)
					(mid 421.105477 -277.457261)
					(end 421.141398 -277.47214)
				)
				(arc
					(start 422.540938 -277.47214)
					(mid 422.576859 -277.457261)
					(end 422.591738 -277.42134)
				)
				(arc
					(start 422.591738 -277.0124)
					(mid 422.576859 -276.976479)
					(end 422.540938 -276.9616)
				)
				(arc
					(start 421.141398 -276.9616)
					(mid 421.105477 -276.976479)
					(end 421.090598 -277.0124)
				)
			)
		)
	)
	(zone
		(layers "In1.Cu" "In2.Cu")
		(hatch none 0.5)
		(connect_pads
			(clearance 0)
		)
		(min_thickness 0.25)
		(keepout
			(tracks not_allowed)
			(vias allowed)
			(pads allowed)
			(copperpour not_allowed)
			(footprints allowed)
		)
		(placement
			(enabled no)
			(sheetname "")
		)
		(fill yes
			(thermal_gap 0.5)
			(thermal_bridge_width 0.5)
			(island_removal_mode 0)
		)
		(polygon
			(pts
				(arc
					(start 406.002998 -210.27136)
					(mid 406.017877 -210.307281)
					(end 406.053798 -210.32216)
				)
				(arc
					(start 407.453338 -210.32216)
					(mid 407.489259 -210.307281)
					(end 407.504138 -210.27136)
				)
				(arc
					(start 407.504138 -209.86242)
					(mid 407.489259 -209.826499)
					(end 407.453338 -209.81162)
				)
				(arc
					(start 406.053798 -209.81162)
					(mid 406.017877 -209.826499)
					(end 406.002998 -209.86242)
				)
			)
		)
	)
	(zone
		(layers "In1.Cu" "In2.Cu")
		(hatch none 0.5)
		(connect_pads
			(clearance 0)
		)
		(min_thickness 0.25)
		(keepout
			(tracks not_allowed)
			(vias allowed)
			(pads allowed)
			(copperpour not_allowed)
			(footprints allowed)
		)
		(placement
			(enabled no)
			(sheetname "")
		)
		(fill yes
			(thermal_gap 0.5)
			(thermal_bridge_width 0.5)
			(island_removal_mode 0)
		)
		(polygon
			(pts
				(arc
					(start 425.190666 -284.221428)
					(mid 425.205545 -284.257349)
					(end 425.241466 -284.272228)
				)
				(arc
					(start 426.641006 -284.272228)
					(mid 426.676927 -284.257349)
					(end 426.691806 -284.221428)
				)
				(arc
					(start 426.691806 -283.812488)
					(mid 426.676927 -283.776567)
					(end 426.641006 -283.761688)
				)
				(arc
					(start 425.241466 -283.761688)
					(mid 425.205545 -283.776567)
					(end 425.190666 -283.812488)
				)
			)
		)
	)
	(zone
		(layers "In1.Cu" "In2.Cu")
		(hatch none 0.5)
		(connect_pads
			(clearance 0)
		)
		(min_thickness 0.25)
		(keepout
			(tracks not_allowed)
			(vias allowed)
			(pads allowed)
			(copperpour not_allowed)
			(footprints allowed)
		)
		(placement
			(enabled no)
			(sheetname "")
		)
		(fill yes
			(thermal_gap 0.5)
			(thermal_bridge_width 0.5)
			(island_removal_mode 0)
		)
		(polygon
			(pts
				(arc
					(start 255.330198 -312.27141)
					(mid 255.345077 -312.307331)
					(end 255.380998 -312.32221)
				)
				(arc
					(start 256.780538 -312.32221)
					(mid 256.816459 -312.307331)
					(end 256.831338 -312.27141)
				)
				(arc
					(start 256.831338 -311.86247)
					(mid 256.816459 -311.826549)
					(end 256.780538 -311.81167)
				)
				(arc
					(start 255.380998 -311.81167)
					(mid 255.345077 -311.826549)
					(end 255.330198 -311.86247)
				)
			)
		)
	)
	(zone
		(layers "In1.Cu" "In2.Cu")
		(hatch none 0.5)
		(connect_pads
			(clearance 0)
		)
		(min_thickness 0.25)
		(keepout
			(tracks not_allowed)
			(vias allowed)
			(pads allowed)
			(copperpour not_allowed)
			(footprints allowed)
		)
		(placement
			(enabled no)
			(sheetname "")
		)
		(fill yes
			(thermal_gap 0.5)
			(thermal_bridge_width 0.5)
			(island_removal_mode 0)
		)
		(polygon
			(pts
				(arc
					(start 177.250598 -199.221344)
					(mid 177.265477 -199.257265)
					(end 177.301398 -199.272144)
				)
				(arc
					(start 178.700938 -199.272144)
					(mid 178.736859 -199.257265)
					(end 178.751738 -199.221344)
				)
				(arc
					(start 178.751738 -198.812404)
					(mid 178.736859 -198.776483)
					(end 178.700938 -198.761604)
				)
				(arc
					(start 177.301398 -198.761604)
					(mid 177.265477 -198.776483)
					(end 177.250598 -198.812404)
				)
			)
		)
	)
	(zone
		(layers "In1.Cu" "In2.Cu")
		(hatch none 0.5)
		(connect_pads
			(clearance 0)
		)
		(min_thickness 0.25)
		(keepout
			(tracks not_allowed)
			(vias allowed)
			(pads allowed)
			(copperpour not_allowed)
			(footprints allowed)
		)
		(placement
			(enabled no)
			(sheetname "")
		)
		(fill yes
			(thermal_gap 0.5)
			(thermal_bridge_width 0.5)
			(island_removal_mode 0)
		)
		(polygon
			(pts
				(arc
					(start 406.002998 -204.32141)
					(mid 406.017877 -204.357331)
					(end 406.053798 -204.37221)
				)
				(arc
					(start 407.453338 -204.37221)
					(mid 407.489259 -204.357331)
					(end 407.504138 -204.32141)
				)
				(arc
					(start 407.504138 -203.91247)
					(mid 407.489259 -203.876549)
					(end 407.453338 -203.86167)
				)
				(arc
					(start 406.053798 -203.86167)
					(mid 406.017877 -203.876549)
					(end 406.002998 -203.91247)
				)
			)
		)
	)
	(zone
		(layers "In1.Cu" "In2.Cu")
		(hatch none 0.5)
		(connect_pads
			(clearance 0)
		)
		(min_thickness 0.25)
		(keepout
			(tracks not_allowed)
			(vias allowed)
			(pads allowed)
			(copperpour not_allowed)
			(footprints allowed)
		)
		(placement
			(enabled no)
			(sheetname "")
		)
		(fill yes
			(thermal_gap 0.5)
			(thermal_bridge_width 0.5)
			(island_removal_mode 0)
		)
		(polygon
			(pts
				(arc
					(start 293.049198 -264.671302)
					(mid 293.064077 -264.707223)
					(end 293.099998 -264.722102)
				)
				(arc
					(start 294.499538 -264.722102)
					(mid 294.535459 -264.707223)
					(end 294.550338 -264.671302)
				)
				(arc
					(start 294.550338 -264.262362)
					(mid 294.535459 -264.226441)
					(end 294.499538 -264.211562)
				)
				(arc
					(start 293.099998 -264.211562)
					(mid 293.064077 -264.226441)
					(end 293.049198 -264.262362)
				)
			)
		)
	)
	(zone
		(layers "In1.Cu" "In2.Cu")
		(hatch none 0.5)
		(connect_pads
			(clearance 0)
		)
		(min_thickness 0.25)
		(keepout
			(tracks not_allowed)
			(vias allowed)
			(pads allowed)
			(copperpour not_allowed)
			(footprints allowed)
		)
		(placement
			(enabled no)
			(sheetname "")
		)
		(fill yes
			(thermal_gap 0.5)
			(thermal_bridge_width 0.5)
			(island_removal_mode 0)
		)
		(polygon
			(pts
				(arc
					(start 443.721998 -210.27136)
					(mid 443.736877 -210.307281)
					(end 443.772798 -210.32216)
				)
				(arc
					(start 445.172338 -210.32216)
					(mid 445.208259 -210.307281)
					(end 445.223138 -210.27136)
				)
				(arc
					(start 445.223138 -209.86242)
					(mid 445.208259 -209.826499)
					(end 445.172338 -209.81162)
				)
				(arc
					(start 443.772798 -209.81162)
					(mid 443.736877 -209.826499)
					(end 443.721998 -209.86242)
				)
			)
		)
	)
	(zone
		(layers "In1.Cu" "In2.Cu")
		(hatch none 0.5)
		(connect_pads
			(clearance 0)
		)
		(min_thickness 0.25)
		(keepout
			(tracks not_allowed)
			(vias allowed)
			(pads allowed)
			(copperpour not_allowed)
			(footprints allowed)
		)
		(placement
			(enabled no)
			(sheetname "")
		)
		(fill yes
			(thermal_gap 0.5)
			(thermal_bridge_width 0.5)
			(island_removal_mode 0)
		)
		(polygon
			(pts
				(arc
					(start 266.974066 -311.421526)
					(mid 266.988945 -311.457447)
					(end 267.024866 -311.472326)
				)
				(arc
					(start 268.424406 -311.472326)
					(mid 268.460327 -311.457447)
					(end 268.475206 -311.421526)
				)
				(arc
					(start 268.475206 -311.012586)
					(mid 268.460327 -310.976665)
					(end 268.424406 -310.961786)
				)
				(arc
					(start 267.024866 -310.961786)
					(mid 266.988945 -310.976665)
					(end 266.974066 -311.012586)
				)
			)
		)
	)
	(zone
		(layers "In1.Cu" "In2.Cu")
		(hatch none 0.5)
		(connect_pads
			(clearance 0)
		)
		(min_thickness 0.25)
		(keepout
			(tracks not_allowed)
			(vias allowed)
			(pads allowed)
			(copperpour not_allowed)
			(footprints allowed)
		)
		(placement
			(enabled no)
			(sheetname "")
		)
		(fill yes
			(thermal_gap 0.5)
			(thermal_bridge_width 0.5)
			(island_removal_mode 0)
		)
		(polygon
			(pts
				(arc
					(start 158.06293 -312.27141)
					(mid 158.077809 -312.307331)
					(end 158.11373 -312.32221)
				)
				(arc
					(start 159.51327 -312.32221)
					(mid 159.549191 -312.307331)
					(end 159.56407 -312.27141)
				)
				(arc
					(start 159.56407 -311.86247)
					(mid 159.549191 -311.826549)
					(end 159.51327 -311.81167)
				)
				(arc
					(start 158.11373 -311.81167)
					(mid 158.077809 -311.826549)
					(end 158.06293 -311.86247)
				)
			)
		)
	)
	(zone
		(layers "In1.Cu" "In2.Cu")
		(hatch none 0.5)
		(connect_pads
			(clearance 0)
		)
		(min_thickness 0.25)
		(keepout
			(tracks not_allowed)
			(vias allowed)
			(pads allowed)
			(copperpour not_allowed)
			(footprints allowed)
		)
		(placement
			(enabled no)
			(sheetname "")
		)
		(fill yes
			(thermal_gap 0.5)
			(thermal_bridge_width 0.5)
			(island_removal_mode 0)
		)
		(polygon
			(pts
				(arc
					(start 173.15053 -296.121328)
					(mid 173.165409 -296.157249)
					(end 173.20133 -296.172128)
				)
				(arc
					(start 174.60087 -296.172128)
					(mid 174.636791 -296.157249)
					(end 174.65167 -296.121328)
				)
				(arc
					(start 174.65167 -295.712388)
					(mid 174.636791 -295.676467)
					(end 174.60087 -295.661588)
				)
				(arc
					(start 173.20133 -295.661588)
					(mid 173.165409 -295.676467)
					(end 173.15053 -295.712388)
				)
			)
		)
	)
	(zone
		(layers "In1.Cu" "In2.Cu")
		(hatch none 0.5)
		(connect_pads
			(clearance 0)
		)
		(min_thickness 0.25)
		(keepout
			(tracks not_allowed)
			(vias allowed)
			(pads allowed)
			(copperpour not_allowed)
			(footprints allowed)
		)
		(placement
			(enabled no)
			(sheetname "")
		)
		(fill yes
			(thermal_gap 0.5)
			(thermal_bridge_width 0.5)
			(island_removal_mode 0)
		)
		(polygon
			(pts
				(arc
					(start 207.425798 -237.471458)
					(mid 207.440677 -237.507379)
					(end 207.476598 -237.522258)
				)
				(arc
					(start 208.876138 -237.522258)
					(mid 208.912059 -237.507379)
					(end 208.926938 -237.471458)
				)
				(arc
					(start 208.926938 -237.062518)
					(mid 208.912059 -237.026597)
					(end 208.876138 -237.011718)
				)
				(arc
					(start 207.476598 -237.011718)
					(mid 207.440677 -237.026597)
					(end 207.425798 -237.062518)
				)
			)
		)
	)
	(zone
		(layers "In1.Cu" "In2.Cu")
		(hatch none 0.5)
		(connect_pads
			(clearance 0)
		)
		(min_thickness 0.25)
		(keepout
			(tracks not_allowed)
			(vias allowed)
			(pads allowed)
			(copperpour not_allowed)
			(footprints allowed)
		)
		(placement
			(enabled no)
			(sheetname "")
		)
		(fill yes
			(thermal_gap 0.5)
			(thermal_bridge_width 0.5)
			(island_removal_mode 0)
		)
		(polygon
			(pts
				(arc
					(start 180.69433 -269.771368)
					(mid 180.709209 -269.807289)
					(end 180.74513 -269.822168)
				)
				(arc
					(start 182.14467 -269.822168)
					(mid 182.180591 -269.807289)
					(end 182.19547 -269.771368)
				)
				(arc
					(start 182.19547 -269.362428)
					(mid 182.180591 -269.326507)
					(end 182.14467 -269.311628)
				)
				(arc
					(start 180.74513 -269.311628)
					(mid 180.709209 -269.326507)
					(end 180.69433 -269.362428)
				)
			)
		)
	)
	(zone
		(layers "In1.Cu" "In2.Cu")
		(hatch none 0.5)
		(connect_pads
			(clearance 0)
		)
		(min_thickness 0.25)
		(keepout
			(tracks not_allowed)
			(vias allowed)
			(pads allowed)
			(copperpour not_allowed)
			(footprints allowed)
		)
		(placement
			(enabled no)
			(sheetname "")
		)
		(fill yes
			(thermal_gap 0.5)
			(thermal_bridge_width 0.5)
			(island_removal_mode 0)
		)
		(polygon
			(pts
				(arc
					(start 447.822066 -306.32146)
					(mid 447.836945 -306.357381)
					(end 447.872866 -306.37226)
				)
				(arc
					(start 449.272406 -306.37226)
					(mid 449.308327 -306.357381)
					(end 449.323206 -306.32146)
				)
				(arc
					(start 449.323206 -305.91252)
					(mid 449.308327 -305.876599)
					(end 449.272406 -305.86172)
				)
				(arc
					(start 447.872866 -305.86172)
					(mid 447.836945 -305.876599)
					(end 447.822066 -305.91252)
				)
			)
		)
	)
	(zone
		(layers "In1.Cu" "In2.Cu")
		(hatch none 0.5)
		(connect_pads
			(clearance 0)
		)
		(min_thickness 0.25)
		(keepout
			(tracks not_allowed)
			(vias allowed)
			(pads allowed)
			(copperpour not_allowed)
			(footprints allowed)
		)
		(placement
			(enabled no)
			(sheetname "")
		)
		(fill yes
			(thermal_gap 0.5)
			(thermal_bridge_width 0.5)
			(island_removal_mode 0)
		)
		(polygon
			(pts
				(arc
					(start 436.178198 -249.371358)
					(mid 436.193077 -249.407279)
					(end 436.228998 -249.422158)
				)
				(arc
					(start 437.628538 -249.422158)
					(mid 437.664459 -249.407279)
					(end 437.679338 -249.371358)
				)
				(arc
					(start 437.679338 -248.962418)
					(mid 437.664459 -248.926497)
					(end 437.628538 -248.911618)
				)
				(arc
					(start 436.228998 -248.911618)
					(mid 436.193077 -248.926497)
					(end 436.178198 -248.962418)
				)
			)
		)
	)
	(zone
		(layers "In1.Cu" "In2.Cu")
		(hatch none 0.5)
		(connect_pads
			(clearance 0)
		)
		(min_thickness 0.25)
		(keepout
			(tracks not_allowed)
			(vias allowed)
			(pads allowed)
			(copperpour not_allowed)
			(footprints allowed)
		)
		(placement
			(enabled no)
			(sheetname "")
		)
		(fill yes
			(thermal_gap 0.5)
			(thermal_bridge_width 0.5)
			(island_removal_mode 0)
		)
		(polygon
			(pts
				(arc
					(start 49.209198 -225.571304)
					(mid 49.224077 -225.607225)
					(end 49.259998 -225.622104)
				)
				(arc
					(start 50.659538 -225.622104)
					(mid 50.695459 -225.607225)
					(end 50.710338 -225.571304)
				)
				(arc
					(start 50.710338 -225.162364)
					(mid 50.695459 -225.126443)
					(end 50.659538 -225.111564)
				)
				(arc
					(start 49.259998 -225.111564)
					(mid 49.224077 -225.126443)
					(end 49.209198 -225.162364)
				)
			)
		)
	)
	(zone
		(layers "In1.Cu" "In2.Cu")
		(hatch none 0.5)
		(connect_pads
			(clearance 0)
		)
		(min_thickness 0.25)
		(keepout
			(tracks not_allowed)
			(vias allowed)
			(pads allowed)
			(copperpour not_allowed)
			(footprints allowed)
		)
		(placement
			(enabled no)
			(sheetname "")
		)
		(fill yes
			(thermal_gap 0.5)
			(thermal_bridge_width 0.5)
			(island_removal_mode 0)
		)
		(polygon
			(pts
				(arc
					(start 19.033998 -223.871536)
					(mid 19.048877 -223.907457)
					(end 19.084798 -223.922336)
				)
				(arc
					(start 20.484338 -223.922336)
					(mid 20.520259 -223.907457)
					(end 20.535138 -223.871536)
				)
				(arc
					(start 20.535138 -223.462596)
					(mid 20.520259 -223.426675)
					(end 20.484338 -223.411796)
				)
				(arc
					(start 19.084798 -223.411796)
					(mid 19.048877 -223.426675)
					(end 19.033998 -223.462596)
				)
			)
		)
	)
	(zone
		(layers "In1.Cu" "In2.Cu")
		(hatch none 0.5)
		(connect_pads
			(clearance 0)
		)
		(min_thickness 0.25)
		(keepout
			(tracks not_allowed)
			(vias allowed)
			(pads allowed)
			(copperpour not_allowed)
			(footprints allowed)
		)
		(placement
			(enabled no)
			(sheetname "")
		)
		(fill yes
			(thermal_gap 0.5)
			(thermal_bridge_width 0.5)
			(island_removal_mode 0)
		)
		(polygon
			(pts
				(arc
					(start 52.65293 -280.821384)
					(mid 52.667809 -280.857305)
					(end 52.70373 -280.872184)
				)
				(arc
					(start 54.10327 -280.872184)
					(mid 54.139191 -280.857305)
					(end 54.15407 -280.821384)
				)
				(arc
					(start 54.15407 -280.412444)
					(mid 54.139191 -280.376523)
					(end 54.10327 -280.361644)
				)
				(arc
					(start 52.70373 -280.361644)
					(mid 52.667809 -280.376523)
					(end 52.65293 -280.412444)
				)
			)
		)
	)
	(zone
		(layers "In1.Cu" "In2.Cu")
		(hatch none 0.5)
		(connect_pads
			(clearance 0)
		)
		(min_thickness 0.25)
		(keepout
			(tracks not_allowed)
			(vias allowed)
			(pads allowed)
			(copperpour not_allowed)
			(footprints allowed)
		)
		(placement
			(enabled no)
			(sheetname "")
		)
		(fill yes
			(thermal_gap 0.5)
			(thermal_bridge_width 0.5)
			(island_removal_mode 0)
		)
		(polygon
			(pts
				(arc
					(start 259.430266 -263.821418)
					(mid 259.445145 -263.857339)
					(end 259.481066 -263.872218)
				)
				(arc
					(start 260.880606 -263.872218)
					(mid 260.916527 -263.857339)
					(end 260.931406 -263.821418)
				)
				(arc
					(start 260.931406 -263.412478)
					(mid 260.916527 -263.376557)
					(end 260.880606 -263.361678)
				)
				(arc
					(start 259.481066 -263.361678)
					(mid 259.445145 -263.376557)
					(end 259.430266 -263.412478)
				)
			)
		)
	)
	(zone
		(layers "In1.Cu" "In2.Cu")
		(hatch none 0.5)
		(connect_pads
			(clearance 0)
		)
		(min_thickness 0.25)
		(keepout
			(tracks not_allowed)
			(vias allowed)
			(pads allowed)
			(copperpour not_allowed)
			(footprints allowed)
		)
		(placement
			(enabled no)
			(sheetname "")
		)
		(fill yes
			(thermal_gap 0.5)
			(thermal_bridge_width 0.5)
			(island_removal_mode 0)
		)
		(polygon
			(pts
				(arc
					(start 19.033998 -227.271326)
					(mid 19.048877 -227.307247)
					(end 19.084798 -227.322126)
				)
				(arc
					(start 20.484338 -227.322126)
					(mid 20.520259 -227.307247)
					(end 20.535138 -227.271326)
				)
				(arc
					(start 20.535138 -226.862386)
					(mid 20.520259 -226.826465)
					(end 20.484338 -226.811586)
				)
				(arc
					(start 19.084798 -226.811586)
					(mid 19.048877 -226.826465)
					(end 19.033998 -226.862386)
				)
			)
		)
	)
	(zone
		(layers "In1.Cu" "In2.Cu")
		(hatch none 0.5)
		(connect_pads
			(clearance 0)
		)
		(min_thickness 0.25)
		(keepout
			(tracks not_allowed)
			(vias allowed)
			(pads allowed)
			(copperpour not_allowed)
			(footprints allowed)
		)
		(placement
			(enabled no)
			(sheetname "")
		)
		(fill yes
			(thermal_gap 0.5)
			(thermal_bridge_width 0.5)
			(island_removal_mode 0)
		)
		(polygon
			(pts
				(arc
					(start 37.56533 -198.37146)
					(mid 37.580209 -198.407381)
					(end 37.61613 -198.42226)
				)
				(arc
					(start 39.01567 -198.42226)
					(mid 39.051591 -198.407381)
					(end 39.06647 -198.37146)
				)
				(arc
					(start 39.06647 -197.96252)
					(mid 39.051591 -197.926599)
					(end 39.01567 -197.91172)
				)
				(arc
					(start 37.61613 -197.91172)
					(mid 37.580209 -197.926599)
					(end 37.56533 -197.96252)
				)
			)
		)
	)
	(zone
		(layers "In1.Cu" "In2.Cu")
		(hatch none 0.5)
		(connect_pads
			(clearance 0)
		)
		(min_thickness 0.25)
		(keepout
			(tracks not_allowed)
			(vias allowed)
			(pads allowed)
			(copperpour not_allowed)
			(footprints allowed)
		)
		(placement
			(enabled no)
			(sheetname "")
		)
		(fill yes
			(thermal_gap 0.5)
			(thermal_bridge_width 0.5)
			(island_removal_mode 0)
		)
		(polygon
			(pts
				(arc
					(start 41.665398 -304.621438)
					(mid 41.680277 -304.657359)
					(end 41.716198 -304.672238)
				)
				(arc
					(start 43.115738 -304.672238)
					(mid 43.151659 -304.657359)
					(end 43.166538 -304.621438)
				)
				(arc
					(start 43.166538 -304.212498)
					(mid 43.151659 -304.176577)
					(end 43.115738 -304.161698)
				)
				(arc
					(start 41.716198 -304.161698)
					(mid 41.680277 -304.176577)
					(end 41.665398 -304.212498)
				)
			)
		)
	)
	(zone
		(layers "In1.Cu" "In2.Cu")
		(hatch none 0.5)
		(connect_pads
			(clearance 0)
		)
		(min_thickness 0.25)
		(keepout
			(tracks not_allowed)
			(vias allowed)
			(pads allowed)
			(copperpour not_allowed)
			(footprints allowed)
		)
		(placement
			(enabled no)
			(sheetname "")
		)
		(fill yes
			(thermal_gap 0.5)
			(thermal_bridge_width 0.5)
			(island_removal_mode 0)
		)
		(polygon
			(pts
				(arc
					(start 60.19673 -288.471356)
					(mid 60.211609 -288.507277)
					(end 60.24753 -288.522156)
				)
				(arc
					(start 61.64707 -288.522156)
					(mid 61.682991 -288.507277)
					(end 61.69787 -288.471356)
				)
				(arc
					(start 61.69787 -288.062416)
					(mid 61.682991 -288.026495)
					(end 61.64707 -288.011616)
				)
				(arc
					(start 60.24753 -288.011616)
					(mid 60.211609 -288.026495)
					(end 60.19673 -288.062416)
				)
			)
		)
	)
	(zone
		(layers "In1.Cu" "In2.Cu")
		(hatch none 0.5)
		(connect_pads
			(clearance 0)
		)
		(min_thickness 0.25)
		(keepout
			(tracks not_allowed)
			(vias allowed)
			(pads allowed)
			(copperpour not_allowed)
			(footprints allowed)
		)
		(placement
			(enabled no)
			(sheetname "")
		)
		(fill yes
			(thermal_gap 0.5)
			(thermal_bridge_width 0.5)
			(island_removal_mode 0)
		)
		(polygon
			(pts
				(arc
					(start 30.02153 -291.8714)
					(mid 30.036409 -291.907321)
					(end 30.07233 -291.9222)
				)
				(arc
					(start 31.47187 -291.9222)
					(mid 31.507791 -291.907321)
					(end 31.52267 -291.8714)
				)
				(arc
					(start 31.52267 -291.46246)
					(mid 31.507791 -291.426539)
					(end 31.47187 -291.41166)
				)
				(arc
					(start 30.07233 -291.41166)
					(mid 30.036409 -291.426539)
					(end 30.02153 -291.46246)
				)
			)
		)
	)
	(zone
		(layers "In1.Cu" "In2.Cu")
		(hatch none 0.5)
		(connect_pads
			(clearance 0)
		)
		(min_thickness 0.25)
		(keepout
			(tracks not_allowed)
			(vias allowed)
			(pads allowed)
			(copperpour not_allowed)
			(footprints allowed)
		)
		(placement
			(enabled no)
			(sheetname "")
		)
		(fill yes
			(thermal_gap 0.5)
			(thermal_bridge_width 0.5)
			(island_removal_mode 0)
		)
		(polygon
			(pts
				(arc
					(start 184.794398 -312.27141)
					(mid 184.809277 -312.307331)
					(end 184.845198 -312.32221)
				)
				(arc
					(start 186.244738 -312.32221)
					(mid 186.280659 -312.307331)
					(end 186.295538 -312.27141)
				)
				(arc
					(start 186.295538 -311.86247)
					(mid 186.280659 -311.826549)
					(end 186.244738 -311.81167)
				)
				(arc
					(start 184.845198 -311.81167)
					(mid 184.809277 -311.826549)
					(end 184.794398 -311.86247)
				)
			)
		)
	)
	(zone
		(layers "In1.Cu" "In2.Cu")
		(hatch none 0.5)
		(connect_pads
			(clearance 0)
		)
		(min_thickness 0.25)
		(keepout
			(tracks not_allowed)
			(vias allowed)
			(pads allowed)
			(copperpour not_allowed)
			(footprints allowed)
		)
		(placement
			(enabled no)
			(sheetname "")
		)
		(fill yes
			(thermal_gap 0.5)
			(thermal_bridge_width 0.5)
			(island_removal_mode 0)
		)
		(polygon
			(pts
				(arc
					(start 417.646866 -284.221428)
					(mid 417.661745 -284.257349)
					(end 417.697666 -284.272228)
				)
				(arc
					(start 419.097206 -284.272228)
					(mid 419.133127 -284.257349)
					(end 419.148006 -284.221428)
				)
				(arc
					(start 419.148006 -283.812488)
					(mid 419.133127 -283.776567)
					(end 419.097206 -283.761688)
				)
				(arc
					(start 417.697666 -283.761688)
					(mid 417.661745 -283.776567)
					(end 417.646866 -283.812488)
				)
			)
		)
	)
	(zone
		(layers "In1.Cu" "In2.Cu")
		(hatch none 0.5)
		(connect_pads
			(clearance 0)
		)
		(min_thickness 0.25)
		(keepout
			(tracks not_allowed)
			(vias allowed)
			(pads allowed)
			(copperpour not_allowed)
			(footprints allowed)
		)
		(placement
			(enabled no)
			(sheetname "")
		)
		(fill yes
			(thermal_gap 0.5)
			(thermal_bridge_width 0.5)
			(island_removal_mode 0)
		)
		(polygon
			(pts
				(arc
					(start 266.974066 -292.721538)
					(mid 266.988945 -292.757459)
					(end 267.024866 -292.772338)
				)
				(arc
					(start 268.424406 -292.772338)
					(mid 268.460327 -292.757459)
					(end 268.475206 -292.721538)
				)
				(arc
					(start 268.475206 -292.312598)
					(mid 268.460327 -292.276677)
					(end 268.424406 -292.261798)
				)
				(arc
					(start 267.024866 -292.261798)
					(mid 266.988945 -292.276677)
					(end 266.974066 -292.312598)
				)
			)
		)
	)
	(zone
		(layers "In1.Cu" "In2.Cu")
		(hatch none 0.5)
		(connect_pads
			(clearance 0)
		)
		(min_thickness 0.25)
		(keepout
			(tracks not_allowed)
			(vias allowed)
			(pads allowed)
			(copperpour not_allowed)
			(footprints allowed)
		)
		(placement
			(enabled no)
			(sheetname "")
		)
		(fill yes
			(thermal_gap 0.5)
			(thermal_bridge_width 0.5)
			(island_removal_mode 0)
		)
		(polygon
			(pts
				(arc
					(start 421.090598 -206.021432)
					(mid 421.105477 -206.057353)
					(end 421.141398 -206.072232)
				)
				(arc
					(start 422.540938 -206.072232)
					(mid 422.576859 -206.057353)
					(end 422.591738 -206.021432)
				)
				(arc
					(start 422.591738 -205.612492)
					(mid 422.576859 -205.576571)
					(end 422.540938 -205.561692)
				)
				(arc
					(start 421.141398 -205.561692)
					(mid 421.105477 -205.576571)
					(end 421.090598 -205.612492)
				)
			)
		)
	)
	(zone
		(layers "In1.Cu" "In2.Cu")
		(hatch none 0.5)
		(connect_pads
			(clearance 0)
		)
		(min_thickness 0.25)
		(keepout
			(tracks not_allowed)
			(vias allowed)
			(pads allowed)
			(copperpour not_allowed)
			(footprints allowed)
		)
		(placement
			(enabled no)
			(sheetname "")
		)
		(fill yes
			(thermal_gap 0.5)
			(thermal_bridge_width 0.5)
			(island_removal_mode 0)
		)
		(polygon
			(pts
				(arc
					(start 440.278266 -200.071482)
					(mid 440.293145 -200.107403)
					(end 440.329066 -200.122282)
				)
				(arc
					(start 441.728606 -200.122282)
					(mid 441.764527 -200.107403)
					(end 441.779406 -200.071482)
				)
				(arc
					(start 441.779406 -199.662542)
					(mid 441.764527 -199.626621)
					(end 441.728606 -199.611742)
				)
				(arc
					(start 440.329066 -199.611742)
					(mid 440.293145 -199.626621)
					(end 440.278266 -199.662542)
				)
			)
		)
	)
	(zone
		(layers "In1.Cu" "In2.Cu")
		(hatch none 0.5)
		(connect_pads
			(clearance 0)
		)
		(min_thickness 0.25)
		(keepout
			(tracks not_allowed)
			(vias allowed)
			(pads allowed)
			(copperpour not_allowed)
			(footprints allowed)
		)
		(placement
			(enabled no)
			(sheetname "")
		)
		(fill yes
			(thermal_gap 0.5)
			(thermal_bridge_width 0.5)
			(island_removal_mode 0)
		)
		(polygon
			(pts
				(arc
					(start 207.425798 -209.421476)
					(mid 207.440677 -209.457397)
					(end 207.476598 -209.472276)
				)
				(arc
					(start 208.876138 -209.472276)
					(mid 208.912059 -209.457397)
					(end 208.926938 -209.421476)
				)
				(arc
					(start 208.926938 -209.012536)
					(mid 208.912059 -208.976615)
					(end 208.876138 -208.961736)
				)
				(arc
					(start 207.476598 -208.961736)
					(mid 207.440677 -208.976615)
					(end 207.425798 -209.012536)
				)
			)
		)
	)
	(zone
		(layers "In1.Cu" "In2.Cu")
		(hatch none 0.5)
		(connect_pads
			(clearance 0)
		)
		(min_thickness 0.25)
		(keepout
			(tracks not_allowed)
			(vias allowed)
			(pads allowed)
			(copperpour not_allowed)
			(footprints allowed)
		)
		(placement
			(enabled no)
			(sheetname "")
		)
		(fill yes
			(thermal_gap 0.5)
			(thermal_bridge_width 0.5)
			(island_removal_mode 0)
		)
		(polygon
			(pts
				(arc
					(start 177.250598 -211.121498)
					(mid 177.265477 -211.157419)
					(end 177.301398 -211.172298)
				)
				(arc
					(start 178.700938 -211.172298)
					(mid 178.736859 -211.157419)
					(end 178.751738 -211.121498)
				)
				(arc
					(start 178.751738 -210.712558)
					(mid 178.736859 -210.676637)
					(end 178.700938 -210.661758)
				)
				(arc
					(start 177.301398 -210.661758)
					(mid 177.265477 -210.676637)
					(end 177.250598 -210.712558)
				)
			)
		)
	)
	(zone
		(layers "In1.Cu" "In2.Cu")
		(hatch none 0.5)
		(connect_pads
			(clearance 0)
		)
		(min_thickness 0.25)
		(keepout
			(tracks not_allowed)
			(vias allowed)
			(pads allowed)
			(copperpour not_allowed)
			(footprints allowed)
		)
		(placement
			(enabled no)
			(sheetname "")
		)
		(fill yes
			(thermal_gap 0.5)
			(thermal_bridge_width 0.5)
			(island_removal_mode 0)
		)
		(polygon
			(pts
				(arc
					(start 443.721998 -238.321342)
					(mid 443.736877 -238.357263)
					(end 443.772798 -238.372142)
				)
				(arc
					(start 445.172338 -238.372142)
					(mid 445.208259 -238.357263)
					(end 445.223138 -238.321342)
				)
				(arc
					(start 445.223138 -237.912402)
					(mid 445.208259 -237.876481)
					(end 445.172338 -237.861602)
				)
				(arc
					(start 443.772798 -237.861602)
					(mid 443.736877 -237.876481)
					(end 443.721998 -237.912402)
				)
			)
		)
	)
	(zone
		(layers "In1.Cu" "In2.Cu")
		(hatch none 0.5)
		(connect_pads
			(clearance 0)
		)
		(min_thickness 0.25)
		(keepout
			(tracks not_allowed)
			(vias allowed)
			(pads allowed)
			(copperpour not_allowed)
			(footprints allowed)
		)
		(placement
			(enabled no)
			(sheetname "")
		)
		(fill yes
			(thermal_gap 0.5)
			(thermal_bridge_width 0.5)
			(island_removal_mode 0)
		)
		(polygon
			(pts
				(arc
					(start 60.19673 -313.121294)
					(mid 60.211609 -313.157215)
					(end 60.24753 -313.172094)
				)
				(arc
					(start 61.64707 -313.172094)
					(mid 61.682991 -313.157215)
					(end 61.69787 -313.121294)
				)
				(arc
					(start 61.69787 -312.712354)
					(mid 61.682991 -312.676433)
					(end 61.64707 -312.661554)
				)
				(arc
					(start 60.24753 -312.661554)
					(mid 60.211609 -312.676433)
					(end 60.19673 -312.712354)
				)
			)
		)
	)
	(zone
		(layers "In1.Cu" "In2.Cu")
		(hatch none 0.5)
		(connect_pads
			(clearance 0)
		)
		(min_thickness 0.25)
		(keepout
			(tracks not_allowed)
			(vias allowed)
			(pads allowed)
			(copperpour not_allowed)
			(footprints allowed)
		)
		(placement
			(enabled no)
			(sheetname "")
		)
		(fill yes
			(thermal_gap 0.5)
			(thermal_bridge_width 0.5)
			(island_removal_mode 0)
		)
		(polygon
			(pts
				(arc
					(start 173.15053 -251.07138)
					(mid 173.165409 -251.107301)
					(end 173.20133 -251.12218)
				)
				(arc
					(start 174.60087 -251.12218)
					(mid 174.636791 -251.107301)
					(end 174.65167 -251.07138)
				)
				(arc
					(start 174.65167 -250.66244)
					(mid 174.636791 -250.626519)
					(end 174.60087 -250.61164)
				)
				(arc
					(start 173.20133 -250.61164)
					(mid 173.165409 -250.626519)
					(end 173.15053 -250.66244)
				)
			)
		)
	)
	(zone
		(layers "In1.Cu" "In2.Cu")
		(hatch none 0.5)
		(connect_pads
			(clearance 0)
		)
		(min_thickness 0.25)
		(keepout
			(tracks not_allowed)
			(vias allowed)
			(pads allowed)
			(copperpour not_allowed)
			(footprints allowed)
		)
		(placement
			(enabled no)
			(sheetname "")
		)
		(fill yes
			(thermal_gap 0.5)
			(thermal_bridge_width 0.5)
			(island_removal_mode 0)
		)
		(polygon
			(pts
				(arc
					(start 37.56533 -307.171344)
					(mid 37.580209 -307.207265)
					(end 37.61613 -307.222144)
				)
				(arc
					(start 39.01567 -307.222144)
					(mid 39.051591 -307.207265)
					(end 39.06647 -307.171344)
				)
				(arc
					(start 39.06647 -306.762404)
					(mid 39.051591 -306.726483)
					(end 39.01567 -306.711604)
				)
				(arc
					(start 37.61613 -306.711604)
					(mid 37.580209 -306.726483)
					(end 37.56533 -306.762404)
				)
			)
		)
	)
	(zone
		(layers "In1.Cu" "In2.Cu")
		(hatch none 0.5)
		(connect_pads
			(clearance 0)
		)
		(min_thickness 0.25)
		(keepout
			(tracks not_allowed)
			(vias allowed)
			(pads allowed)
			(copperpour not_allowed)
			(footprints allowed)
		)
		(placement
			(enabled no)
			(sheetname "")
		)
		(fill yes
			(thermal_gap 0.5)
			(thermal_bridge_width 0.5)
			(island_removal_mode 0)
		)
		(polygon
			(pts
				(arc
					(start 262.873998 -293.571422)
					(mid 262.888877 -293.607343)
					(end 262.924798 -293.622222)
				)
				(arc
					(start 264.324338 -293.622222)
					(mid 264.360259 -293.607343)
					(end 264.375138 -293.571422)
				)
				(arc
					(start 264.375138 -293.162482)
					(mid 264.360259 -293.126561)
					(end 264.324338 -293.111682)
				)
				(arc
					(start 262.924798 -293.111682)
					(mid 262.888877 -293.126561)
					(end 262.873998 -293.162482)
				)
			)
		)
	)
	(zone
		(layers "In1.Cu" "In2.Cu")
		(hatch none 0.5)
		(connect_pads
			(clearance 0)
		)
		(min_thickness 0.25)
		(keepout
			(tracks not_allowed)
			(vias allowed)
			(pads allowed)
			(copperpour not_allowed)
			(footprints allowed)
		)
		(placement
			(enabled no)
			(sheetname "")
		)
		(fill yes
			(thermal_gap 0.5)
			(thermal_bridge_width 0.5)
			(island_removal_mode 0)
		)
		(polygon
			(pts
				(arc
					(start 300.592998 -274.871434)
					(mid 300.607877 -274.907355)
					(end 300.643798 -274.922234)
				)
				(arc
					(start 302.043338 -274.922234)
					(mid 302.079259 -274.907355)
					(end 302.094138 -274.871434)
				)
				(arc
					(start 302.094138 -274.462494)
					(mid 302.079259 -274.426573)
					(end 302.043338 -274.411694)
				)
				(arc
					(start 300.643798 -274.411694)
					(mid 300.607877 -274.426573)
					(end 300.592998 -274.462494)
				)
			)
		)
	)
	(zone
		(layers "In1.Cu" "In2.Cu")
		(hatch none 0.5)
		(connect_pads
			(clearance 0)
		)
		(min_thickness 0.25)
		(keepout
			(tracks not_allowed)
			(vias allowed)
			(pads allowed)
			(copperpour not_allowed)
			(footprints allowed)
		)
		(placement
			(enabled no)
			(sheetname "")
		)
		(fill yes
			(thermal_gap 0.5)
			(thermal_bridge_width 0.5)
			(island_removal_mode 0)
		)
		(polygon
			(pts
				(arc
					(start 282.061666 -296.971466)
					(mid 282.076545 -297.007387)
					(end 282.112466 -297.022266)
				)
				(arc
					(start 283.512006 -297.022266)
					(mid 283.547927 -297.007387)
					(end 283.562806 -296.971466)
				)
				(arc
					(start 283.562806 -296.562526)
					(mid 283.547927 -296.526605)
					(end 283.512006 -296.511726)
				)
				(arc
					(start 282.112466 -296.511726)
					(mid 282.076545 -296.526605)
					(end 282.061666 -296.562526)
				)
			)
		)
	)
	(zone
		(layers "In1.Cu" "In2.Cu")
		(hatch none 0.5)
		(connect_pads
			(clearance 0)
		)
		(min_thickness 0.25)
		(keepout
			(tracks not_allowed)
			(vias allowed)
			(pads allowed)
			(copperpour not_allowed)
			(footprints allowed)
		)
		(placement
			(enabled no)
			(sheetname "")
		)
		(fill yes
			(thermal_gap 0.5)
			(thermal_bridge_width 0.5)
			(island_removal_mode 0)
		)
		(polygon
			(pts
				(arc
					(start 14.93393 -217.071448)
					(mid 14.948809 -217.107369)
					(end 14.98473 -217.122248)
				)
				(arc
					(start 16.38427 -217.122248)
					(mid 16.420191 -217.107369)
					(end 16.43507 -217.071448)
				)
				(arc
					(start 16.43507 -216.662508)
					(mid 16.420191 -216.626587)
					(end 16.38427 -216.611708)
				)
				(arc
					(start 14.98473 -216.611708)
					(mid 14.948809 -216.626587)
					(end 14.93393 -216.662508)
				)
			)
		)
	)
	(zone
		(layers "In1.Cu" "In2.Cu")
		(hatch none 0.5)
		(connect_pads
			(clearance 0)
		)
		(min_thickness 0.25)
		(keepout
			(tracks not_allowed)
			(vias allowed)
			(pads allowed)
			(copperpour not_allowed)
			(footprints allowed)
		)
		(placement
			(enabled no)
			(sheetname "")
		)
		(fill yes
			(thermal_gap 0.5)
			(thermal_bridge_width 0.5)
			(island_removal_mode 0)
		)
		(polygon
			(pts
				(arc
					(start 7.39013 -240.021364)
					(mid 7.405009 -240.057285)
					(end 7.44093 -240.072164)
				)
				(arc
					(start 8.84047 -240.072164)
					(mid 8.876391 -240.057285)
					(end 8.89127 -240.021364)
				)
				(arc
					(start 8.89127 -239.612424)
					(mid 8.876391 -239.576503)
					(end 8.84047 -239.561624)
				)
				(arc
					(start 7.44093 -239.561624)
					(mid 7.405009 -239.576503)
					(end 7.39013 -239.612424)
				)
			)
		)
	)
	(zone
		(layers "In1.Cu" "In2.Cu")
		(hatch none 0.5)
		(connect_pads
			(clearance 0)
		)
		(min_thickness 0.25)
		(keepout
			(tracks not_allowed)
			(vias allowed)
			(pads allowed)
			(copperpour not_allowed)
			(footprints allowed)
		)
		(placement
			(enabled no)
			(sheetname "")
		)
		(fill yes
			(thermal_gap 0.5)
			(thermal_bridge_width 0.5)
			(island_removal_mode 0)
		)
		(polygon
			(pts
				(arc
					(start 455.365866 -279.9715)
					(mid 455.380745 -280.007421)
					(end 455.416666 -280.0223)
				)
				(arc
					(start 456.816206 -280.0223)
					(mid 456.852127 -280.007421)
					(end 456.867006 -279.9715)
				)
				(arc
					(start 456.867006 -279.56256)
					(mid 456.852127 -279.526639)
					(end 456.816206 -279.51176)
				)
				(arc
					(start 455.416666 -279.51176)
					(mid 455.380745 -279.526639)
					(end 455.365866 -279.56256)
				)
			)
		)
	)
	(zone
		(layers "In1.Cu" "In2.Cu")
		(hatch none 0.5)
		(connect_pads
			(clearance 0)
		)
		(min_thickness 0.25)
		(keepout
			(tracks not_allowed)
			(vias allowed)
			(pads allowed)
			(copperpour not_allowed)
			(footprints allowed)
		)
		(placement
			(enabled no)
			(sheetname "")
		)
		(fill yes
			(thermal_gap 0.5)
			(thermal_bridge_width 0.5)
			(island_removal_mode 0)
		)
		(polygon
			(pts
				(arc
					(start 293.049198 -244.271292)
					(mid 293.064077 -244.307213)
					(end 293.099998 -244.322092)
				)
				(arc
					(start 294.499538 -244.322092)
					(mid 294.535459 -244.307213)
					(end 294.550338 -244.271292)
				)
				(arc
					(start 294.550338 -243.862352)
					(mid 294.535459 -243.826431)
					(end 294.499538 -243.811552)
				)
				(arc
					(start 293.099998 -243.811552)
					(mid 293.064077 -243.826431)
					(end 293.049198 -243.862352)
				)
			)
		)
	)
	(zone
		(layers "In1.Cu" "In2.Cu")
		(hatch none 0.5)
		(connect_pads
			(clearance 0)
		)
		(min_thickness 0.25)
		(keepout
			(tracks not_allowed)
			(vias allowed)
			(pads allowed)
			(copperpour not_allowed)
			(footprints allowed)
		)
		(placement
			(enabled no)
			(sheetname "")
		)
		(fill yes
			(thermal_gap 0.5)
			(thermal_bridge_width 0.5)
			(island_removal_mode 0)
		)
		(polygon
			(pts
				(arc
					(start 188.23813 -198.37146)
					(mid 188.253009 -198.407381)
					(end 188.28893 -198.42226)
				)
				(arc
					(start 189.68847 -198.42226)
					(mid 189.724391 -198.407381)
					(end 189.73927 -198.37146)
				)
				(arc
					(start 189.73927 -197.96252)
					(mid 189.724391 -197.926599)
					(end 189.68847 -197.91172)
				)
				(arc
					(start 188.28893 -197.91172)
					(mid 188.253009 -197.926599)
					(end 188.23813 -197.96252)
				)
			)
		)
	)
	(zone
		(layers "In1.Cu" "In2.Cu")
		(hatch none 0.5)
		(connect_pads
			(clearance 0)
		)
		(min_thickness 0.25)
		(keepout
			(tracks not_allowed)
			(vias allowed)
			(pads allowed)
			(copperpour not_allowed)
			(footprints allowed)
		)
		(placement
			(enabled no)
			(sheetname "")
		)
		(fill yes
			(thermal_gap 0.5)
			(thermal_bridge_width 0.5)
			(island_removal_mode 0)
		)
		(polygon
			(pts
				(arc
					(start 293.049198 -274.871434)
					(mid 293.064077 -274.907355)
					(end 293.099998 -274.922234)
				)
				(arc
					(start 294.499538 -274.922234)
					(mid 294.535459 -274.907355)
					(end 294.550338 -274.871434)
				)
				(arc
					(start 294.550338 -274.462494)
					(mid 294.535459 -274.426573)
					(end 294.499538 -274.411694)
				)
				(arc
					(start 293.099998 -274.411694)
					(mid 293.064077 -274.426573)
					(end 293.049198 -274.462494)
				)
			)
		)
	)
	(zone
		(layers "In1.Cu" "In2.Cu")
		(hatch none 0.5)
		(connect_pads
			(clearance 0)
		)
		(min_thickness 0.25)
		(keepout
			(tracks not_allowed)
			(vias allowed)
			(pads allowed)
			(copperpour not_allowed)
			(footprints allowed)
		)
		(placement
			(enabled no)
			(sheetname "")
		)
		(fill yes
			(thermal_gap 0.5)
			(thermal_bridge_width 0.5)
			(island_removal_mode 0)
		)
		(polygon
			(pts
				(arc
					(start 413.546798 -277.42134)
					(mid 413.561677 -277.457261)
					(end 413.597598 -277.47214)
				)
				(arc
					(start 414.997138 -277.47214)
					(mid 415.033059 -277.457261)
					(end 415.047938 -277.42134)
				)
				(arc
					(start 415.047938 -277.0124)
					(mid 415.033059 -276.976479)
					(end 414.997138 -276.9616)
				)
				(arc
					(start 413.597598 -276.9616)
					(mid 413.561677 -276.976479)
					(end 413.546798 -277.0124)
				)
			)
		)
	)
	(zone
		(layers "In1.Cu" "In2.Cu")
		(hatch none 0.5)
		(connect_pads
			(clearance 0)
		)
		(min_thickness 0.25)
		(keepout
			(tracks not_allowed)
			(vias allowed)
			(pads allowed)
			(copperpour not_allowed)
			(footprints allowed)
		)
		(placement
			(enabled no)
			(sheetname "")
		)
		(fill yes
			(thermal_gap 0.5)
			(thermal_bridge_width 0.5)
			(island_removal_mode 0)
		)
		(polygon
			(pts
				(arc
					(start 49.209198 -260.421374)
					(mid 49.224077 -260.457295)
					(end 49.259998 -260.472174)
				)
				(arc
					(start 50.659538 -260.472174)
					(mid 50.695459 -260.457295)
					(end 50.710338 -260.421374)
				)
				(arc
					(start 50.710338 -260.012434)
					(mid 50.695459 -259.976513)
					(end 50.659538 -259.961634)
				)
				(arc
					(start 49.259998 -259.961634)
					(mid 49.224077 -259.976513)
					(end 49.209198 -260.012434)
				)
			)
		)
	)
	(zone
		(layers "In1.Cu" "In2.Cu")
		(hatch none 0.5)
		(connect_pads
			(clearance 0)
		)
		(min_thickness 0.25)
		(keepout
			(tracks not_allowed)
			(vias allowed)
			(pads allowed)
			(copperpour not_allowed)
			(footprints allowed)
		)
		(placement
			(enabled no)
			(sheetname "")
		)
		(fill yes
			(thermal_gap 0.5)
			(thermal_bridge_width 0.5)
			(island_removal_mode 0)
		)
		(polygon
			(pts
				(arc
					(start 199.881998 -229.821486)
					(mid 199.896877 -229.857407)
					(end 199.932798 -229.872286)
				)
				(arc
					(start 201.332338 -229.872286)
					(mid 201.368259 -229.857407)
					(end 201.383138 -229.821486)
				)
				(arc
					(start 201.383138 -229.412546)
					(mid 201.368259 -229.376625)
					(end 201.332338 -229.361746)
				)
				(arc
					(start 199.932798 -229.361746)
					(mid 199.896877 -229.376625)
					(end 199.881998 -229.412546)
				)
			)
		)
	)
	(zone
		(layers "In1.Cu" "In2.Cu")
		(hatch none 0.5)
		(connect_pads
			(clearance 0)
		)
		(min_thickness 0.25)
		(keepout
			(tracks not_allowed)
			(vias allowed)
			(pads allowed)
			(copperpour not_allowed)
			(footprints allowed)
		)
		(placement
			(enabled no)
			(sheetname "")
		)
		(fill yes
			(thermal_gap 0.5)
			(thermal_bridge_width 0.5)
			(island_removal_mode 0)
		)
		(polygon
			(pts
				(arc
					(start 203.32573 -210.27136)
					(mid 203.340609 -210.307281)
					(end 203.37653 -210.32216)
				)
				(arc
					(start 204.77607 -210.32216)
					(mid 204.811991 -210.307281)
					(end 204.82687 -210.27136)
				)
				(arc
					(start 204.82687 -209.86242)
					(mid 204.811991 -209.826499)
					(end 204.77607 -209.81162)
				)
				(arc
					(start 203.37653 -209.81162)
					(mid 203.340609 -209.826499)
					(end 203.32573 -209.86242)
				)
			)
		)
	)
	(zone
		(layers "In1.Cu" "In2.Cu")
		(hatch none 0.5)
		(connect_pads
			(clearance 0)
		)
		(min_thickness 0.25)
		(keepout
			(tracks not_allowed)
			(vias allowed)
			(pads allowed)
			(copperpour not_allowed)
			(footprints allowed)
		)
		(placement
			(enabled no)
			(sheetname "")
		)
		(fill yes
			(thermal_gap 0.5)
			(thermal_bridge_width 0.5)
			(island_removal_mode 0)
		)
		(polygon
			(pts
				(arc
					(start 7.39013 -206.021432)
					(mid 7.405009 -206.057353)
					(end 7.44093 -206.072232)
				)
				(arc
					(start 8.84047 -206.072232)
					(mid 8.876391 -206.057353)
					(end 8.89127 -206.021432)
				)
				(arc
					(start 8.89127 -205.612492)
					(mid 8.876391 -205.576571)
					(end 8.84047 -205.561692)
				)
				(arc
					(start 7.44093 -205.561692)
					(mid 7.405009 -205.576571)
					(end 7.39013 -205.612492)
				)
			)
		)
	)
	(zone
		(layers "In1.Cu" "In2.Cu")
		(hatch none 0.5)
		(connect_pads
			(clearance 0)
		)
		(min_thickness 0.25)
		(keepout
			(tracks not_allowed)
			(vias allowed)
			(pads allowed)
			(copperpour not_allowed)
			(footprints allowed)
		)
		(placement
			(enabled no)
			(sheetname "")
		)
		(fill yes
			(thermal_gap 0.5)
			(thermal_bridge_width 0.5)
			(island_removal_mode 0)
		)
		(polygon
			(pts
				(arc
					(start 184.794398 -270.621506)
					(mid 184.809277 -270.657427)
					(end 184.845198 -270.672306)
				)
				(arc
					(start 186.244738 -270.672306)
					(mid 186.280659 -270.657427)
					(end 186.295538 -270.621506)
				)
				(arc
					(start 186.295538 -270.212566)
					(mid 186.280659 -270.176645)
					(end 186.244738 -270.161766)
				)
				(arc
					(start 184.845198 -270.161766)
					(mid 184.809277 -270.176645)
					(end 184.794398 -270.212566)
				)
			)
		)
	)
	(zone
		(layers "In1.Cu" "In2.Cu")
		(hatch none 0.5)
		(connect_pads
			(clearance 0)
		)
		(min_thickness 0.25)
		(keepout
			(tracks not_allowed)
			(vias allowed)
			(pads allowed)
			(copperpour not_allowed)
			(footprints allowed)
		)
		(placement
			(enabled no)
			(sheetname "")
		)
		(fill yes
			(thermal_gap 0.5)
			(thermal_bridge_width 0.5)
			(island_removal_mode 0)
		)
		(polygon
			(pts
				(arc
					(start 214.969598 -220.471492)
					(mid 214.984477 -220.507413)
					(end 215.020398 -220.522292)
				)
				(arc
					(start 216.419938 -220.522292)
					(mid 216.455859 -220.507413)
					(end 216.470738 -220.471492)
				)
				(arc
					(start 216.470738 -220.062552)
					(mid 216.455859 -220.026631)
					(end 216.419938 -220.011752)
				)
				(arc
					(start 215.020398 -220.011752)
					(mid 214.984477 -220.026631)
					(end 214.969598 -220.062552)
				)
			)
		)
	)
	(zone
		(layers "In1.Cu" "In2.Cu")
		(hatch none 0.5)
		(connect_pads
			(clearance 0)
		)
		(min_thickness 0.25)
		(keepout
			(tracks not_allowed)
			(vias allowed)
			(pads allowed)
			(copperpour not_allowed)
			(footprints allowed)
		)
		(placement
			(enabled no)
			(sheetname "")
		)
		(fill yes
			(thermal_gap 0.5)
			(thermal_bridge_width 0.5)
			(island_removal_mode 0)
		)
		(polygon
			(pts
				(arc
					(start 304.693066 -298.671488)
					(mid 304.707945 -298.707409)
					(end 304.743866 -298.722288)
				)
				(arc
					(start 306.143406 -298.722288)
					(mid 306.179327 -298.707409)
					(end 306.194206 -298.671488)
				)
				(arc
					(start 306.194206 -298.262548)
					(mid 306.179327 -298.226627)
					(end 306.143406 -298.211748)
				)
				(arc
					(start 304.743866 -298.211748)
					(mid 304.707945 -298.226627)
					(end 304.693066 -298.262548)
				)
			)
		)
	)
	(zone
		(layers "In1.Cu" "In2.Cu")
		(hatch none 0.5)
		(connect_pads
			(clearance 0)
		)
		(min_thickness 0.25)
		(keepout
			(tracks not_allowed)
			(vias allowed)
			(pads allowed)
			(copperpour not_allowed)
			(footprints allowed)
		)
		(placement
			(enabled no)
			(sheetname "")
		)
		(fill yes
			(thermal_gap 0.5)
			(thermal_bridge_width 0.5)
			(island_removal_mode 0)
		)
		(polygon
			(pts
				(arc
					(start 173.15053 -284.221428)
					(mid 173.165409 -284.257349)
					(end 173.20133 -284.272228)
				)
				(arc
					(start 174.60087 -284.272228)
					(mid 174.636791 -284.257349)
					(end 174.65167 -284.221428)
				)
				(arc
					(start 174.65167 -283.812488)
					(mid 174.636791 -283.776567)
					(end 174.60087 -283.761688)
				)
				(arc
					(start 173.20133 -283.761688)
					(mid 173.165409 -283.776567)
					(end 173.15053 -283.812488)
				)
			)
		)
	)
	(zone
		(layers "In1.Cu" "In2.Cu")
		(hatch none 0.5)
		(connect_pads
			(clearance 0)
		)
		(min_thickness 0.25)
		(keepout
			(tracks not_allowed)
			(vias allowed)
			(pads allowed)
			(copperpour not_allowed)
			(footprints allowed)
		)
		(placement
			(enabled no)
			(sheetname "")
		)
		(fill yes
			(thermal_gap 0.5)
			(thermal_bridge_width 0.5)
			(island_removal_mode 0)
		)
		(polygon
			(pts
				(arc
					(start 440.278266 -298.671488)
					(mid 440.293145 -298.707409)
					(end 440.329066 -298.722288)
				)
				(arc
					(start 441.728606 -298.722288)
					(mid 441.764527 -298.707409)
					(end 441.779406 -298.671488)
				)
				(arc
					(start 441.779406 -298.262548)
					(mid 441.764527 -298.226627)
					(end 441.728606 -298.211748)
				)
				(arc
					(start 440.329066 -298.211748)
					(mid 440.293145 -298.226627)
					(end 440.278266 -298.262548)
				)
			)
		)
	)
	(zone
		(layers "In1.Cu" "In2.Cu")
		(hatch none 0.5)
		(connect_pads
			(clearance 0)
		)
		(min_thickness 0.25)
		(keepout
			(tracks not_allowed)
			(vias allowed)
			(pads allowed)
			(copperpour not_allowed)
			(footprints allowed)
		)
		(placement
			(enabled no)
			(sheetname "")
		)
		(fill yes
			(thermal_gap 0.5)
			(thermal_bridge_width 0.5)
			(island_removal_mode 0)
		)
		(polygon
			(pts
				(arc
					(start 52.65293 -282.521406)
					(mid 52.667809 -282.557327)
					(end 52.70373 -282.572206)
				)
				(arc
					(start 54.10327 -282.572206)
					(mid 54.139191 -282.557327)
					(end 54.15407 -282.521406)
				)
				(arc
					(start 54.15407 -282.112466)
					(mid 54.139191 -282.076545)
					(end 54.10327 -282.061666)
				)
				(arc
					(start 52.70373 -282.061666)
					(mid 52.667809 -282.076545)
					(end 52.65293 -282.112466)
				)
			)
		)
	)
	(zone
		(layers "In1.Cu" "In2.Cu")
		(hatch none 0.5)
		(connect_pads
			(clearance 0)
		)
		(min_thickness 0.25)
		(keepout
			(tracks not_allowed)
			(vias allowed)
			(pads allowed)
			(copperpour not_allowed)
			(footprints allowed)
		)
		(placement
			(enabled no)
			(sheetname "")
		)
		(fill yes
			(thermal_gap 0.5)
			(thermal_bridge_width 0.5)
			(island_removal_mode 0)
		)
		(polygon
			(pts
				(arc
					(start 177.250598 -265.52144)
					(mid 177.265477 -265.557361)
					(end 177.301398 -265.57224)
				)
				(arc
					(start 178.700938 -265.57224)
					(mid 178.736859 -265.557361)
					(end 178.751738 -265.52144)
				)
				(arc
					(start 178.751738 -265.1125)
					(mid 178.736859 -265.076579)
					(end 178.700938 -265.0617)
				)
				(arc
					(start 177.301398 -265.0617)
					(mid 177.265477 -265.076579)
					(end 177.250598 -265.1125)
				)
			)
		)
	)
	(zone
		(layers "In1.Cu" "In2.Cu")
		(hatch none 0.5)
		(connect_pads
			(clearance 0)
		)
		(min_thickness 0.25)
		(keepout
			(tracks not_allowed)
			(vias allowed)
			(pads allowed)
			(copperpour not_allowed)
			(footprints allowed)
		)
		(placement
			(enabled no)
			(sheetname "")
		)
		(fill yes
			(thermal_gap 0.5)
			(thermal_bridge_width 0.5)
			(island_removal_mode 0)
		)
		(polygon
			(pts
				(arc
					(start 413.546798 -310.571388)
					(mid 413.561677 -310.607309)
					(end 413.597598 -310.622188)
				)
				(arc
					(start 414.997138 -310.622188)
					(mid 415.033059 -310.607309)
					(end 415.047938 -310.571388)
				)
				(arc
					(start 415.047938 -310.162448)
					(mid 415.033059 -310.126527)
					(end 414.997138 -310.111648)
				)
				(arc
					(start 413.597598 -310.111648)
					(mid 413.561677 -310.126527)
					(end 413.546798 -310.162448)
				)
			)
		)
	)
	(zone
		(layers "In1.Cu" "In2.Cu")
		(hatch none 0.5)
		(connect_pads
			(clearance 0)
		)
		(min_thickness 0.25)
		(keepout
			(tracks not_allowed)
			(vias allowed)
			(pads allowed)
			(copperpour not_allowed)
			(footprints allowed)
		)
		(placement
			(enabled no)
			(sheetname "")
		)
		(fill yes
			(thermal_gap 0.5)
			(thermal_bridge_width 0.5)
			(island_removal_mode 0)
		)
		(polygon
			(pts
				(arc
					(start 440.278266 -205.171548)
					(mid 440.293145 -205.207469)
					(end 440.329066 -205.222348)
				)
				(arc
					(start 441.728606 -205.222348)
					(mid 441.764527 -205.207469)
					(end 441.779406 -205.171548)
				)
				(arc
					(start 441.779406 -204.762608)
					(mid 441.764527 -204.726687)
					(end 441.728606 -204.711808)
				)
				(arc
					(start 440.329066 -204.711808)
					(mid 440.293145 -204.726687)
					(end 440.278266 -204.762608)
				)
			)
		)
	)
	(zone
		(layers "In1.Cu" "In2.Cu")
		(hatch none 0.5)
		(connect_pads
			(clearance 0)
		)
		(min_thickness 0.25)
		(keepout
			(tracks not_allowed)
			(vias allowed)
			(pads allowed)
			(copperpour not_allowed)
			(footprints allowed)
		)
		(placement
			(enabled no)
			(sheetname "")
		)
		(fill yes
			(thermal_gap 0.5)
			(thermal_bridge_width 0.5)
			(island_removal_mode 0)
		)
		(polygon
			(pts
				(arc
					(start 436.178198 -307.171344)
					(mid 436.193077 -307.207265)
					(end 436.228998 -307.222144)
				)
				(arc
					(start 437.628538 -307.222144)
					(mid 437.664459 -307.207265)
					(end 437.679338 -307.171344)
				)
				(arc
					(start 437.679338 -306.762404)
					(mid 437.664459 -306.726483)
					(end 437.628538 -306.711604)
				)
				(arc
					(start 436.228998 -306.711604)
					(mid 436.193077 -306.726483)
					(end 436.178198 -306.762404)
				)
			)
		)
	)
	(zone
		(layers "In1.Cu" "In2.Cu")
		(hatch none 0.5)
		(connect_pads
			(clearance 0)
		)
		(min_thickness 0.25)
		(keepout
			(tracks not_allowed)
			(vias allowed)
			(pads allowed)
			(copperpour not_allowed)
			(footprints allowed)
		)
		(placement
			(enabled no)
			(sheetname "")
		)
		(fill yes
			(thermal_gap 0.5)
			(thermal_bridge_width 0.5)
			(island_removal_mode 0)
		)
		(polygon
			(pts
				(arc
					(start 45.10913 -259.57149)
					(mid 45.124009 -259.607411)
					(end 45.15993 -259.62229)
				)
				(arc
					(start 46.55947 -259.62229)
					(mid 46.595391 -259.607411)
					(end 46.61027 -259.57149)
				)
				(arc
					(start 46.61027 -259.16255)
					(mid 46.595391 -259.126629)
					(end 46.55947 -259.11175)
				)
				(arc
					(start 45.15993 -259.11175)
					(mid 45.124009 -259.126629)
					(end 45.10913 -259.16255)
				)
			)
		)
	)
	(zone
		(layers "In1.Cu" "In2.Cu")
		(hatch none 0.5)
		(connect_pads
			(clearance 0)
		)
		(min_thickness 0.25)
		(keepout
			(tracks not_allowed)
			(vias allowed)
			(pads allowed)
			(copperpour not_allowed)
			(footprints allowed)
		)
		(placement
			(enabled no)
			(sheetname "")
		)
		(fill yes
			(thermal_gap 0.5)
			(thermal_bridge_width 0.5)
			(island_removal_mode 0)
		)
		(polygon
			(pts
				(arc
					(start 277.961598 -288.471356)
					(mid 277.976477 -288.507277)
					(end 278.012398 -288.522156)
				)
				(arc
					(start 279.411938 -288.522156)
					(mid 279.447859 -288.507277)
					(end 279.462738 -288.471356)
				)
				(arc
					(start 279.462738 -288.062416)
					(mid 279.447859 -288.026495)
					(end 279.411938 -288.011616)
				)
				(arc
					(start 278.012398 -288.011616)
					(mid 277.976477 -288.026495)
					(end 277.961598 -288.062416)
				)
			)
		)
	)
	(zone
		(layers "In1.Cu" "In2.Cu")
		(hatch none 0.5)
		(connect_pads
			(clearance 0)
		)
		(min_thickness 0.25)
		(keepout
			(tracks not_allowed)
			(vias allowed)
			(pads allowed)
			(copperpour not_allowed)
			(footprints allowed)
		)
		(placement
			(enabled no)
			(sheetname "")
		)
		(fill yes
			(thermal_gap 0.5)
			(thermal_bridge_width 0.5)
			(island_removal_mode 0)
		)
		(polygon
			(pts
				(arc
					(start 26.577798 -260.421374)
					(mid 26.592677 -260.457295)
					(end 26.628598 -260.472174)
				)
				(arc
					(start 28.028138 -260.472174)
					(mid 28.064059 -260.457295)
					(end 28.078938 -260.421374)
				)
				(arc
					(start 28.078938 -260.012434)
					(mid 28.064059 -259.976513)
					(end 28.028138 -259.961634)
				)
				(arc
					(start 26.628598 -259.961634)
					(mid 26.592677 -259.976513)
					(end 26.577798 -260.012434)
				)
			)
		)
	)
	(zone
		(layers "In1.Cu" "In2.Cu")
		(hatch none 0.5)
		(connect_pads
			(clearance 0)
		)
		(min_thickness 0.25)
		(keepout
			(tracks not_allowed)
			(vias allowed)
			(pads allowed)
			(copperpour not_allowed)
			(footprints allowed)
		)
		(placement
			(enabled no)
			(sheetname "")
		)
		(fill yes
			(thermal_gap 0.5)
			(thermal_bridge_width 0.5)
			(island_removal_mode 0)
		)
		(polygon
			(pts
				(arc
					(start 214.969598 -270.621506)
					(mid 214.984477 -270.657427)
					(end 215.020398 -270.672306)
				)
				(arc
					(start 216.419938 -270.672306)
					(mid 216.455859 -270.657427)
					(end 216.470738 -270.621506)
				)
				(arc
					(start 216.470738 -270.212566)
					(mid 216.455859 -270.176645)
					(end 216.419938 -270.161766)
				)
				(arc
					(start 215.020398 -270.161766)
					(mid 214.984477 -270.176645)
					(end 214.969598 -270.212566)
				)
			)
		)
	)
	(zone
		(layers "In1.Cu" "In2.Cu")
		(hatch none 0.5)
		(connect_pads
			(clearance 0)
		)
		(min_thickness 0.25)
		(keepout
			(tracks not_allowed)
			(vias allowed)
			(pads allowed)
			(copperpour not_allowed)
			(footprints allowed)
		)
		(placement
			(enabled no)
			(sheetname "")
		)
		(fill yes
			(thermal_gap 0.5)
			(thermal_bridge_width 0.5)
			(island_removal_mode 0)
		)
		(polygon
			(pts
				(arc
					(start 169.706798 -296.971466)
					(mid 169.721677 -297.007387)
					(end 169.757598 -297.022266)
				)
				(arc
					(start 171.157138 -297.022266)
					(mid 171.193059 -297.007387)
					(end 171.207938 -296.971466)
				)
				(arc
					(start 171.207938 -296.562526)
					(mid 171.193059 -296.526605)
					(end 171.157138 -296.511726)
				)
				(arc
					(start 169.757598 -296.511726)
					(mid 169.721677 -296.526605)
					(end 169.706798 -296.562526)
				)
			)
		)
	)
	(zone
		(layers "In1.Cu" "In2.Cu")
		(hatch none 0.5)
		(connect_pads
			(clearance 0)
		)
		(min_thickness 0.25)
		(keepout
			(tracks not_allowed)
			(vias allowed)
			(pads allowed)
			(copperpour not_allowed)
			(footprints allowed)
		)
		(placement
			(enabled no)
			(sheetname "")
		)
		(fill yes
			(thermal_gap 0.5)
			(thermal_bridge_width 0.5)
			(island_removal_mode 0)
		)
		(polygon
			(pts
				(arc
					(start 45.10913 -274.871434)
					(mid 45.124009 -274.907355)
					(end 45.15993 -274.922234)
				)
				(arc
					(start 46.55947 -274.922234)
					(mid 46.595391 -274.907355)
					(end 46.61027 -274.871434)
				)
				(arc
					(start 46.61027 -274.462494)
					(mid 46.595391 -274.426573)
					(end 46.55947 -274.411694)
				)
				(arc
					(start 45.15993 -274.411694)
					(mid 45.124009 -274.426573)
					(end 45.10913 -274.462494)
				)
			)
		)
	)
	(zone
		(layers "In1.Cu" "In2.Cu")
		(hatch none 0.5)
		(connect_pads
			(clearance 0)
		)
		(min_thickness 0.25)
		(keepout
			(tracks not_allowed)
			(vias allowed)
			(pads allowed)
			(copperpour not_allowed)
			(footprints allowed)
		)
		(placement
			(enabled no)
			(sheetname "")
		)
		(fill yes
			(thermal_gap 0.5)
			(thermal_bridge_width 0.5)
			(island_removal_mode 0)
		)
		(polygon
			(pts
				(arc
					(start 11.490198 -291.021516)
					(mid 11.505077 -291.057437)
					(end 11.540998 -291.072316)
				)
				(arc
					(start 12.940538 -291.072316)
					(mid 12.976459 -291.057437)
					(end 12.991338 -291.021516)
				)
				(arc
					(start 12.991338 -290.612576)
					(mid 12.976459 -290.576655)
					(end 12.940538 -290.561776)
				)
				(arc
					(start 11.540998 -290.561776)
					(mid 11.505077 -290.576655)
					(end 11.490198 -290.612576)
				)
			)
		)
	)
	(zone
		(layers "In1.Cu" "In2.Cu")
		(hatch none 0.5)
		(connect_pads
			(clearance 0)
		)
		(min_thickness 0.25)
		(keepout
			(tracks not_allowed)
			(vias allowed)
			(pads allowed)
			(copperpour not_allowed)
			(footprints allowed)
		)
		(placement
			(enabled no)
			(sheetname "")
		)
		(fill yes
			(thermal_gap 0.5)
			(thermal_bridge_width 0.5)
			(island_removal_mode 0)
		)
		(polygon
			(pts
				(arc
					(start 41.665398 -239.17148)
					(mid 41.680277 -239.207401)
					(end 41.716198 -239.22228)
				)
				(arc
					(start 43.115738 -239.22228)
					(mid 43.151659 -239.207401)
					(end 43.166538 -239.17148)
				)
				(arc
					(start 43.166538 -238.76254)
					(mid 43.151659 -238.726619)
					(end 43.115738 -238.71174)
				)
				(arc
					(start 41.716198 -238.71174)
					(mid 41.680277 -238.726619)
					(end 41.665398 -238.76254)
				)
			)
		)
	)
	(zone
		(layers "In1.Cu" "In2.Cu")
		(hatch none 0.5)
		(connect_pads
			(clearance 0)
		)
		(min_thickness 0.25)
		(keepout
			(tracks not_allowed)
			(vias allowed)
			(pads allowed)
			(copperpour not_allowed)
			(footprints allowed)
		)
		(placement
			(enabled no)
			(sheetname "")
		)
		(fill yes
			(thermal_gap 0.5)
			(thermal_bridge_width 0.5)
			(island_removal_mode 0)
		)
		(polygon
			(pts
				(arc
					(start 417.646866 -279.9715)
					(mid 417.661745 -280.007421)
					(end 417.697666 -280.0223)
				)
				(arc
					(start 419.097206 -280.0223)
					(mid 419.133127 -280.007421)
					(end 419.148006 -279.9715)
				)
				(arc
					(start 419.148006 -279.56256)
					(mid 419.133127 -279.526639)
					(end 419.097206 -279.51176)
				)
				(arc
					(start 417.697666 -279.51176)
					(mid 417.661745 -279.526639)
					(end 417.646866 -279.56256)
				)
			)
		)
	)
	(zone
		(layers "In1.Cu" "In2.Cu")
		(hatch none 0.5)
		(connect_pads
			(clearance 0)
		)
		(min_thickness 0.25)
		(keepout
			(tracks not_allowed)
			(vias allowed)
			(pads allowed)
			(copperpour not_allowed)
			(footprints allowed)
		)
		(placement
			(enabled no)
			(sheetname "")
		)
		(fill yes
			(thermal_gap 0.5)
			(thermal_bridge_width 0.5)
			(island_removal_mode 0)
		)
		(polygon
			(pts
				(arc
					(start 184.794398 -306.32146)
					(mid 184.809277 -306.357381)
					(end 184.845198 -306.37226)
				)
				(arc
					(start 186.244738 -306.37226)
					(mid 186.280659 -306.357381)
					(end 186.295538 -306.32146)
				)
				(arc
					(start 186.295538 -305.91252)
					(mid 186.280659 -305.876599)
					(end 186.244738 -305.86172)
				)
				(arc
					(start 184.845198 -305.86172)
					(mid 184.809277 -305.876599)
					(end 184.794398 -305.91252)
				)
			)
		)
	)
	(zone
		(layers "In1.Cu" "In2.Cu")
		(hatch none 0.5)
		(connect_pads
			(clearance 0)
		)
		(min_thickness 0.25)
		(keepout
			(tracks not_allowed)
			(vias allowed)
			(pads allowed)
			(copperpour not_allowed)
			(footprints allowed)
		)
		(placement
			(enabled no)
			(sheetname "")
		)
		(fill yes
			(thermal_gap 0.5)
			(thermal_bridge_width 0.5)
			(island_removal_mode 0)
		)
		(polygon
			(pts
				(arc
					(start 199.881998 -298.671488)
					(mid 199.896877 -298.707409)
					(end 199.932798 -298.722288)
				)
				(arc
					(start 201.332338 -298.722288)
					(mid 201.368259 -298.707409)
					(end 201.383138 -298.671488)
				)
				(arc
					(start 201.383138 -298.262548)
					(mid 201.368259 -298.226627)
					(end 201.332338 -298.211748)
				)
				(arc
					(start 199.932798 -298.211748)
					(mid 199.896877 -298.226627)
					(end 199.881998 -298.262548)
				)
			)
		)
	)
	(zone
		(layers "In1.Cu" "In2.Cu")
		(hatch none 0.5)
		(connect_pads
			(clearance 0)
		)
		(min_thickness 0.25)
		(keepout
			(tracks not_allowed)
			(vias allowed)
			(pads allowed)
			(copperpour not_allowed)
			(footprints allowed)
		)
		(placement
			(enabled no)
			(sheetname "")
		)
		(fill yes
			(thermal_gap 0.5)
			(thermal_bridge_width 0.5)
			(island_removal_mode 0)
		)
		(polygon
			(pts
				(arc
					(start 45.10913 -264.671302)
					(mid 45.124009 -264.707223)
					(end 45.15993 -264.722102)
				)
				(arc
					(start 46.55947 -264.722102)
					(mid 46.595391 -264.707223)
					(end 46.61027 -264.671302)
				)
				(arc
					(start 46.61027 -264.262362)
					(mid 46.595391 -264.226441)
					(end 46.55947 -264.211562)
				)
				(arc
					(start 45.15993 -264.211562)
					(mid 45.124009 -264.226441)
					(end 45.10913 -264.262362)
				)
			)
		)
	)
	(zone
		(layers "In1.Cu" "In2.Cu")
		(hatch none 0.5)
		(connect_pads
			(clearance 0)
		)
		(min_thickness 0.25)
		(keepout
			(tracks not_allowed)
			(vias allowed)
			(pads allowed)
			(copperpour not_allowed)
			(footprints allowed)
		)
		(placement
			(enabled no)
			(sheetname "")
		)
		(fill yes
			(thermal_gap 0.5)
			(thermal_bridge_width 0.5)
			(island_removal_mode 0)
		)
		(polygon
			(pts
				(arc
					(start 285.505398 -221.321376)
					(mid 285.520277 -221.357297)
					(end 285.556198 -221.372176)
				)
				(arc
					(start 286.955738 -221.372176)
					(mid 286.991659 -221.357297)
					(end 287.006538 -221.321376)
				)
				(arc
					(start 287.006538 -220.912436)
					(mid 286.991659 -220.876515)
					(end 286.955738 -220.861636)
				)
				(arc
					(start 285.556198 -220.861636)
					(mid 285.520277 -220.876515)
					(end 285.505398 -220.912436)
				)
			)
		)
	)
	(zone
		(layers "In1.Cu" "In2.Cu")
		(hatch none 0.5)
		(connect_pads
			(clearance 0)
		)
		(min_thickness 0.25)
		(keepout
			(tracks not_allowed)
			(vias allowed)
			(pads allowed)
			(copperpour not_allowed)
			(footprints allowed)
		)
		(placement
			(enabled no)
			(sheetname "")
		)
		(fill yes
			(thermal_gap 0.5)
			(thermal_bridge_width 0.5)
			(island_removal_mode 0)
		)
		(polygon
			(pts
				(arc
					(start 158.06293 -293.571422)
					(mid 158.077809 -293.607343)
					(end 158.11373 -293.622222)
				)
				(arc
					(start 159.51327 -293.622222)
					(mid 159.549191 -293.607343)
					(end 159.56407 -293.571422)
				)
				(arc
					(start 159.56407 -293.162482)
					(mid 159.549191 -293.126561)
					(end 159.51327 -293.111682)
				)
				(arc
					(start 158.11373 -293.111682)
					(mid 158.077809 -293.126561)
					(end 158.06293 -293.162482)
				)
			)
		)
	)
	(zone
		(layers "In1.Cu" "In2.Cu")
		(hatch none 0.5)
		(connect_pads
			(clearance 0)
		)
		(min_thickness 0.25)
		(keepout
			(tracks not_allowed)
			(vias allowed)
			(pads allowed)
			(copperpour not_allowed)
			(footprints allowed)
		)
		(placement
			(enabled no)
			(sheetname "")
		)
		(fill yes
			(thermal_gap 0.5)
			(thermal_bridge_width 0.5)
			(island_removal_mode 0)
		)
		(polygon
			(pts
				(arc
					(start 255.330198 -259.57149)
					(mid 255.345077 -259.607411)
					(end 255.380998 -259.62229)
				)
				(arc
					(start 256.780538 -259.62229)
					(mid 256.816459 -259.607411)
					(end 256.831338 -259.57149)
				)
				(arc
					(start 256.831338 -259.16255)
					(mid 256.816459 -259.126629)
					(end 256.780538 -259.11175)
				)
				(arc
					(start 255.380998 -259.11175)
					(mid 255.345077 -259.126629)
					(end 255.330198 -259.16255)
				)
			)
		)
	)
	(zone
		(layers "In1.Cu" "In2.Cu")
		(hatch none 0.5)
		(connect_pads
			(clearance 0)
		)
		(min_thickness 0.25)
		(keepout
			(tracks not_allowed)
			(vias allowed)
			(pads allowed)
			(copperpour not_allowed)
			(footprints allowed)
		)
		(placement
			(enabled no)
			(sheetname "")
		)
		(fill yes
			(thermal_gap 0.5)
			(thermal_bridge_width 0.5)
			(island_removal_mode 0)
		)
		(polygon
			(pts
				(arc
					(start 45.10913 -200.921366)
					(mid 45.124009 -200.957287)
					(end 45.15993 -200.972166)
				)
				(arc
					(start 46.55947 -200.972166)
					(mid 46.595391 -200.957287)
					(end 46.61027 -200.921366)
				)
				(arc
					(start 46.61027 -200.512426)
					(mid 46.595391 -200.476505)
					(end 46.55947 -200.461626)
				)
				(arc
					(start 45.15993 -200.461626)
					(mid 45.124009 -200.476505)
					(end 45.10913 -200.512426)
				)
			)
		)
	)
	(zone
		(layers "In1.Cu" "In2.Cu")
		(hatch none 0.5)
		(connect_pads
			(clearance 0)
		)
		(min_thickness 0.25)
		(keepout
			(tracks not_allowed)
			(vias allowed)
			(pads allowed)
			(copperpour not_allowed)
			(footprints allowed)
		)
		(placement
			(enabled no)
			(sheetname "")
		)
		(fill yes
			(thermal_gap 0.5)
			(thermal_bridge_width 0.5)
			(island_removal_mode 0)
		)
		(polygon
			(pts
				(arc
					(start 45.10913 -296.121328)
					(mid 45.124009 -296.157249)
					(end 45.15993 -296.172128)
				)
				(arc
					(start 46.55947 -296.172128)
					(mid 46.595391 -296.157249)
					(end 46.61027 -296.121328)
				)
				(arc
					(start 46.61027 -295.712388)
					(mid 46.595391 -295.676467)
					(end 46.55947 -295.661588)
				)
				(arc
					(start 45.15993 -295.661588)
					(mid 45.124009 -295.676467)
					(end 45.10913 -295.712388)
				)
			)
		)
	)
	(zone
		(layers "In1.Cu" "In2.Cu")
		(hatch none 0.5)
		(connect_pads
			(clearance 0)
		)
		(min_thickness 0.25)
		(keepout
			(tracks not_allowed)
			(vias allowed)
			(pads allowed)
			(copperpour not_allowed)
			(footprints allowed)
		)
		(placement
			(enabled no)
			(sheetname "")
		)
		(fill yes
			(thermal_gap 0.5)
			(thermal_bridge_width 0.5)
			(island_removal_mode 0)
		)
		(polygon
			(pts
				(arc
					(start 266.974066 -313.971432)
					(mid 266.988945 -314.007353)
					(end 267.024866 -314.022232)
				)
				(arc
					(start 268.424406 -314.022232)
					(mid 268.460327 -314.007353)
					(end 268.475206 -313.971432)
				)
				(arc
					(start 268.475206 -313.562492)
					(mid 268.460327 -313.526571)
					(end 268.424406 -313.511692)
				)
				(arc
					(start 267.024866 -313.511692)
					(mid 266.988945 -313.526571)
					(end 266.974066 -313.562492)
				)
			)
		)
	)
	(zone
		(layers "In1.Cu" "In2.Cu")
		(hatch none 0.5)
		(connect_pads
			(clearance 0)
		)
		(min_thickness 0.25)
		(keepout
			(tracks not_allowed)
			(vias allowed)
			(pads allowed)
			(copperpour not_allowed)
			(footprints allowed)
		)
		(placement
			(enabled no)
			(sheetname "")
		)
		(fill yes
			(thermal_gap 0.5)
			(thermal_bridge_width 0.5)
			(island_removal_mode 0)
		)
		(polygon
			(pts
				(arc
					(start 312.236866 -285.92145)
					(mid 312.251745 -285.957371)
					(end 312.287666 -285.97225)
				)
				(arc
					(start 313.687206 -285.97225)
					(mid 313.723127 -285.957371)
					(end 313.738006 -285.92145)
				)
				(arc
					(start 313.738006 -285.51251)
					(mid 313.723127 -285.476589)
					(end 313.687206 -285.46171)
				)
				(arc
					(start 312.287666 -285.46171)
					(mid 312.251745 -285.476589)
					(end 312.236866 -285.51251)
				)
			)
		)
	)
	(zone
		(layers "In1.Cu" "In2.Cu")
		(hatch none 0.5)
		(connect_pads
			(clearance 0)
		)
		(min_thickness 0.25)
		(keepout
			(tracks not_allowed)
			(vias allowed)
			(pads allowed)
			(copperpour not_allowed)
			(footprints allowed)
		)
		(placement
			(enabled no)
			(sheetname "")
		)
		(fill yes
			(thermal_gap 0.5)
			(thermal_bridge_width 0.5)
			(island_removal_mode 0)
		)
		(polygon
			(pts
				(arc
					(start 462.909666 -287.621472)
					(mid 462.924545 -287.657393)
					(end 462.960466 -287.672272)
				)
				(arc
					(start 464.360006 -287.672272)
					(mid 464.395927 -287.657393)
					(end 464.410806 -287.621472)
				)
				(arc
					(start 464.410806 -287.212532)
					(mid 464.395927 -287.176611)
					(end 464.360006 -287.161732)
				)
				(arc
					(start 462.960466 -287.161732)
					(mid 462.924545 -287.176611)
					(end 462.909666 -287.212532)
				)
			)
		)
	)
	(zone
		(layers "In1.Cu" "In2.Cu")
		(hatch none 0.5)
		(connect_pads
			(clearance 0)
		)
		(min_thickness 0.25)
		(keepout
			(tracks not_allowed)
			(vias allowed)
			(pads allowed)
			(copperpour not_allowed)
			(footprints allowed)
		)
		(placement
			(enabled no)
			(sheetname "")
		)
		(fill yes
			(thermal_gap 0.5)
			(thermal_bridge_width 0.5)
			(island_removal_mode 0)
		)
		(polygon
			(pts
				(arc
					(start 49.209198 -270.621506)
					(mid 49.224077 -270.657427)
					(end 49.259998 -270.672306)
				)
				(arc
					(start 50.659538 -270.672306)
					(mid 50.695459 -270.657427)
					(end 50.710338 -270.621506)
				)
				(arc
					(start 50.710338 -270.212566)
					(mid 50.695459 -270.176645)
					(end 50.659538 -270.161766)
				)
				(arc
					(start 49.259998 -270.161766)
					(mid 49.224077 -270.176645)
					(end 49.209198 -270.212566)
				)
			)
		)
	)
	(zone
		(layers "In1.Cu" "In2.Cu")
		(hatch none 0.5)
		(connect_pads
			(clearance 0)
		)
		(min_thickness 0.25)
		(keepout
			(tracks not_allowed)
			(vias allowed)
			(pads allowed)
			(copperpour not_allowed)
			(footprints allowed)
		)
		(placement
			(enabled no)
			(sheetname "")
		)
		(fill yes
			(thermal_gap 0.5)
			(thermal_bridge_width 0.5)
			(island_removal_mode 0)
		)
		(polygon
			(pts
				(arc
					(start 52.65293 -307.171344)
					(mid 52.667809 -307.207265)
					(end 52.70373 -307.222144)
				)
				(arc
					(start 54.10327 -307.222144)
					(mid 54.139191 -307.207265)
					(end 54.15407 -307.171344)
				)
				(arc
					(start 54.15407 -306.762404)
					(mid 54.139191 -306.726483)
					(end 54.10327 -306.711604)
				)
				(arc
					(start 52.70373 -306.711604)
					(mid 52.667809 -306.726483)
					(end 52.65293 -306.762404)
				)
			)
		)
	)
	(zone
		(layers "In1.Cu" "In2.Cu")
		(hatch none 0.5)
		(connect_pads
			(clearance 0)
		)
		(min_thickness 0.25)
		(keepout
			(tracks not_allowed)
			(vias allowed)
			(pads allowed)
			(copperpour not_allowed)
			(footprints allowed)
		)
		(placement
			(enabled no)
			(sheetname "")
		)
		(fill yes
			(thermal_gap 0.5)
			(thermal_bridge_width 0.5)
			(island_removal_mode 0)
		)
		(polygon
			(pts
				(arc
					(start 417.646866 -306.32146)
					(mid 417.661745 -306.357381)
					(end 417.697666 -306.37226)
				)
				(arc
					(start 419.097206 -306.37226)
					(mid 419.133127 -306.357381)
					(end 419.148006 -306.32146)
				)
				(arc
					(start 419.148006 -305.91252)
					(mid 419.133127 -305.876599)
					(end 419.097206 -305.86172)
				)
				(arc
					(start 417.697666 -305.86172)
					(mid 417.661745 -305.876599)
					(end 417.646866 -305.91252)
				)
			)
		)
	)
	(zone
		(layers "In1.Cu" "In2.Cu")
		(hatch none 0.5)
		(connect_pads
			(clearance 0)
		)
		(min_thickness 0.25)
		(keepout
			(tracks not_allowed)
			(vias allowed)
			(pads allowed)
			(copperpour not_allowed)
			(footprints allowed)
		)
		(placement
			(enabled no)
			(sheetname "")
		)
		(fill yes
			(thermal_gap 0.5)
			(thermal_bridge_width 0.5)
			(island_removal_mode 0)
		)
		(polygon
			(pts
				(arc
					(start 188.23813 -288.471356)
					(mid 188.253009 -288.507277)
					(end 188.28893 -288.522156)
				)
				(arc
					(start 189.68847 -288.522156)
					(mid 189.724391 -288.507277)
					(end 189.73927 -288.471356)
				)
				(arc
					(start 189.73927 -288.062416)
					(mid 189.724391 -288.026495)
					(end 189.68847 -288.011616)
				)
				(arc
					(start 188.28893 -288.011616)
					(mid 188.253009 -288.026495)
					(end 188.23813 -288.062416)
				)
			)
		)
	)
	(zone
		(layers "In1.Cu" "In2.Cu")
		(hatch none 0.5)
		(connect_pads
			(clearance 0)
		)
		(min_thickness 0.25)
		(keepout
			(tracks not_allowed)
			(vias allowed)
			(pads allowed)
			(copperpour not_allowed)
			(footprints allowed)
		)
		(placement
			(enabled no)
			(sheetname "")
		)
		(fill yes
			(thermal_gap 0.5)
			(thermal_bridge_width 0.5)
			(island_removal_mode 0)
		)
		(polygon
			(pts
				(arc
					(start 177.250598 -233.22153)
					(mid 177.265477 -233.257451)
					(end 177.301398 -233.27233)
				)
				(arc
					(start 178.700938 -233.27233)
					(mid 178.736859 -233.257451)
					(end 178.751738 -233.22153)
				)
				(arc
					(start 178.751738 -232.81259)
					(mid 178.736859 -232.776669)
					(end 178.700938 -232.76179)
				)
				(arc
					(start 177.301398 -232.76179)
					(mid 177.265477 -232.776669)
					(end 177.250598 -232.81259)
				)
			)
		)
	)
	(zone
		(layers "In1.Cu" "In2.Cu")
		(hatch none 0.5)
		(connect_pads
			(clearance 0)
		)
		(min_thickness 0.25)
		(keepout
			(tracks not_allowed)
			(vias allowed)
			(pads allowed)
			(copperpour not_allowed)
			(footprints allowed)
		)
		(placement
			(enabled no)
			(sheetname "")
		)
		(fill yes
			(thermal_gap 0.5)
			(thermal_bridge_width 0.5)
			(island_removal_mode 0)
		)
		(polygon
			(pts
				(arc
					(start 304.693066 -203.471526)
					(mid 304.707945 -203.507447)
					(end 304.743866 -203.522326)
				)
				(arc
					(start 306.143406 -203.522326)
					(mid 306.179327 -203.507447)
					(end 306.194206 -203.471526)
				)
				(arc
					(start 306.194206 -203.062586)
					(mid 306.179327 -203.026665)
					(end 306.143406 -203.011786)
				)
				(arc
					(start 304.743866 -203.011786)
					(mid 304.707945 -203.026665)
					(end 304.693066 -203.062586)
				)
			)
		)
	)
	(zone
		(layers "In1.Cu" "In2.Cu")
		(hatch none 0.5)
		(connect_pads
			(clearance 0)
		)
		(min_thickness 0.25)
		(keepout
			(tracks not_allowed)
			(vias allowed)
			(pads allowed)
			(copperpour not_allowed)
			(footprints allowed)
		)
		(placement
			(enabled no)
			(sheetname "")
		)
		(fill yes
			(thermal_gap 0.5)
			(thermal_bridge_width 0.5)
			(island_removal_mode 0)
		)
		(polygon
			(pts
				(arc
					(start 447.822066 -248.521474)
					(mid 447.836945 -248.557395)
					(end 447.872866 -248.572274)
				)
				(arc
					(start 449.272406 -248.572274)
					(mid 449.308327 -248.557395)
					(end 449.323206 -248.521474)
				)
				(arc
					(start 449.323206 -248.112534)
					(mid 449.308327 -248.076613)
					(end 449.272406 -248.061734)
				)
				(arc
					(start 447.872866 -248.061734)
					(mid 447.836945 -248.076613)
					(end 447.822066 -248.112534)
				)
			)
		)
	)
	(zone
		(layers "In1.Cu" "In2.Cu")
		(hatch none 0.5)
		(connect_pads
			(clearance 0)
		)
		(min_thickness 0.25)
		(keepout
			(tracks not_allowed)
			(vias allowed)
			(pads allowed)
			(copperpour not_allowed)
			(footprints allowed)
		)
		(placement
			(enabled no)
			(sheetname "")
		)
		(fill yes
			(thermal_gap 0.5)
			(thermal_bridge_width 0.5)
			(island_removal_mode 0)
		)
		(polygon
			(pts
				(arc
					(start 274.517866 -234.921298)
					(mid 274.532745 -234.957219)
					(end 274.568666 -234.972098)
				)
				(arc
					(start 275.968206 -234.972098)
					(mid 276.004127 -234.957219)
					(end 276.019006 -234.921298)
				)
				(arc
					(start 276.019006 -234.512358)
					(mid 276.004127 -234.476437)
					(end 275.968206 -234.461558)
				)
				(arc
					(start 274.568666 -234.461558)
					(mid 274.532745 -234.476437)
					(end 274.517866 -234.512358)
				)
			)
		)
	)
	(zone
		(layers "In1.Cu" "In2.Cu")
		(hatch none 0.5)
		(connect_pads
			(clearance 0)
		)
		(min_thickness 0.25)
		(keepout
			(tracks not_allowed)
			(vias allowed)
			(pads allowed)
			(copperpour not_allowed)
			(footprints allowed)
		)
		(placement
			(enabled no)
			(sheetname "")
		)
		(fill yes
			(thermal_gap 0.5)
			(thermal_bridge_width 0.5)
			(island_removal_mode 0)
		)
		(polygon
			(pts
				(arc
					(start 293.049198 -211.971382)
					(mid 293.064077 -212.007303)
					(end 293.099998 -212.022182)
				)
				(arc
					(start 294.499538 -212.022182)
					(mid 294.535459 -212.007303)
					(end 294.550338 -211.971382)
				)
				(arc
					(start 294.550338 -211.562442)
					(mid 294.535459 -211.526521)
					(end 294.499538 -211.511642)
				)
				(arc
					(start 293.099998 -211.511642)
					(mid 293.064077 -211.526521)
					(end 293.049198 -211.562442)
				)
			)
		)
	)
	(zone
		(layers "In1.Cu" "In2.Cu")
		(hatch none 0.5)
		(connect_pads
			(clearance 0)
		)
		(min_thickness 0.25)
		(keepout
			(tracks not_allowed)
			(vias allowed)
			(pads allowed)
			(copperpour not_allowed)
			(footprints allowed)
		)
		(placement
			(enabled no)
			(sheetname "")
		)
		(fill yes
			(thermal_gap 0.5)
			(thermal_bridge_width 0.5)
			(island_removal_mode 0)
		)
		(polygon
			(pts
				(arc
					(start 192.338198 -216.22131)
					(mid 192.353077 -216.257231)
					(end 192.388998 -216.27211)
				)
				(arc
					(start 193.788538 -216.27211)
					(mid 193.824459 -216.257231)
					(end 193.839338 -216.22131)
				)
				(arc
					(start 193.839338 -215.81237)
					(mid 193.824459 -215.776449)
					(end 193.788538 -215.76157)
				)
				(arc
					(start 192.388998 -215.76157)
					(mid 192.353077 -215.776449)
					(end 192.338198 -215.81237)
				)
			)
		)
	)
	(zone
		(layers "In1.Cu" "In2.Cu")
		(hatch none 0.5)
		(connect_pads
			(clearance 0)
		)
		(min_thickness 0.25)
		(keepout
			(tracks not_allowed)
			(vias allowed)
			(pads allowed)
			(copperpour not_allowed)
			(footprints allowed)
		)
		(placement
			(enabled no)
			(sheetname "")
		)
		(fill yes
			(thermal_gap 0.5)
			(thermal_bridge_width 0.5)
			(island_removal_mode 0)
		)
		(polygon
			(pts
				(arc
					(start 410.103066 -245.12143)
					(mid 410.117945 -245.157351)
					(end 410.153866 -245.17223)
				)
				(arc
					(start 411.553406 -245.17223)
					(mid 411.589327 -245.157351)
					(end 411.604206 -245.12143)
				)
				(arc
					(start 411.604206 -244.71249)
					(mid 411.589327 -244.676569)
					(end 411.553406 -244.66169)
				)
				(arc
					(start 410.153866 -244.66169)
					(mid 410.117945 -244.676569)
					(end 410.103066 -244.71249)
				)
			)
		)
	)
	(zone
		(layers "In1.Cu" "In2.Cu")
		(hatch none 0.5)
		(connect_pads
			(clearance 0)
		)
		(min_thickness 0.25)
		(keepout
			(tracks not_allowed)
			(vias allowed)
			(pads allowed)
			(copperpour not_allowed)
			(footprints allowed)
		)
		(placement
			(enabled no)
			(sheetname "")
		)
		(fill yes
			(thermal_gap 0.5)
			(thermal_bridge_width 0.5)
			(island_removal_mode 0)
		)
		(polygon
			(pts
				(arc
					(start 52.65293 -235.771436)
					(mid 52.667809 -235.807357)
					(end 52.70373 -235.822236)
				)
				(arc
					(start 54.10327 -235.822236)
					(mid 54.139191 -235.807357)
					(end 54.15407 -235.771436)
				)
				(arc
					(start 54.15407 -235.362496)
					(mid 54.139191 -235.326575)
					(end 54.10327 -235.311696)
				)
				(arc
					(start 52.70373 -235.311696)
					(mid 52.667809 -235.326575)
					(end 52.65293 -235.362496)
				)
			)
		)
	)
	(zone
		(layers "In1.Cu" "In2.Cu")
		(hatch none 0.5)
		(connect_pads
			(clearance 0)
		)
		(min_thickness 0.25)
		(keepout
			(tracks not_allowed)
			(vias allowed)
			(pads allowed)
			(copperpour not_allowed)
			(footprints allowed)
		)
		(placement
			(enabled no)
			(sheetname "")
		)
		(fill yes
			(thermal_gap 0.5)
			(thermal_bridge_width 0.5)
			(island_removal_mode 0)
		)
		(polygon
			(pts
				(arc
					(start 214.969598 -240.871502)
					(mid 214.984477 -240.907423)
					(end 215.020398 -240.922302)
				)
				(arc
					(start 216.419938 -240.922302)
					(mid 216.455859 -240.907423)
					(end 216.470738 -240.871502)
				)
				(arc
					(start 216.470738 -240.462562)
					(mid 216.455859 -240.426641)
					(end 216.419938 -240.411762)
				)
				(arc
					(start 215.020398 -240.411762)
					(mid 214.984477 -240.426641)
					(end 214.969598 -240.462562)
				)
			)
		)
	)
	(zone
		(layers "In1.Cu" "In2.Cu")
		(hatch none 0.5)
		(connect_pads
			(clearance 0)
		)
		(min_thickness 0.25)
		(keepout
			(tracks not_allowed)
			(vias allowed)
			(pads allowed)
			(copperpour not_allowed)
			(footprints allowed)
		)
		(placement
			(enabled no)
			(sheetname "")
		)
		(fill yes
			(thermal_gap 0.5)
			(thermal_bridge_width 0.5)
			(island_removal_mode 0)
		)
		(polygon
			(pts
				(arc
					(start 293.049198 -230.67137)
					(mid 293.064077 -230.707291)
					(end 293.099998 -230.72217)
				)
				(arc
					(start 294.499538 -230.72217)
					(mid 294.535459 -230.707291)
					(end 294.550338 -230.67137)
				)
				(arc
					(start 294.550338 -230.26243)
					(mid 294.535459 -230.226509)
					(end 294.499538 -230.21163)
				)
				(arc
					(start 293.099998 -230.21163)
					(mid 293.064077 -230.226509)
					(end 293.049198 -230.26243)
				)
			)
		)
	)
	(zone
		(layers "In1.Cu" "In2.Cu")
		(hatch none 0.5)
		(connect_pads
			(clearance 0)
		)
		(min_thickness 0.25)
		(keepout
			(tracks not_allowed)
			(vias allowed)
			(pads allowed)
			(copperpour not_allowed)
			(footprints allowed)
		)
		(placement
			(enabled no)
			(sheetname "")
		)
		(fill yes
			(thermal_gap 0.5)
			(thermal_bridge_width 0.5)
			(island_removal_mode 0)
		)
		(polygon
			(pts
				(arc
					(start 262.873998 -249.371358)
					(mid 262.888877 -249.407279)
					(end 262.924798 -249.422158)
				)
				(arc
					(start 264.324338 -249.422158)
					(mid 264.360259 -249.407279)
					(end 264.375138 -249.371358)
				)
				(arc
					(start 264.375138 -248.962418)
					(mid 264.360259 -248.926497)
					(end 264.324338 -248.911618)
				)
				(arc
					(start 262.924798 -248.911618)
					(mid 262.888877 -248.926497)
					(end 262.873998 -248.962418)
				)
			)
		)
	)
	(zone
		(layers "In1.Cu" "In2.Cu")
		(hatch none 0.5)
		(connect_pads
			(clearance 0)
		)
		(min_thickness 0.25)
		(keepout
			(tracks not_allowed)
			(vias allowed)
			(pads allowed)
			(copperpour not_allowed)
			(footprints allowed)
		)
		(placement
			(enabled no)
			(sheetname "")
		)
		(fill yes
			(thermal_gap 0.5)
			(thermal_bridge_width 0.5)
			(island_removal_mode 0)
		)
		(polygon
			(pts
				(arc
					(start 7.39013 -217.071448)
					(mid 7.405009 -217.107369)
					(end 7.44093 -217.122248)
				)
				(arc
					(start 8.84047 -217.122248)
					(mid 8.876391 -217.107369)
					(end 8.89127 -217.071448)
				)
				(arc
					(start 8.89127 -216.662508)
					(mid 8.876391 -216.626587)
					(end 8.84047 -216.611708)
				)
				(arc
					(start 7.44093 -216.611708)
					(mid 7.405009 -216.626587)
					(end 7.39013 -216.662508)
				)
			)
		)
	)
	(zone
		(layers "In1.Cu" "In2.Cu")
		(hatch none 0.5)
		(connect_pads
			(clearance 0)
		)
		(min_thickness 0.25)
		(keepout
			(tracks not_allowed)
			(vias allowed)
			(pads allowed)
			(copperpour not_allowed)
			(footprints allowed)
		)
		(placement
			(enabled no)
			(sheetname "")
		)
		(fill yes
			(thermal_gap 0.5)
			(thermal_bridge_width 0.5)
			(island_removal_mode 0)
		)
		(polygon
			(pts
				(arc
					(start 312.236866 -309.721504)
					(mid 312.251745 -309.757425)
					(end 312.287666 -309.772304)
				)
				(arc
					(start 313.687206 -309.772304)
					(mid 313.723127 -309.757425)
					(end 313.738006 -309.721504)
				)
				(arc
					(start 313.738006 -309.312564)
					(mid 313.723127 -309.276643)
					(end 313.687206 -309.261764)
				)
				(arc
					(start 312.287666 -309.261764)
					(mid 312.251745 -309.276643)
					(end 312.236866 -309.312564)
				)
			)
		)
	)
	(zone
		(layers "In1.Cu" "In2.Cu")
		(hatch none 0.5)
		(connect_pads
			(clearance 0)
		)
		(min_thickness 0.25)
		(keepout
			(tracks not_allowed)
			(vias allowed)
			(pads allowed)
			(copperpour not_allowed)
			(footprints allowed)
		)
		(placement
			(enabled no)
			(sheetname "")
		)
		(fill yes
			(thermal_gap 0.5)
			(thermal_bridge_width 0.5)
			(island_removal_mode 0)
		)
		(polygon
			(pts
				(arc
					(start 199.881998 -279.9715)
					(mid 199.896877 -280.007421)
					(end 199.932798 -280.0223)
				)
				(arc
					(start 201.332338 -280.0223)
					(mid 201.368259 -280.007421)
					(end 201.383138 -279.9715)
				)
				(arc
					(start 201.383138 -279.56256)
					(mid 201.368259 -279.526639)
					(end 201.332338 -279.51176)
				)
				(arc
					(start 199.932798 -279.51176)
					(mid 199.896877 -279.526639)
					(end 199.881998 -279.56256)
				)
			)
		)
	)
	(zone
		(layers "In1.Cu" "In2.Cu")
		(hatch none 0.5)
		(connect_pads
			(clearance 0)
		)
		(min_thickness 0.25)
		(keepout
			(tracks not_allowed)
			(vias allowed)
			(pads allowed)
			(copperpour not_allowed)
			(footprints allowed)
		)
		(placement
			(enabled no)
			(sheetname "")
		)
		(fill yes
			(thermal_gap 0.5)
			(thermal_bridge_width 0.5)
			(island_removal_mode 0)
		)
		(polygon
			(pts
				(arc
					(start 417.646866 -260.421374)
					(mid 417.661745 -260.457295)
					(end 417.697666 -260.472174)
				)
				(arc
					(start 419.097206 -260.472174)
					(mid 419.133127 -260.457295)
					(end 419.148006 -260.421374)
				)
				(arc
					(start 419.148006 -260.012434)
					(mid 419.133127 -259.976513)
					(end 419.097206 -259.961634)
				)
				(arc
					(start 417.697666 -259.961634)
					(mid 417.661745 -259.976513)
					(end 417.646866 -260.012434)
				)
			)
		)
	)
	(zone
		(layers "In1.Cu" "In2.Cu")
		(hatch none 0.5)
		(connect_pads
			(clearance 0)
		)
		(min_thickness 0.25)
		(keepout
			(tracks not_allowed)
			(vias allowed)
			(pads allowed)
			(copperpour not_allowed)
			(footprints allowed)
		)
		(placement
			(enabled no)
			(sheetname "")
		)
		(fill yes
			(thermal_gap 0.5)
			(thermal_bridge_width 0.5)
			(island_removal_mode 0)
		)
		(polygon
			(pts
				(arc
					(start 41.665398 -285.92145)
					(mid 41.680277 -285.957371)
					(end 41.716198 -285.97225)
				)
				(arc
					(start 43.115738 -285.97225)
					(mid 43.151659 -285.957371)
					(end 43.166538 -285.92145)
				)
				(arc
					(start 43.166538 -285.51251)
					(mid 43.151659 -285.476589)
					(end 43.115738 -285.46171)
				)
				(arc
					(start 41.716198 -285.46171)
					(mid 41.680277 -285.476589)
					(end 41.665398 -285.51251)
				)
			)
		)
	)
	(zone
		(layers "In1.Cu" "In2.Cu")
		(hatch none 0.5)
		(connect_pads
			(clearance 0)
		)
		(min_thickness 0.25)
		(keepout
			(tracks not_allowed)
			(vias allowed)
			(pads allowed)
			(copperpour not_allowed)
			(footprints allowed)
		)
		(placement
			(enabled no)
			(sheetname "")
		)
		(fill yes
			(thermal_gap 0.5)
			(thermal_bridge_width 0.5)
			(island_removal_mode 0)
		)
		(polygon
			(pts
				(arc
					(start 195.78193 -200.071482)
					(mid 195.796809 -200.107403)
					(end 195.83273 -200.122282)
				)
				(arc
					(start 197.23227 -200.122282)
					(mid 197.268191 -200.107403)
					(end 197.28307 -200.071482)
				)
				(arc
					(start 197.28307 -199.662542)
					(mid 197.268191 -199.626621)
					(end 197.23227 -199.611742)
				)
				(arc
					(start 195.83273 -199.611742)
					(mid 195.796809 -199.626621)
					(end 195.78193 -199.662542)
				)
			)
		)
	)
	(zone
		(layers "In1.Cu" "In2.Cu")
		(hatch none 0.5)
		(connect_pads
			(clearance 0)
		)
		(min_thickness 0.25)
		(keepout
			(tracks not_allowed)
			(vias allowed)
			(pads allowed)
			(copperpour not_allowed)
			(footprints allowed)
		)
		(placement
			(enabled no)
			(sheetname "")
		)
		(fill yes
			(thermal_gap 0.5)
			(thermal_bridge_width 0.5)
			(island_removal_mode 0)
		)
		(polygon
			(pts
				(arc
					(start 162.162998 -304.621438)
					(mid 162.177877 -304.657359)
					(end 162.213798 -304.672238)
				)
				(arc
					(start 163.613338 -304.672238)
					(mid 163.649259 -304.657359)
					(end 163.664138 -304.621438)
				)
				(arc
					(start 163.664138 -304.212498)
					(mid 163.649259 -304.176577)
					(end 163.613338 -304.161698)
				)
				(arc
					(start 162.213798 -304.161698)
					(mid 162.177877 -304.176577)
					(end 162.162998 -304.212498)
				)
			)
		)
	)
	(zone
		(layers "In1.Cu" "In2.Cu")
		(hatch none 0.5)
		(connect_pads
			(clearance 0)
		)
		(min_thickness 0.25)
		(keepout
			(tracks not_allowed)
			(vias allowed)
			(pads allowed)
			(copperpour not_allowed)
			(footprints allowed)
		)
		(placement
			(enabled no)
			(sheetname "")
		)
		(fill yes
			(thermal_gap 0.5)
			(thermal_bridge_width 0.5)
			(island_removal_mode 0)
		)
		(polygon
			(pts
				(arc
					(start 195.78193 -274.871434)
					(mid 195.796809 -274.907355)
					(end 195.83273 -274.922234)
				)
				(arc
					(start 197.23227 -274.922234)
					(mid 197.268191 -274.907355)
					(end 197.28307 -274.871434)
				)
				(arc
					(start 197.28307 -274.462494)
					(mid 197.268191 -274.426573)
					(end 197.23227 -274.411694)
				)
				(arc
					(start 195.83273 -274.411694)
					(mid 195.796809 -274.426573)
					(end 195.78193 -274.462494)
				)
			)
		)
	)
	(zone
		(layers "In1.Cu" "In2.Cu")
		(hatch none 0.5)
		(connect_pads
			(clearance 0)
		)
		(min_thickness 0.25)
		(keepout
			(tracks not_allowed)
			(vias allowed)
			(pads allowed)
			(copperpour not_allowed)
			(footprints allowed)
		)
		(placement
			(enabled no)
			(sheetname "")
		)
		(fill yes
			(thermal_gap 0.5)
			(thermal_bridge_width 0.5)
			(island_removal_mode 0)
		)
		(polygon
			(pts
				(arc
					(start 406.002998 -228.121464)
					(mid 406.017877 -228.157385)
					(end 406.053798 -228.172264)
				)
				(arc
					(start 407.453338 -228.172264)
					(mid 407.489259 -228.157385)
					(end 407.504138 -228.121464)
				)
				(arc
					(start 407.504138 -227.712524)
					(mid 407.489259 -227.676603)
					(end 407.453338 -227.661724)
				)
				(arc
					(start 406.053798 -227.661724)
					(mid 406.017877 -227.676603)
					(end 406.002998 -227.712524)
				)
			)
		)
	)
	(zone
		(layers "In1.Cu" "In2.Cu")
		(hatch none 0.5)
		(connect_pads
			(clearance 0)
		)
		(min_thickness 0.25)
		(keepout
			(tracks not_allowed)
			(vias allowed)
			(pads allowed)
			(copperpour not_allowed)
			(footprints allowed)
		)
		(placement
			(enabled no)
			(sheetname "")
		)
		(fill yes
			(thermal_gap 0.5)
			(thermal_bridge_width 0.5)
			(island_removal_mode 0)
		)
		(polygon
			(pts
				(arc
					(start 428.634398 -232.371392)
					(mid 428.649277 -232.407313)
					(end 428.685198 -232.422192)
				)
				(arc
					(start 430.084738 -232.422192)
					(mid 430.120659 -232.407313)
					(end 430.135538 -232.371392)
				)
				(arc
					(start 430.135538 -231.962452)
					(mid 430.120659 -231.926531)
					(end 430.084738 -231.911652)
				)
				(arc
					(start 428.685198 -231.911652)
					(mid 428.649277 -231.926531)
					(end 428.634398 -231.962452)
				)
			)
		)
	)
	(zone
		(layers "In1.Cu" "In2.Cu")
		(hatch none 0.5)
		(connect_pads
			(clearance 0)
		)
		(min_thickness 0.25)
		(keepout
			(tracks not_allowed)
			(vias allowed)
			(pads allowed)
			(copperpour not_allowed)
			(footprints allowed)
		)
		(placement
			(enabled no)
			(sheetname "")
		)
		(fill yes
			(thermal_gap 0.5)
			(thermal_bridge_width 0.5)
			(island_removal_mode 0)
		)
		(polygon
			(pts
				(arc
					(start 458.809598 -268.071346)
					(mid 458.824477 -268.107267)
					(end 458.860398 -268.122146)
				)
				(arc
					(start 460.259938 -268.122146)
					(mid 460.295859 -268.107267)
					(end 460.310738 -268.071346)
				)
				(arc
					(start 460.310738 -267.662406)
					(mid 460.295859 -267.626485)
					(end 460.259938 -267.611606)
				)
				(arc
					(start 458.860398 -267.611606)
					(mid 458.824477 -267.626485)
					(end 458.809598 -267.662406)
				)
			)
		)
	)
	(zone
		(layers "In1.Cu" "In2.Cu")
		(hatch none 0.5)
		(connect_pads
			(clearance 0)
		)
		(min_thickness 0.25)
		(keepout
			(tracks not_allowed)
			(vias allowed)
			(pads allowed)
			(copperpour not_allowed)
			(footprints allowed)
		)
		(placement
			(enabled no)
			(sheetname "")
		)
		(fill yes
			(thermal_gap 0.5)
			(thermal_bridge_width 0.5)
			(island_removal_mode 0)
		)
		(polygon
			(pts
				(arc
					(start 195.78193 -280.821384)
					(mid 195.796809 -280.857305)
					(end 195.83273 -280.872184)
				)
				(arc
					(start 197.23227 -280.872184)
					(mid 197.268191 -280.857305)
					(end 197.28307 -280.821384)
				)
				(arc
					(start 197.28307 -280.412444)
					(mid 197.268191 -280.376523)
					(end 197.23227 -280.361644)
				)
				(arc
					(start 195.83273 -280.361644)
					(mid 195.796809 -280.376523)
					(end 195.78193 -280.412444)
				)
			)
		)
	)
	(zone
		(layers "In1.Cu" "In2.Cu")
		(hatch none 0.5)
		(connect_pads
			(clearance 0)
		)
		(min_thickness 0.25)
		(keepout
			(tracks not_allowed)
			(vias allowed)
			(pads allowed)
			(copperpour not_allowed)
			(footprints allowed)
		)
		(placement
			(enabled no)
			(sheetname "")
		)
		(fill yes
			(thermal_gap 0.5)
			(thermal_bridge_width 0.5)
			(island_removal_mode 0)
		)
		(polygon
			(pts
				(arc
					(start 188.23813 -235.771436)
					(mid 188.253009 -235.807357)
					(end 188.28893 -235.822236)
				)
				(arc
					(start 189.68847 -235.822236)
					(mid 189.724391 -235.807357)
					(end 189.73927 -235.771436)
				)
				(arc
					(start 189.73927 -235.362496)
					(mid 189.724391 -235.326575)
					(end 189.68847 -235.311696)
				)
				(arc
					(start 188.28893 -235.311696)
					(mid 188.253009 -235.326575)
					(end 188.23813 -235.362496)
				)
			)
		)
	)
	(zone
		(layers "In1.Cu" "In2.Cu")
		(hatch none 0.5)
		(connect_pads
			(clearance 0)
		)
		(min_thickness 0.25)
		(keepout
			(tracks not_allowed)
			(vias allowed)
			(pads allowed)
			(copperpour not_allowed)
			(footprints allowed)
		)
		(placement
			(enabled no)
			(sheetname "")
		)
		(fill yes
			(thermal_gap 0.5)
			(thermal_bridge_width 0.5)
			(island_removal_mode 0)
		)
		(polygon
			(pts
				(arc
					(start 19.033998 -250.221496)
					(mid 19.048877 -250.257417)
					(end 19.084798 -250.272296)
				)
				(arc
					(start 20.484338 -250.272296)
					(mid 20.520259 -250.257417)
					(end 20.535138 -250.221496)
				)
				(arc
					(start 20.535138 -249.812556)
					(mid 20.520259 -249.776635)
					(end 20.484338 -249.761756)
				)
				(arc
					(start 19.084798 -249.761756)
					(mid 19.048877 -249.776635)
					(end 19.033998 -249.812556)
				)
			)
		)
	)
	(zone
		(layers "In1.Cu" "In2.Cu")
		(hatch none 0.5)
		(connect_pads
			(clearance 0)
		)
		(min_thickness 0.25)
		(keepout
			(tracks not_allowed)
			(vias allowed)
			(pads allowed)
			(copperpour not_allowed)
			(footprints allowed)
		)
		(placement
			(enabled no)
			(sheetname "")
		)
		(fill yes
			(thermal_gap 0.5)
			(thermal_bridge_width 0.5)
			(island_removal_mode 0)
		)
		(polygon
			(pts
				(arc
					(start 406.002998 -305.471322)
					(mid 406.017877 -305.507243)
					(end 406.053798 -305.522122)
				)
				(arc
					(start 407.453338 -305.522122)
					(mid 407.489259 -305.507243)
					(end 407.504138 -305.471322)
				)
				(arc
					(start 407.504138 -305.062382)
					(mid 407.489259 -305.026461)
					(end 407.453338 -305.011582)
				)
				(arc
					(start 406.053798 -305.011582)
					(mid 406.017877 -305.026461)
					(end 406.002998 -305.062382)
				)
			)
		)
	)
	(zone
		(layers "In1.Cu" "In2.Cu")
		(hatch none 0.5)
		(connect_pads
			(clearance 0)
		)
		(min_thickness 0.25)
		(keepout
			(tracks not_allowed)
			(vias allowed)
			(pads allowed)
			(copperpour not_allowed)
			(footprints allowed)
		)
		(placement
			(enabled no)
			(sheetname "")
		)
		(fill yes
			(thermal_gap 0.5)
			(thermal_bridge_width 0.5)
			(island_removal_mode 0)
		)
		(polygon
			(pts
				(arc
					(start 14.93393 -234.071414)
					(mid 14.948809 -234.107335)
					(end 14.98473 -234.122214)
				)
				(arc
					(start 16.38427 -234.122214)
					(mid 16.420191 -234.107335)
					(end 16.43507 -234.071414)
				)
				(arc
					(start 16.43507 -233.662474)
					(mid 16.420191 -233.626553)
					(end 16.38427 -233.611674)
				)
				(arc
					(start 14.98473 -233.611674)
					(mid 14.948809 -233.626553)
					(end 14.93393 -233.662474)
				)
			)
		)
	)
	(zone
		(layers "In1.Cu" "In2.Cu")
		(hatch none 0.5)
		(connect_pads
			(clearance 0)
		)
		(min_thickness 0.25)
		(keepout
			(tracks not_allowed)
			(vias allowed)
			(pads allowed)
			(copperpour not_allowed)
			(footprints allowed)
		)
		(placement
			(enabled no)
			(sheetname "")
		)
		(fill yes
			(thermal_gap 0.5)
			(thermal_bridge_width 0.5)
			(island_removal_mode 0)
		)
		(polygon
			(pts
				(arc
					(start 447.822066 -203.471526)
					(mid 447.836945 -203.507447)
					(end 447.872866 -203.522326)
				)
				(arc
					(start 449.272406 -203.522326)
					(mid 449.308327 -203.507447)
					(end 449.323206 -203.471526)
				)
				(arc
					(start 449.323206 -203.062586)
					(mid 449.308327 -203.026665)
					(end 449.272406 -203.011786)
				)
				(arc
					(start 447.872866 -203.011786)
					(mid 447.836945 -203.026665)
					(end 447.822066 -203.062586)
				)
			)
		)
	)
	(zone
		(layers "In1.Cu" "In2.Cu")
		(hatch none 0.5)
		(connect_pads
			(clearance 0)
		)
		(min_thickness 0.25)
		(keepout
			(tracks not_allowed)
			(vias allowed)
			(pads allowed)
			(copperpour not_allowed)
			(footprints allowed)
		)
		(placement
			(enabled no)
			(sheetname "")
		)
		(fill yes
			(thermal_gap 0.5)
			(thermal_bridge_width 0.5)
			(island_removal_mode 0)
		)
		(polygon
			(pts
				(arc
					(start 19.033998 -302.921416)
					(mid 19.048877 -302.957337)
					(end 19.084798 -302.972216)
				)
				(arc
					(start 20.484338 -302.972216)
					(mid 20.520259 -302.957337)
					(end 20.535138 -302.921416)
				)
				(arc
					(start 20.535138 -302.512476)
					(mid 20.520259 -302.476555)
					(end 20.484338 -302.461676)
				)
				(arc
					(start 19.084798 -302.461676)
					(mid 19.048877 -302.476555)
					(end 19.033998 -302.512476)
				)
			)
		)
	)
	(zone
		(layers "In1.Cu" "In2.Cu")
		(hatch none 0.5)
		(connect_pads
			(clearance 0)
		)
		(min_thickness 0.25)
		(keepout
			(tracks not_allowed)
			(vias allowed)
			(pads allowed)
			(copperpour not_allowed)
			(footprints allowed)
		)
		(placement
			(enabled no)
			(sheetname "")
		)
		(fill yes
			(thermal_gap 0.5)
			(thermal_bridge_width 0.5)
			(island_removal_mode 0)
		)
		(polygon
			(pts
				(arc
					(start 165.60673 -204.32141)
					(mid 165.621609 -204.357331)
					(end 165.65753 -204.37221)
				)
				(arc
					(start 167.05707 -204.37221)
					(mid 167.092991 -204.357331)
					(end 167.10787 -204.32141)
				)
				(arc
					(start 167.10787 -203.91247)
					(mid 167.092991 -203.876549)
					(end 167.05707 -203.86167)
				)
				(arc
					(start 165.65753 -203.86167)
					(mid 165.621609 -203.876549)
					(end 165.60673 -203.91247)
				)
			)
		)
	)
	(zone
		(layers "In1.Cu" "In2.Cu")
		(hatch none 0.5)
		(connect_pads
			(clearance 0)
		)
		(min_thickness 0.25)
		(keepout
			(tracks not_allowed)
			(vias allowed)
			(pads allowed)
			(copperpour not_allowed)
			(footprints allowed)
		)
		(placement
			(enabled no)
			(sheetname "")
		)
		(fill yes
			(thermal_gap 0.5)
			(thermal_bridge_width 0.5)
			(island_removal_mode 0)
		)
		(polygon
			(pts
				(arc
					(start 270.417798 -251.07138)
					(mid 270.432677 -251.107301)
					(end 270.468598 -251.12218)
				)
				(arc
					(start 271.868138 -251.12218)
					(mid 271.904059 -251.107301)
					(end 271.918938 -251.07138)
				)
				(arc
					(start 271.918938 -250.66244)
					(mid 271.904059 -250.626519)
					(end 271.868138 -250.61164)
				)
				(arc
					(start 270.468598 -250.61164)
					(mid 270.432677 -250.626519)
					(end 270.417798 -250.66244)
				)
			)
		)
	)
	(zone
		(layers "In1.Cu" "In2.Cu")
		(hatch none 0.5)
		(connect_pads
			(clearance 0)
		)
		(min_thickness 0.25)
		(keepout
			(tracks not_allowed)
			(vias allowed)
			(pads allowed)
			(copperpour not_allowed)
			(footprints allowed)
		)
		(placement
			(enabled no)
			(sheetname "")
		)
		(fill yes
			(thermal_gap 0.5)
			(thermal_bridge_width 0.5)
			(island_removal_mode 0)
		)
		(polygon
			(pts
				(arc
					(start 421.090598 -293.571422)
					(mid 421.105477 -293.607343)
					(end 421.141398 -293.622222)
				)
				(arc
					(start 422.540938 -293.622222)
					(mid 422.576859 -293.607343)
					(end 422.591738 -293.571422)
				)
				(arc
					(start 422.591738 -293.162482)
					(mid 422.576859 -293.126561)
					(end 422.540938 -293.111682)
				)
				(arc
					(start 421.141398 -293.111682)
					(mid 421.105477 -293.126561)
					(end 421.090598 -293.162482)
				)
			)
		)
	)
	(zone
		(layers "In1.Cu" "In2.Cu")
		(hatch none 0.5)
		(connect_pads
			(clearance 0)
		)
		(min_thickness 0.25)
		(keepout
			(tracks not_allowed)
			(vias allowed)
			(pads allowed)
			(copperpour not_allowed)
			(footprints allowed)
		)
		(placement
			(enabled no)
			(sheetname "")
		)
		(fill yes
			(thermal_gap 0.5)
			(thermal_bridge_width 0.5)
			(island_removal_mode 0)
		)
		(polygon
			(pts
				(arc
					(start 22.47773 -235.771436)
					(mid 22.492609 -235.807357)
					(end 22.52853 -235.822236)
				)
				(arc
					(start 23.92807 -235.822236)
					(mid 23.963991 -235.807357)
					(end 23.97887 -235.771436)
				)
				(arc
					(start 23.97887 -235.362496)
					(mid 23.963991 -235.326575)
					(end 23.92807 -235.311696)
				)
				(arc
					(start 22.52853 -235.311696)
					(mid 22.492609 -235.326575)
					(end 22.47773 -235.362496)
				)
			)
		)
	)
	(zone
		(layers "In1.Cu" "In2.Cu")
		(hatch none 0.5)
		(connect_pads
			(clearance 0)
		)
		(min_thickness 0.25)
		(keepout
			(tracks not_allowed)
			(vias allowed)
			(pads allowed)
			(copperpour not_allowed)
			(footprints allowed)
		)
		(placement
			(enabled no)
			(sheetname "")
		)
		(fill yes
			(thermal_gap 0.5)
			(thermal_bridge_width 0.5)
			(island_removal_mode 0)
		)
		(polygon
			(pts
				(arc
					(start 165.60673 -286.771334)
					(mid 165.621609 -286.807255)
					(end 165.65753 -286.822134)
				)
				(arc
					(start 167.05707 -286.822134)
					(mid 167.092991 -286.807255)
					(end 167.10787 -286.771334)
				)
				(arc
					(start 167.10787 -286.362394)
					(mid 167.092991 -286.326473)
					(end 167.05707 -286.311594)
				)
				(arc
					(start 165.65753 -286.311594)
					(mid 165.621609 -286.326473)
					(end 165.60673 -286.362394)
				)
			)
		)
	)
	(zone
		(layers "In1.Cu" "In2.Cu")
		(hatch none 0.5)
		(connect_pads
			(clearance 0)
		)
		(min_thickness 0.25)
		(keepout
			(tracks not_allowed)
			(vias allowed)
			(pads allowed)
			(copperpour not_allowed)
			(footprints allowed)
		)
		(placement
			(enabled no)
			(sheetname "")
		)
		(fill yes
			(thermal_gap 0.5)
			(thermal_bridge_width 0.5)
			(island_removal_mode 0)
		)
		(polygon
			(pts
				(arc
					(start 417.646866 -291.021516)
					(mid 417.661745 -291.057437)
					(end 417.697666 -291.072316)
				)
				(arc
					(start 419.097206 -291.072316)
					(mid 419.133127 -291.057437)
					(end 419.148006 -291.021516)
				)
				(arc
					(start 419.148006 -290.612576)
					(mid 419.133127 -290.576655)
					(end 419.097206 -290.561776)
				)
				(arc
					(start 417.697666 -290.561776)
					(mid 417.661745 -290.576655)
					(end 417.646866 -290.612576)
				)
			)
		)
	)
	(zone
		(layers "In1.Cu" "In2.Cu")
		(hatch none 0.5)
		(connect_pads
			(clearance 0)
		)
		(min_thickness 0.25)
		(keepout
			(tracks not_allowed)
			(vias allowed)
			(pads allowed)
			(copperpour not_allowed)
			(footprints allowed)
		)
		(placement
			(enabled no)
			(sheetname "")
		)
		(fill yes
			(thermal_gap 0.5)
			(thermal_bridge_width 0.5)
			(island_removal_mode 0)
		)
		(polygon
			(pts
				(arc
					(start 56.752998 -205.171548)
					(mid 56.767877 -205.207469)
					(end 56.803798 -205.222348)
				)
				(arc
					(start 58.203338 -205.222348)
					(mid 58.239259 -205.207469)
					(end 58.254138 -205.171548)
				)
				(arc
					(start 58.254138 -204.762608)
					(mid 58.239259 -204.726687)
					(end 58.203338 -204.711808)
				)
				(arc
					(start 56.803798 -204.711808)
					(mid 56.767877 -204.726687)
					(end 56.752998 -204.762608)
				)
			)
		)
	)
	(zone
		(layers "In1.Cu" "In2.Cu")
		(hatch none 0.5)
		(connect_pads
			(clearance 0)
		)
		(min_thickness 0.25)
		(keepout
			(tracks not_allowed)
			(vias allowed)
			(pads allowed)
			(copperpour not_allowed)
			(footprints allowed)
		)
		(placement
			(enabled no)
			(sheetname "")
		)
		(fill yes
			(thermal_gap 0.5)
			(thermal_bridge_width 0.5)
			(island_removal_mode 0)
		)
		(polygon
			(pts
				(arc
					(start 451.265798 -202.621388)
					(mid 451.280677 -202.657309)
					(end 451.316598 -202.672188)
				)
				(arc
					(start 452.716138 -202.672188)
					(mid 452.752059 -202.657309)
					(end 452.766938 -202.621388)
				)
				(arc
					(start 452.766938 -202.212448)
					(mid 452.752059 -202.176527)
					(end 452.716138 -202.161648)
				)
				(arc
					(start 451.316598 -202.161648)
					(mid 451.280677 -202.176527)
					(end 451.265798 -202.212448)
				)
			)
		)
	)
	(zone
		(layers "In1.Cu" "In2.Cu")
		(hatch none 0.5)
		(connect_pads
			(clearance 0)
		)
		(min_thickness 0.25)
		(keepout
			(tracks not_allowed)
			(vias allowed)
			(pads allowed)
			(copperpour not_allowed)
			(footprints allowed)
		)
		(placement
			(enabled no)
			(sheetname "")
		)
		(fill yes
			(thermal_gap 0.5)
			(thermal_bridge_width 0.5)
			(island_removal_mode 0)
		)
		(polygon
			(pts
				(arc
					(start 180.69433 -302.921416)
					(mid 180.709209 -302.957337)
					(end 180.74513 -302.972216)
				)
				(arc
					(start 182.14467 -302.972216)
					(mid 182.180591 -302.957337)
					(end 182.19547 -302.921416)
				)
				(arc
					(start 182.19547 -302.512476)
					(mid 182.180591 -302.476555)
					(end 182.14467 -302.461676)
				)
				(arc
					(start 180.74513 -302.461676)
					(mid 180.709209 -302.476555)
					(end 180.69433 -302.512476)
				)
			)
		)
	)
	(zone
		(layers "In1.Cu" "In2.Cu")
		(hatch none 0.5)
		(connect_pads
			(clearance 0)
		)
		(min_thickness 0.25)
		(keepout
			(tracks not_allowed)
			(vias allowed)
			(pads allowed)
			(copperpour not_allowed)
			(footprints allowed)
		)
		(placement
			(enabled no)
			(sheetname "")
		)
		(fill yes
			(thermal_gap 0.5)
			(thermal_bridge_width 0.5)
			(island_removal_mode 0)
		)
		(polygon
			(pts
				(arc
					(start 184.794398 -234.921298)
					(mid 184.809277 -234.957219)
					(end 184.845198 -234.972098)
				)
				(arc
					(start 186.244738 -234.972098)
					(mid 186.280659 -234.957219)
					(end 186.295538 -234.921298)
				)
				(arc
					(start 186.295538 -234.512358)
					(mid 186.280659 -234.476437)
					(end 186.244738 -234.461558)
				)
				(arc
					(start 184.845198 -234.461558)
					(mid 184.809277 -234.476437)
					(end 184.794398 -234.512358)
				)
			)
		)
	)
	(zone
		(layers "In1.Cu" "In2.Cu")
		(hatch none 0.5)
		(connect_pads
			(clearance 0)
		)
		(min_thickness 0.25)
		(keepout
			(tracks not_allowed)
			(vias allowed)
			(pads allowed)
			(copperpour not_allowed)
			(footprints allowed)
		)
		(placement
			(enabled no)
			(sheetname "")
		)
		(fill yes
			(thermal_gap 0.5)
			(thermal_bridge_width 0.5)
			(island_removal_mode 0)
		)
		(polygon
			(pts
				(arc
					(start 440.278266 -287.621472)
					(mid 440.293145 -287.657393)
					(end 440.329066 -287.672272)
				)
				(arc
					(start 441.728606 -287.672272)
					(mid 441.764527 -287.657393)
					(end 441.779406 -287.621472)
				)
				(arc
					(start 441.779406 -287.212532)
					(mid 441.764527 -287.176611)
					(end 441.728606 -287.161732)
				)
				(arc
					(start 440.329066 -287.161732)
					(mid 440.293145 -287.176611)
					(end 440.278266 -287.212532)
				)
			)
		)
	)
	(zone
		(layers "In1.Cu" "In2.Cu")
		(hatch none 0.5)
		(connect_pads
			(clearance 0)
		)
		(min_thickness 0.25)
		(keepout
			(tracks not_allowed)
			(vias allowed)
			(pads allowed)
			(copperpour not_allowed)
			(footprints allowed)
		)
		(placement
			(enabled no)
			(sheetname "")
		)
		(fill yes
			(thermal_gap 0.5)
			(thermal_bridge_width 0.5)
			(island_removal_mode 0)
		)
		(polygon
			(pts
				(arc
					(start 64.296798 -245.12143)
					(mid 64.311677 -245.157351)
					(end 64.347598 -245.17223)
				)
				(arc
					(start 65.747138 -245.17223)
					(mid 65.783059 -245.157351)
					(end 65.797938 -245.12143)
				)
				(arc
					(start 65.797938 -244.71249)
					(mid 65.783059 -244.676569)
					(end 65.747138 -244.66169)
				)
				(arc
					(start 64.347598 -244.66169)
					(mid 64.311677 -244.676569)
					(end 64.296798 -244.71249)
				)
			)
		)
	)
	(zone
		(layers "In1.Cu" "In2.Cu")
		(hatch none 0.5)
		(connect_pads
			(clearance 0)
		)
		(min_thickness 0.25)
		(keepout
			(tracks not_allowed)
			(vias allowed)
			(pads allowed)
			(copperpour not_allowed)
			(footprints allowed)
		)
		(placement
			(enabled no)
			(sheetname "")
		)
		(fill yes
			(thermal_gap 0.5)
			(thermal_bridge_width 0.5)
			(island_removal_mode 0)
		)
		(polygon
			(pts
				(arc
					(start 297.149266 -227.271326)
					(mid 297.164145 -227.307247)
					(end 297.200066 -227.322126)
				)
				(arc
					(start 298.599606 -227.322126)
					(mid 298.635527 -227.307247)
					(end 298.650406 -227.271326)
				)
				(arc
					(start 298.650406 -226.862386)
					(mid 298.635527 -226.826465)
					(end 298.599606 -226.811586)
				)
				(arc
					(start 297.200066 -226.811586)
					(mid 297.164145 -226.826465)
					(end 297.149266 -226.862386)
				)
			)
		)
	)
	(zone
		(layers "In1.Cu" "In2.Cu")
		(hatch none 0.5)
		(connect_pads
			(clearance 0)
		)
		(min_thickness 0.25)
		(keepout
			(tracks not_allowed)
			(vias allowed)
			(pads allowed)
			(copperpour not_allowed)
			(footprints allowed)
		)
		(placement
			(enabled no)
			(sheetname "")
		)
		(fill yes
			(thermal_gap 0.5)
			(thermal_bridge_width 0.5)
			(island_removal_mode 0)
		)
		(polygon
			(pts
				(arc
					(start 304.693066 -263.821418)
					(mid 304.707945 -263.857339)
					(end 304.743866 -263.872218)
				)
				(arc
					(start 306.143406 -263.872218)
					(mid 306.179327 -263.857339)
					(end 306.194206 -263.821418)
				)
				(arc
					(start 306.194206 -263.412478)
					(mid 306.179327 -263.376557)
					(end 306.143406 -263.361678)
				)
				(arc
					(start 304.743866 -263.361678)
					(mid 304.707945 -263.376557)
					(end 304.693066 -263.412478)
				)
			)
		)
	)
	(zone
		(layers "In1.Cu" "In2.Cu")
		(hatch none 0.5)
		(connect_pads
			(clearance 0)
		)
		(min_thickness 0.25)
		(keepout
			(tracks not_allowed)
			(vias allowed)
			(pads allowed)
			(copperpour not_allowed)
			(footprints allowed)
		)
		(placement
			(enabled no)
			(sheetname "")
		)
		(fill yes
			(thermal_gap 0.5)
			(thermal_bridge_width 0.5)
			(island_removal_mode 0)
		)
		(polygon
			(pts
				(arc
					(start 451.265798 -291.8714)
					(mid 451.280677 -291.907321)
					(end 451.316598 -291.9222)
				)
				(arc
					(start 452.716138 -291.9222)
					(mid 452.752059 -291.907321)
					(end 452.766938 -291.8714)
				)
				(arc
					(start 452.766938 -291.46246)
					(mid 452.752059 -291.426539)
					(end 452.716138 -291.41166)
				)
				(arc
					(start 451.316598 -291.41166)
					(mid 451.280677 -291.426539)
					(end 451.265798 -291.46246)
				)
			)
		)
	)
	(zone
		(layers "In1.Cu" "In2.Cu")
		(hatch none 0.5)
		(connect_pads
			(clearance 0)
		)
		(min_thickness 0.25)
		(keepout
			(tracks not_allowed)
			(vias allowed)
			(pads allowed)
			(copperpour not_allowed)
			(footprints allowed)
		)
		(placement
			(enabled no)
			(sheetname "")
		)
		(fill yes
			(thermal_gap 0.5)
			(thermal_bridge_width 0.5)
			(island_removal_mode 0)
		)
		(polygon
			(pts
				(arc
					(start 49.209198 -228.121464)
					(mid 49.224077 -228.157385)
					(end 49.259998 -228.172264)
				)
				(arc
					(start 50.659538 -228.172264)
					(mid 50.695459 -228.157385)
					(end 50.710338 -228.121464)
				)
				(arc
					(start 50.710338 -227.712524)
					(mid 50.695459 -227.676603)
					(end 50.659538 -227.661724)
				)
				(arc
					(start 49.259998 -227.661724)
					(mid 49.224077 -227.676603)
					(end 49.209198 -227.712524)
				)
			)
		)
	)
	(zone
		(layers "In1.Cu" "In2.Cu")
		(hatch none 0.5)
		(connect_pads
			(clearance 0)
		)
		(min_thickness 0.25)
		(keepout
			(tracks not_allowed)
			(vias allowed)
			(pads allowed)
			(copperpour not_allowed)
			(footprints allowed)
		)
		(placement
			(enabled no)
			(sheetname "")
		)
		(fill yes
			(thermal_gap 0.5)
			(thermal_bridge_width 0.5)
			(island_removal_mode 0)
		)
		(polygon
			(pts
				(arc
					(start 447.822066 -278.271478)
					(mid 447.836945 -278.307399)
					(end 447.872866 -278.322278)
				)
				(arc
					(start 449.272406 -278.322278)
					(mid 449.308327 -278.307399)
					(end 449.323206 -278.271478)
				)
				(arc
					(start 449.323206 -277.862538)
					(mid 449.308327 -277.826617)
					(end 449.272406 -277.811738)
				)
				(arc
					(start 447.872866 -277.811738)
					(mid 447.836945 -277.826617)
					(end 447.822066 -277.862538)
				)
			)
		)
	)
	(zone
		(layers "In1.Cu" "In2.Cu")
		(hatch none 0.5)
		(connect_pads
			(clearance 0)
		)
		(min_thickness 0.25)
		(keepout
			(tracks not_allowed)
			(vias allowed)
			(pads allowed)
			(copperpour not_allowed)
			(footprints allowed)
		)
		(placement
			(enabled no)
			(sheetname "")
		)
		(fill yes
			(thermal_gap 0.5)
			(thermal_bridge_width 0.5)
			(island_removal_mode 0)
		)
		(polygon
			(pts
				(arc
					(start 162.162998 -291.021516)
					(mid 162.177877 -291.057437)
					(end 162.213798 -291.072316)
				)
				(arc
					(start 163.613338 -291.072316)
					(mid 163.649259 -291.057437)
					(end 163.664138 -291.021516)
				)
				(arc
					(start 163.664138 -290.612576)
					(mid 163.649259 -290.576655)
					(end 163.613338 -290.561776)
				)
				(arc
					(start 162.213798 -290.561776)
					(mid 162.177877 -290.576655)
					(end 162.162998 -290.612576)
				)
			)
		)
	)
	(zone
		(layers "In1.Cu" "In2.Cu")
		(hatch none 0.5)
		(connect_pads
			(clearance 0)
		)
		(min_thickness 0.25)
		(keepout
			(tracks not_allowed)
			(vias allowed)
			(pads allowed)
			(copperpour not_allowed)
			(footprints allowed)
		)
		(placement
			(enabled no)
			(sheetname "")
		)
		(fill yes
			(thermal_gap 0.5)
			(thermal_bridge_width 0.5)
			(island_removal_mode 0)
		)
		(polygon
			(pts
				(arc
					(start 19.033998 -201.771504)
					(mid 19.048877 -201.807425)
					(end 19.084798 -201.822304)
				)
				(arc
					(start 20.484338 -201.822304)
					(mid 20.520259 -201.807425)
					(end 20.535138 -201.771504)
				)
				(arc
					(start 20.535138 -201.362564)
					(mid 20.520259 -201.326643)
					(end 20.484338 -201.311764)
				)
				(arc
					(start 19.084798 -201.311764)
					(mid 19.048877 -201.326643)
					(end 19.033998 -201.362564)
				)
			)
		)
	)
	(zone
		(layers "In1.Cu" "In2.Cu")
		(hatch none 0.5)
		(connect_pads
			(clearance 0)
		)
		(min_thickness 0.25)
		(keepout
			(tracks not_allowed)
			(vias allowed)
			(pads allowed)
			(copperpour not_allowed)
			(footprints allowed)
		)
		(placement
			(enabled no)
			(sheetname "")
		)
		(fill yes
			(thermal_gap 0.5)
			(thermal_bridge_width 0.5)
			(island_removal_mode 0)
		)
		(polygon
			(pts
				(arc
					(start 451.265798 -302.921416)
					(mid 451.280677 -302.957337)
					(end 451.316598 -302.972216)
				)
				(arc
					(start 452.716138 -302.972216)
					(mid 452.752059 -302.957337)
					(end 452.766938 -302.921416)
				)
				(arc
					(start 452.766938 -302.512476)
					(mid 452.752059 -302.476555)
					(end 452.716138 -302.461676)
				)
				(arc
					(start 451.316598 -302.461676)
					(mid 451.280677 -302.476555)
					(end 451.265798 -302.512476)
				)
			)
		)
	)
	(zone
		(layers "In1.Cu" "In2.Cu")
		(hatch none 0.5)
		(connect_pads
			(clearance 0)
		)
		(min_thickness 0.25)
		(keepout
			(tracks not_allowed)
			(vias allowed)
			(pads allowed)
			(copperpour not_allowed)
			(footprints allowed)
		)
		(placement
			(enabled no)
			(sheetname "")
		)
		(fill yes
			(thermal_gap 0.5)
			(thermal_bridge_width 0.5)
			(island_removal_mode 0)
		)
		(polygon
			(pts
				(arc
					(start 432.734466 -284.221428)
					(mid 432.749345 -284.257349)
					(end 432.785266 -284.272228)
				)
				(arc
					(start 434.184806 -284.272228)
					(mid 434.220727 -284.257349)
					(end 434.235606 -284.221428)
				)
				(arc
					(start 434.235606 -283.812488)
					(mid 434.220727 -283.776567)
					(end 434.184806 -283.761688)
				)
				(arc
					(start 432.785266 -283.761688)
					(mid 432.749345 -283.776567)
					(end 432.734466 -283.812488)
				)
			)
		)
	)
	(zone
		(layers "In1.Cu" "In2.Cu")
		(hatch none 0.5)
		(connect_pads
			(clearance 0)
		)
		(min_thickness 0.25)
		(keepout
			(tracks not_allowed)
			(vias allowed)
			(pads allowed)
			(copperpour not_allowed)
			(footprints allowed)
		)
		(placement
			(enabled no)
			(sheetname "")
		)
		(fill yes
			(thermal_gap 0.5)
			(thermal_bridge_width 0.5)
			(island_removal_mode 0)
		)
		(polygon
			(pts
				(arc
					(start 7.39013 -271.47139)
					(mid 7.405009 -271.507311)
					(end 7.44093 -271.52219)
				)
				(arc
					(start 8.84047 -271.52219)
					(mid 8.876391 -271.507311)
					(end 8.89127 -271.47139)
				)
				(arc
					(start 8.89127 -271.06245)
					(mid 8.876391 -271.026529)
					(end 8.84047 -271.01165)
				)
				(arc
					(start 7.44093 -271.01165)
					(mid 7.405009 -271.026529)
					(end 7.39013 -271.06245)
				)
			)
		)
	)
	(zone
		(layers "In1.Cu" "In2.Cu")
		(hatch none 0.5)
		(connect_pads
			(clearance 0)
		)
		(min_thickness 0.25)
		(keepout
			(tracks not_allowed)
			(vias allowed)
			(pads allowed)
			(copperpour not_allowed)
			(footprints allowed)
		)
		(placement
			(enabled no)
			(sheetname "")
		)
		(fill yes
			(thermal_gap 0.5)
			(thermal_bridge_width 0.5)
			(island_removal_mode 0)
		)
		(polygon
			(pts
				(arc
					(start 188.23813 -268.071346)
					(mid 188.253009 -268.107267)
					(end 188.28893 -268.122146)
				)
				(arc
					(start 189.68847 -268.122146)
					(mid 189.724391 -268.107267)
					(end 189.73927 -268.071346)
				)
				(arc
					(start 189.73927 -267.662406)
					(mid 189.724391 -267.626485)
					(end 189.68847 -267.611606)
				)
				(arc
					(start 188.28893 -267.611606)
					(mid 188.253009 -267.626485)
					(end 188.23813 -267.662406)
				)
			)
		)
	)
	(zone
		(layers "In1.Cu" "In2.Cu")
		(hatch none 0.5)
		(connect_pads
			(clearance 0)
		)
		(min_thickness 0.25)
		(keepout
			(tracks not_allowed)
			(vias allowed)
			(pads allowed)
			(copperpour not_allowed)
			(footprints allowed)
		)
		(placement
			(enabled no)
			(sheetname "")
		)
		(fill yes
			(thermal_gap 0.5)
			(thermal_bridge_width 0.5)
			(island_removal_mode 0)
		)
		(polygon
			(pts
				(arc
					(start 259.430266 -268.921484)
					(mid 259.445145 -268.957405)
					(end 259.481066 -268.972284)
				)
				(arc
					(start 260.880606 -268.972284)
					(mid 260.916527 -268.957405)
					(end 260.931406 -268.921484)
				)
				(arc
					(start 260.931406 -268.512544)
					(mid 260.916527 -268.476623)
					(end 260.880606 -268.461744)
				)
				(arc
					(start 259.481066 -268.461744)
					(mid 259.445145 -268.476623)
					(end 259.430266 -268.512544)
				)
			)
		)
	)
	(zone
		(layers "In1.Cu" "In2.Cu")
		(hatch none 0.5)
		(connect_pads
			(clearance 0)
		)
		(min_thickness 0.25)
		(keepout
			(tracks not_allowed)
			(vias allowed)
			(pads allowed)
			(copperpour not_allowed)
			(footprints allowed)
		)
		(placement
			(enabled no)
			(sheetname "")
		)
		(fill yes
			(thermal_gap 0.5)
			(thermal_bridge_width 0.5)
			(island_removal_mode 0)
		)
		(polygon
			(pts
				(arc
					(start 158.06293 -204.32141)
					(mid 158.077809 -204.357331)
					(end 158.11373 -204.37221)
				)
				(arc
					(start 159.51327 -204.37221)
					(mid 159.549191 -204.357331)
					(end 159.56407 -204.32141)
				)
				(arc
					(start 159.56407 -203.91247)
					(mid 159.549191 -203.876549)
					(end 159.51327 -203.86167)
				)
				(arc
					(start 158.11373 -203.86167)
					(mid 158.077809 -203.876549)
					(end 158.06293 -203.91247)
				)
			)
		)
	)
	(zone
		(layers "In1.Cu" "In2.Cu")
		(hatch none 0.5)
		(connect_pads
			(clearance 0)
		)
		(min_thickness 0.25)
		(keepout
			(tracks not_allowed)
			(vias allowed)
			(pads allowed)
			(copperpour not_allowed)
			(footprints allowed)
		)
		(placement
			(enabled no)
			(sheetname "")
		)
		(fill yes
			(thermal_gap 0.5)
			(thermal_bridge_width 0.5)
			(island_removal_mode 0)
		)
		(polygon
			(pts
				(arc
					(start 162.162998 -267.221462)
					(mid 162.177877 -267.257383)
					(end 162.213798 -267.272262)
				)
				(arc
					(start 163.613338 -267.272262)
					(mid 163.649259 -267.257383)
					(end 163.664138 -267.221462)
				)
				(arc
					(start 163.664138 -266.812522)
					(mid 163.649259 -266.776601)
					(end 163.613338 -266.761722)
				)
				(arc
					(start 162.213798 -266.761722)
					(mid 162.177877 -266.776601)
					(end 162.162998 -266.812522)
				)
			)
		)
	)
	(zone
		(layers "In1.Cu" "In2.Cu")
		(hatch none 0.5)
		(connect_pads
			(clearance 0)
		)
		(min_thickness 0.25)
		(keepout
			(tracks not_allowed)
			(vias allowed)
			(pads allowed)
			(copperpour not_allowed)
			(footprints allowed)
		)
		(placement
			(enabled no)
			(sheetname "")
		)
		(fill yes
			(thermal_gap 0.5)
			(thermal_bridge_width 0.5)
			(island_removal_mode 0)
		)
		(polygon
			(pts
				(arc
					(start 300.592998 -297.82135)
					(mid 300.607877 -297.857271)
					(end 300.643798 -297.87215)
				)
				(arc
					(start 302.043338 -297.87215)
					(mid 302.079259 -297.857271)
					(end 302.094138 -297.82135)
				)
				(arc
					(start 302.094138 -297.41241)
					(mid 302.079259 -297.376489)
					(end 302.043338 -297.36161)
				)
				(arc
					(start 300.643798 -297.36161)
					(mid 300.607877 -297.376489)
					(end 300.592998 -297.41241)
				)
			)
		)
	)
	(zone
		(layers "In1.Cu" "In2.Cu")
		(hatch none 0.5)
		(connect_pads
			(clearance 0)
		)
		(min_thickness 0.25)
		(keepout
			(tracks not_allowed)
			(vias allowed)
			(pads allowed)
			(copperpour not_allowed)
			(footprints allowed)
		)
		(placement
			(enabled no)
			(sheetname "")
		)
		(fill yes
			(thermal_gap 0.5)
			(thermal_bridge_width 0.5)
			(island_removal_mode 0)
		)
		(polygon
			(pts
				(arc
					(start 428.634398 -202.621388)
					(mid 428.649277 -202.657309)
					(end 428.685198 -202.672188)
				)
				(arc
					(start 430.084738 -202.672188)
					(mid 430.120659 -202.657309)
					(end 430.135538 -202.621388)
				)
				(arc
					(start 430.135538 -202.212448)
					(mid 430.120659 -202.176527)
					(end 430.084738 -202.161648)
				)
				(arc
					(start 428.685198 -202.161648)
					(mid 428.649277 -202.176527)
					(end 428.634398 -202.212448)
				)
			)
		)
	)
	(zone
		(layers "In1.Cu" "In2.Cu")
		(hatch none 0.5)
		(connect_pads
			(clearance 0)
		)
		(min_thickness 0.25)
		(keepout
			(tracks not_allowed)
			(vias allowed)
			(pads allowed)
			(copperpour not_allowed)
			(footprints allowed)
		)
		(placement
			(enabled no)
			(sheetname "")
		)
		(fill yes
			(thermal_gap 0.5)
			(thermal_bridge_width 0.5)
			(island_removal_mode 0)
		)
		(polygon
			(pts
				(arc
					(start 22.47773 -249.371358)
					(mid 22.492609 -249.407279)
					(end 22.52853 -249.422158)
				)
				(arc
					(start 23.92807 -249.422158)
					(mid 23.963991 -249.407279)
					(end 23.97887 -249.371358)
				)
				(arc
					(start 23.97887 -248.962418)
					(mid 23.963991 -248.926497)
					(end 23.92807 -248.911618)
				)
				(arc
					(start 22.52853 -248.911618)
					(mid 22.492609 -248.926497)
					(end 22.47773 -248.962418)
				)
			)
		)
	)
	(zone
		(layers "In1.Cu" "In2.Cu")
		(hatch none 0.5)
		(connect_pads
			(clearance 0)
		)
		(min_thickness 0.25)
		(keepout
			(tracks not_allowed)
			(vias allowed)
			(pads allowed)
			(copperpour not_allowed)
			(footprints allowed)
		)
		(placement
			(enabled no)
			(sheetname "")
		)
		(fill yes
			(thermal_gap 0.5)
			(thermal_bridge_width 0.5)
			(island_removal_mode 0)
		)
		(polygon
			(pts
				(arc
					(start 413.546798 -262.971534)
					(mid 413.561677 -263.007455)
					(end 413.597598 -263.022334)
				)
				(arc
					(start 414.997138 -263.022334)
					(mid 415.033059 -263.007455)
					(end 415.047938 -262.971534)
				)
				(arc
					(start 415.047938 -262.562594)
					(mid 415.033059 -262.526673)
					(end 414.997138 -262.511794)
				)
				(arc
					(start 413.597598 -262.511794)
					(mid 413.561677 -262.526673)
					(end 413.546798 -262.562594)
				)
			)
		)
	)
	(zone
		(layers "In1.Cu" "In2.Cu")
		(hatch none 0.5)
		(connect_pads
			(clearance 0)
		)
		(min_thickness 0.25)
		(keepout
			(tracks not_allowed)
			(vias allowed)
			(pads allowed)
			(copperpour not_allowed)
			(footprints allowed)
		)
		(placement
			(enabled no)
			(sheetname "")
		)
		(fill yes
			(thermal_gap 0.5)
			(thermal_bridge_width 0.5)
			(island_removal_mode 0)
		)
		(polygon
			(pts
				(arc
					(start 203.32573 -293.571422)
					(mid 203.340609 -293.607343)
					(end 203.37653 -293.622222)
				)
				(arc
					(start 204.77607 -293.622222)
					(mid 204.811991 -293.607343)
					(end 204.82687 -293.571422)
				)
				(arc
					(start 204.82687 -293.162482)
					(mid 204.811991 -293.126561)
					(end 204.77607 -293.111682)
				)
				(arc
					(start 203.37653 -293.111682)
					(mid 203.340609 -293.126561)
					(end 203.32573 -293.162482)
				)
			)
		)
	)
	(zone
		(layers "In1.Cu" "In2.Cu")
		(hatch none 0.5)
		(connect_pads
			(clearance 0)
		)
		(min_thickness 0.25)
		(keepout
			(tracks not_allowed)
			(vias allowed)
			(pads allowed)
			(copperpour not_allowed)
			(footprints allowed)
		)
		(placement
			(enabled no)
			(sheetname "")
		)
		(fill yes
			(thermal_gap 0.5)
			(thermal_bridge_width 0.5)
			(island_removal_mode 0)
		)
		(polygon
			(pts
				(arc
					(start 451.265798 -297.82135)
					(mid 451.280677 -297.857271)
					(end 451.316598 -297.87215)
				)
				(arc
					(start 452.716138 -297.87215)
					(mid 452.752059 -297.857271)
					(end 452.766938 -297.82135)
				)
				(arc
					(start 452.766938 -297.41241)
					(mid 452.752059 -297.376489)
					(end 452.716138 -297.36161)
				)
				(arc
					(start 451.316598 -297.36161)
					(mid 451.280677 -297.376489)
					(end 451.265798 -297.41241)
				)
			)
		)
	)
	(zone
		(layers "In1.Cu" "In2.Cu")
		(hatch none 0.5)
		(connect_pads
			(clearance 0)
		)
		(min_thickness 0.25)
		(keepout
			(tracks not_allowed)
			(vias allowed)
			(pads allowed)
			(copperpour not_allowed)
			(footprints allowed)
		)
		(placement
			(enabled no)
			(sheetname "")
		)
		(fill yes
			(thermal_gap 0.5)
			(thermal_bridge_width 0.5)
			(island_removal_mode 0)
		)
		(polygon
			(pts
				(arc
					(start 312.236866 -199.221344)
					(mid 312.251745 -199.257265)
					(end 312.287666 -199.272144)
				)
				(arc
					(start 313.687206 -199.272144)
					(mid 313.723127 -199.257265)
					(end 313.738006 -199.221344)
				)
				(arc
					(start 313.738006 -198.812404)
					(mid 313.723127 -198.776483)
					(end 313.687206 -198.761604)
				)
				(arc
					(start 312.287666 -198.761604)
					(mid 312.251745 -198.776483)
					(end 312.236866 -198.812404)
				)
			)
		)
	)
	(zone
		(layers "In1.Cu" "In2.Cu")
		(hatch none 0.5)
		(connect_pads
			(clearance 0)
		)
		(min_thickness 0.25)
		(keepout
			(tracks not_allowed)
			(vias allowed)
			(pads allowed)
			(copperpour not_allowed)
			(footprints allowed)
		)
		(placement
			(enabled no)
			(sheetname "")
		)
		(fill yes
			(thermal_gap 0.5)
			(thermal_bridge_width 0.5)
			(island_removal_mode 0)
		)
		(polygon
			(pts
				(arc
					(start 440.278266 -309.721504)
					(mid 440.293145 -309.757425)
					(end 440.329066 -309.772304)
				)
				(arc
					(start 441.728606 -309.772304)
					(mid 441.764527 -309.757425)
					(end 441.779406 -309.721504)
				)
				(arc
					(start 441.779406 -309.312564)
					(mid 441.764527 -309.276643)
					(end 441.728606 -309.261764)
				)
				(arc
					(start 440.329066 -309.261764)
					(mid 440.293145 -309.276643)
					(end 440.278266 -309.312564)
				)
			)
		)
	)
	(zone
		(layers "In1.Cu" "In2.Cu")
		(hatch none 0.5)
		(connect_pads
			(clearance 0)
		)
		(min_thickness 0.25)
		(keepout
			(tracks not_allowed)
			(vias allowed)
			(pads allowed)
			(copperpour not_allowed)
			(footprints allowed)
		)
		(placement
			(enabled no)
			(sheetname "")
		)
		(fill yes
			(thermal_gap 0.5)
			(thermal_bridge_width 0.5)
			(island_removal_mode 0)
		)
		(polygon
			(pts
				(arc
					(start 7.39013 -245.971314)
					(mid 7.405009 -246.007235)
					(end 7.44093 -246.022114)
				)
				(arc
					(start 8.84047 -246.022114)
					(mid 8.876391 -246.007235)
					(end 8.89127 -245.971314)
				)
				(arc
					(start 8.89127 -245.562374)
					(mid 8.876391 -245.526453)
					(end 8.84047 -245.511574)
				)
				(arc
					(start 7.44093 -245.511574)
					(mid 7.405009 -245.526453)
					(end 7.39013 -245.562374)
				)
			)
		)
	)
	(zone
		(layers "In1.Cu" "In2.Cu")
		(hatch none 0.5)
		(connect_pads
			(clearance 0)
		)
		(min_thickness 0.25)
		(keepout
			(tracks not_allowed)
			(vias allowed)
			(pads allowed)
			(copperpour not_allowed)
			(footprints allowed)
		)
		(placement
			(enabled no)
			(sheetname "")
		)
		(fill yes
			(thermal_gap 0.5)
			(thermal_bridge_width 0.5)
			(island_removal_mode 0)
		)
		(polygon
			(pts
				(arc
					(start 11.490198 -218.77147)
					(mid 11.505077 -218.807391)
					(end 11.540998 -218.82227)
				)
				(arc
					(start 12.940538 -218.82227)
					(mid 12.976459 -218.807391)
					(end 12.991338 -218.77147)
				)
				(arc
					(start 12.991338 -218.36253)
					(mid 12.976459 -218.326609)
					(end 12.940538 -218.31173)
				)
				(arc
					(start 11.540998 -218.31173)
					(mid 11.505077 -218.326609)
					(end 11.490198 -218.36253)
				)
			)
		)
	)
	(zone
		(layers "In1.Cu" "In2.Cu")
		(hatch none 0.5)
		(connect_pads
			(clearance 0)
		)
		(min_thickness 0.25)
		(keepout
			(tracks not_allowed)
			(vias allowed)
			(pads allowed)
			(copperpour not_allowed)
			(footprints allowed)
		)
		(placement
			(enabled no)
			(sheetname "")
		)
		(fill yes
			(thermal_gap 0.5)
			(thermal_bridge_width 0.5)
			(island_removal_mode 0)
		)
		(polygon
			(pts
				(arc
					(start 289.605466 -268.921484)
					(mid 289.620345 -268.957405)
					(end 289.656266 -268.972284)
				)
				(arc
					(start 291.055806 -268.972284)
					(mid 291.091727 -268.957405)
					(end 291.106606 -268.921484)
				)
				(arc
					(start 291.106606 -268.512544)
					(mid 291.091727 -268.476623)
					(end 291.055806 -268.461744)
				)
				(arc
					(start 289.656266 -268.461744)
					(mid 289.620345 -268.476623)
					(end 289.605466 -268.512544)
				)
			)
		)
	)
	(zone
		(layers "In1.Cu" "In2.Cu")
		(hatch none 0.5)
		(connect_pads
			(clearance 0)
		)
		(min_thickness 0.25)
		(keepout
			(tracks not_allowed)
			(vias allowed)
			(pads allowed)
			(copperpour not_allowed)
			(footprints allowed)
		)
		(placement
			(enabled no)
			(sheetname "")
		)
		(fill yes
			(thermal_gap 0.5)
			(thermal_bridge_width 0.5)
			(island_removal_mode 0)
		)
		(polygon
			(pts
				(arc
					(start 30.02153 -316.521338)
					(mid 30.036409 -316.557259)
					(end 30.07233 -316.572138)
				)
				(arc
					(start 31.47187 -316.572138)
					(mid 31.507791 -316.557259)
					(end 31.52267 -316.521338)
				)
				(arc
					(start 31.52267 -316.112398)
					(mid 31.507791 -316.076477)
					(end 31.47187 -316.061598)
				)
				(arc
					(start 30.07233 -316.061598)
					(mid 30.036409 -316.076477)
					(end 30.02153 -316.112398)
				)
			)
		)
	)
	(zone
		(layers "In1.Cu" "In2.Cu")
		(hatch none 0.5)
		(connect_pads
			(clearance 0)
		)
		(min_thickness 0.25)
		(keepout
			(tracks not_allowed)
			(vias allowed)
			(pads allowed)
			(copperpour not_allowed)
			(footprints allowed)
		)
		(placement
			(enabled no)
			(sheetname "")
		)
		(fill yes
			(thermal_gap 0.5)
			(thermal_bridge_width 0.5)
			(island_removal_mode 0)
		)
		(polygon
			(pts
				(arc
					(start 173.15053 -221.321376)
					(mid 173.165409 -221.357297)
					(end 173.20133 -221.372176)
				)
				(arc
					(start 174.60087 -221.372176)
					(mid 174.636791 -221.357297)
					(end 174.65167 -221.321376)
				)
				(arc
					(start 174.65167 -220.912436)
					(mid 174.636791 -220.876515)
					(end 174.60087 -220.861636)
				)
				(arc
					(start 173.20133 -220.861636)
					(mid 173.165409 -220.876515)
					(end 173.15053 -220.912436)
				)
			)
		)
	)
	(zone
		(layers "In1.Cu" "In2.Cu")
		(hatch none 0.5)
		(connect_pads
			(clearance 0)
		)
		(min_thickness 0.25)
		(keepout
			(tracks not_allowed)
			(vias allowed)
			(pads allowed)
			(copperpour not_allowed)
			(footprints allowed)
		)
		(placement
			(enabled no)
			(sheetname "")
		)
		(fill yes
			(thermal_gap 0.5)
			(thermal_bridge_width 0.5)
			(island_removal_mode 0)
		)
		(polygon
			(pts
				(arc
					(start 184.794398 -291.021516)
					(mid 184.809277 -291.057437)
					(end 184.845198 -291.072316)
				)
				(arc
					(start 186.244738 -291.072316)
					(mid 186.280659 -291.057437)
					(end 186.295538 -291.021516)
				)
				(arc
					(start 186.295538 -290.612576)
					(mid 186.280659 -290.576655)
					(end 186.244738 -290.561776)
				)
				(arc
					(start 184.845198 -290.561776)
					(mid 184.809277 -290.576655)
					(end 184.794398 -290.612576)
				)
			)
		)
	)
	(zone
		(layers "In1.Cu" "In2.Cu")
		(hatch none 0.5)
		(connect_pads
			(clearance 0)
		)
		(min_thickness 0.25)
		(keepout
			(tracks not_allowed)
			(vias allowed)
			(pads allowed)
			(copperpour not_allowed)
			(footprints allowed)
		)
		(placement
			(enabled no)
			(sheetname "")
		)
		(fill yes
			(thermal_gap 0.5)
			(thermal_bridge_width 0.5)
			(island_removal_mode 0)
		)
		(polygon
			(pts
				(arc
					(start 259.430266 -223.871536)
					(mid 259.445145 -223.907457)
					(end 259.481066 -223.922336)
				)
				(arc
					(start 260.880606 -223.922336)
					(mid 260.916527 -223.907457)
					(end 260.931406 -223.871536)
				)
				(arc
					(start 260.931406 -223.462596)
					(mid 260.916527 -223.426675)
					(end 260.880606 -223.411796)
				)
				(arc
					(start 259.481066 -223.411796)
					(mid 259.445145 -223.426675)
					(end 259.430266 -223.462596)
				)
			)
		)
	)
	(zone
		(layers "In1.Cu" "In2.Cu")
		(hatch none 0.5)
		(connect_pads
			(clearance 0)
		)
		(min_thickness 0.25)
		(keepout
			(tracks not_allowed)
			(vias allowed)
			(pads allowed)
			(copperpour not_allowed)
			(footprints allowed)
		)
		(placement
			(enabled no)
			(sheetname "")
		)
		(fill yes
			(thermal_gap 0.5)
			(thermal_bridge_width 0.5)
			(island_removal_mode 0)
		)
		(polygon
			(pts
				(arc
					(start 45.10913 -224.72142)
					(mid 45.124009 -224.757341)
					(end 45.15993 -224.77222)
				)
				(arc
					(start 46.55947 -224.77222)
					(mid 46.595391 -224.757341)
					(end 46.61027 -224.72142)
				)
				(arc
					(start 46.61027 -224.31248)
					(mid 46.595391 -224.276559)
					(end 46.55947 -224.26168)
				)
				(arc
					(start 45.15993 -224.26168)
					(mid 45.124009 -224.276559)
					(end 45.10913 -224.31248)
				)
			)
		)
	)
	(zone
		(layers "In1.Cu" "In2.Cu")
		(hatch none 0.5)
		(connect_pads
			(clearance 0)
		)
		(min_thickness 0.25)
		(keepout
			(tracks not_allowed)
			(vias allowed)
			(pads allowed)
			(copperpour not_allowed)
			(footprints allowed)
		)
		(placement
			(enabled no)
			(sheetname "")
		)
		(fill yes
			(thermal_gap 0.5)
			(thermal_bridge_width 0.5)
			(island_removal_mode 0)
		)
		(polygon
			(pts
				(arc
					(start 255.330198 -252.771402)
					(mid 255.345077 -252.807323)
					(end 255.380998 -252.822202)
				)
				(arc
					(start 256.780538 -252.822202)
					(mid 256.816459 -252.807323)
					(end 256.831338 -252.771402)
				)
				(arc
					(start 256.831338 -252.362462)
					(mid 256.816459 -252.326541)
					(end 256.780538 -252.311662)
				)
				(arc
					(start 255.380998 -252.311662)
					(mid 255.345077 -252.326541)
					(end 255.330198 -252.362462)
				)
			)
		)
	)
	(zone
		(layers "In1.Cu" "In2.Cu")
		(hatch none 0.5)
		(connect_pads
			(clearance 0)
		)
		(min_thickness 0.25)
		(keepout
			(tracks not_allowed)
			(vias allowed)
			(pads allowed)
			(copperpour not_allowed)
			(footprints allowed)
		)
		(placement
			(enabled no)
			(sheetname "")
		)
		(fill yes
			(thermal_gap 0.5)
			(thermal_bridge_width 0.5)
			(island_removal_mode 0)
		)
		(polygon
			(pts
				(arc
					(start 49.209198 -212.82152)
					(mid 49.224077 -212.857441)
					(end 49.259998 -212.87232)
				)
				(arc
					(start 50.659538 -212.87232)
					(mid 50.695459 -212.857441)
					(end 50.710338 -212.82152)
				)
				(arc
					(start 50.710338 -212.41258)
					(mid 50.695459 -212.376659)
					(end 50.659538 -212.36178)
				)
				(arc
					(start 49.259998 -212.36178)
					(mid 49.224077 -212.376659)
					(end 49.209198 -212.41258)
				)
			)
		)
	)
	(zone
		(layers "In1.Cu" "In2.Cu")
		(hatch none 0.5)
		(connect_pads
			(clearance 0)
		)
		(min_thickness 0.25)
		(keepout
			(tracks not_allowed)
			(vias allowed)
			(pads allowed)
			(copperpour not_allowed)
			(footprints allowed)
		)
		(placement
			(enabled no)
			(sheetname "")
		)
		(fill yes
			(thermal_gap 0.5)
			(thermal_bridge_width 0.5)
			(island_removal_mode 0)
		)
		(polygon
			(pts
				(arc
					(start 274.517866 -228.121464)
					(mid 274.532745 -228.157385)
					(end 274.568666 -228.172264)
				)
				(arc
					(start 275.968206 -228.172264)
					(mid 276.004127 -228.157385)
					(end 276.019006 -228.121464)
				)
				(arc
					(start 276.019006 -227.712524)
					(mid 276.004127 -227.676603)
					(end 275.968206 -227.661724)
				)
				(arc
					(start 274.568666 -227.661724)
					(mid 274.532745 -227.676603)
					(end 274.517866 -227.712524)
				)
			)
		)
	)
	(zone
		(layers "In1.Cu" "In2.Cu")
		(hatch none 0.5)
		(connect_pads
			(clearance 0)
		)
		(min_thickness 0.25)
		(keepout
			(tracks not_allowed)
			(vias allowed)
			(pads allowed)
			(copperpour not_allowed)
			(footprints allowed)
		)
		(placement
			(enabled no)
			(sheetname "")
		)
		(fill yes
			(thermal_gap 0.5)
			(thermal_bridge_width 0.5)
			(island_removal_mode 0)
		)
		(polygon
			(pts
				(arc
					(start 270.417798 -305.471322)
					(mid 270.432677 -305.507243)
					(end 270.468598 -305.522122)
				)
				(arc
					(start 271.868138 -305.522122)
					(mid 271.904059 -305.507243)
					(end 271.918938 -305.471322)
				)
				(arc
					(start 271.918938 -305.062382)
					(mid 271.904059 -305.026461)
					(end 271.868138 -305.011582)
				)
				(arc
					(start 270.468598 -305.011582)
					(mid 270.432677 -305.026461)
					(end 270.417798 -305.062382)
				)
			)
		)
	)
	(zone
		(layers "In1.Cu" "In2.Cu")
		(hatch none 0.5)
		(connect_pads
			(clearance 0)
		)
		(min_thickness 0.25)
		(keepout
			(tracks not_allowed)
			(vias allowed)
			(pads allowed)
			(copperpour not_allowed)
			(footprints allowed)
		)
		(placement
			(enabled no)
			(sheetname "")
		)
		(fill yes
			(thermal_gap 0.5)
			(thermal_bridge_width 0.5)
			(island_removal_mode 0)
		)
		(polygon
			(pts
				(arc
					(start 169.706798 -239.17148)
					(mid 169.721677 -239.207401)
					(end 169.757598 -239.22228)
				)
				(arc
					(start 171.157138 -239.22228)
					(mid 171.193059 -239.207401)
					(end 171.207938 -239.17148)
				)
				(arc
					(start 171.207938 -238.76254)
					(mid 171.193059 -238.726619)
					(end 171.157138 -238.71174)
				)
				(arc
					(start 169.757598 -238.71174)
					(mid 169.721677 -238.726619)
					(end 169.706798 -238.76254)
				)
			)
		)
	)
	(zone
		(layers "In1.Cu" "In2.Cu")
		(hatch none 0.5)
		(connect_pads
			(clearance 0)
		)
		(min_thickness 0.25)
		(keepout
			(tracks not_allowed)
			(vias allowed)
			(pads allowed)
			(copperpour not_allowed)
			(footprints allowed)
		)
		(placement
			(enabled no)
			(sheetname "")
		)
		(fill yes
			(thermal_gap 0.5)
			(thermal_bridge_width 0.5)
			(island_removal_mode 0)
		)
		(polygon
			(pts
				(arc
					(start 255.330198 -275.721318)
					(mid 255.345077 -275.757239)
					(end 255.380998 -275.772118)
				)
				(arc
					(start 256.780538 -275.772118)
					(mid 256.816459 -275.757239)
					(end 256.831338 -275.721318)
				)
				(arc
					(start 256.831338 -275.312378)
					(mid 256.816459 -275.276457)
					(end 256.780538 -275.261578)
				)
				(arc
					(start 255.380998 -275.261578)
					(mid 255.345077 -275.276457)
					(end 255.330198 -275.312378)
				)
			)
		)
	)
	(zone
		(layers "In1.Cu" "In2.Cu")
		(hatch none 0.5)
		(connect_pads
			(clearance 0)
		)
		(min_thickness 0.25)
		(keepout
			(tracks not_allowed)
			(vias allowed)
			(pads allowed)
			(copperpour not_allowed)
			(footprints allowed)
		)
		(placement
			(enabled no)
			(sheetname "")
		)
		(fill yes
			(thermal_gap 0.5)
			(thermal_bridge_width 0.5)
			(island_removal_mode 0)
		)
		(polygon
			(pts
				(arc
					(start 462.909666 -195.821554)
					(mid 462.924545 -195.857475)
					(end 462.960466 -195.872354)
				)
				(arc
					(start 464.360006 -195.872354)
					(mid 464.395927 -195.857475)
					(end 464.410806 -195.821554)
				)
				(arc
					(start 464.410806 -195.412614)
					(mid 464.395927 -195.376693)
					(end 464.360006 -195.361814)
				)
				(arc
					(start 462.960466 -195.361814)
					(mid 462.924545 -195.376693)
					(end 462.909666 -195.412614)
				)
			)
		)
	)
	(zone
		(layers "In1.Cu" "In2.Cu")
		(hatch none 0.5)
		(connect_pads
			(clearance 0)
		)
		(min_thickness 0.25)
		(keepout
			(tracks not_allowed)
			(vias allowed)
			(pads allowed)
			(copperpour not_allowed)
			(footprints allowed)
		)
		(placement
			(enabled no)
			(sheetname "")
		)
		(fill yes
			(thermal_gap 0.5)
			(thermal_bridge_width 0.5)
			(island_removal_mode 0)
		)
		(polygon
			(pts
				(arc
					(start 37.56533 -261.271512)
					(mid 37.580209 -261.307433)
					(end 37.61613 -261.322312)
				)
				(arc
					(start 39.01567 -261.322312)
					(mid 39.051591 -261.307433)
					(end 39.06647 -261.271512)
				)
				(arc
					(start 39.06647 -260.862572)
					(mid 39.051591 -260.826651)
					(end 39.01567 -260.811772)
				)
				(arc
					(start 37.61613 -260.811772)
					(mid 37.580209 -260.826651)
					(end 37.56533 -260.862572)
				)
			)
		)
	)
	(zone
		(layers "In1.Cu" "In2.Cu")
		(hatch none 0.5)
		(connect_pads
			(clearance 0)
		)
		(min_thickness 0.25)
		(keepout
			(tracks not_allowed)
			(vias allowed)
			(pads allowed)
			(copperpour not_allowed)
			(footprints allowed)
		)
		(placement
			(enabled no)
			(sheetname "")
		)
		(fill yes
			(thermal_gap 0.5)
			(thermal_bridge_width 0.5)
			(island_removal_mode 0)
		)
		(polygon
			(pts
				(arc
					(start 443.721998 -221.321376)
					(mid 443.736877 -221.357297)
					(end 443.772798 -221.372176)
				)
				(arc
					(start 445.172338 -221.372176)
					(mid 445.208259 -221.357297)
					(end 445.223138 -221.321376)
				)
				(arc
					(start 445.223138 -220.912436)
					(mid 445.208259 -220.876515)
					(end 445.172338 -220.861636)
				)
				(arc
					(start 443.772798 -220.861636)
					(mid 443.736877 -220.876515)
					(end 443.721998 -220.912436)
				)
			)
		)
	)
	(zone
		(layers "In1.Cu" "In2.Cu")
		(hatch none 0.5)
		(connect_pads
			(clearance 0)
		)
		(min_thickness 0.25)
		(keepout
			(tracks not_allowed)
			(vias allowed)
			(pads allowed)
			(copperpour not_allowed)
			(footprints allowed)
		)
		(placement
			(enabled no)
			(sheetname "")
		)
		(fill yes
			(thermal_gap 0.5)
			(thermal_bridge_width 0.5)
			(island_removal_mode 0)
		)
		(polygon
			(pts
				(arc
					(start 207.425798 -223.871536)
					(mid 207.440677 -223.907457)
					(end 207.476598 -223.922336)
				)
				(arc
					(start 208.876138 -223.922336)
					(mid 208.912059 -223.907457)
					(end 208.926938 -223.871536)
				)
				(arc
					(start 208.926938 -223.462596)
					(mid 208.912059 -223.426675)
					(end 208.876138 -223.411796)
				)
				(arc
					(start 207.476598 -223.411796)
					(mid 207.440677 -223.426675)
					(end 207.425798 -223.462596)
				)
			)
		)
	)
	(zone
		(layers "In1.Cu" "In2.Cu")
		(hatch none 0.5)
		(connect_pads
			(clearance 0)
		)
		(min_thickness 0.25)
		(keepout
			(tracks not_allowed)
			(vias allowed)
			(pads allowed)
			(copperpour not_allowed)
			(footprints allowed)
		)
		(placement
			(enabled no)
			(sheetname "")
		)
		(fill yes
			(thermal_gap 0.5)
			(thermal_bridge_width 0.5)
			(island_removal_mode 0)
		)
		(polygon
			(pts
				(arc
					(start 443.721998 -262.971534)
					(mid 443.736877 -263.007455)
					(end 443.772798 -263.022334)
				)
				(arc
					(start 445.172338 -263.022334)
					(mid 445.208259 -263.007455)
					(end 445.223138 -262.971534)
				)
				(arc
					(start 445.223138 -262.562594)
					(mid 445.208259 -262.526673)
					(end 445.172338 -262.511794)
				)
				(arc
					(start 443.772798 -262.511794)
					(mid 443.736877 -262.526673)
					(end 443.721998 -262.562594)
				)
			)
		)
	)
	(zone
		(layers "In1.Cu" "In2.Cu")
		(hatch none 0.5)
		(connect_pads
			(clearance 0)
		)
		(min_thickness 0.25)
		(keepout
			(tracks not_allowed)
			(vias allowed)
			(pads allowed)
			(copperpour not_allowed)
			(footprints allowed)
		)
		(placement
			(enabled no)
			(sheetname "")
		)
		(fill yes
			(thermal_gap 0.5)
			(thermal_bridge_width 0.5)
			(island_removal_mode 0)
		)
		(polygon
			(pts
				(arc
					(start 22.47773 -277.42134)
					(mid 22.492609 -277.457261)
					(end 22.52853 -277.47214)
				)
				(arc
					(start 23.92807 -277.47214)
					(mid 23.963991 -277.457261)
					(end 23.97887 -277.42134)
				)
				(arc
					(start 23.97887 -277.0124)
					(mid 23.963991 -276.976479)
					(end 23.92807 -276.9616)
				)
				(arc
					(start 22.52853 -276.9616)
					(mid 22.492609 -276.976479)
					(end 22.47773 -277.0124)
				)
			)
		)
	)
	(zone
		(layers "In1.Cu" "In2.Cu")
		(hatch none 0.5)
		(connect_pads
			(clearance 0)
		)
		(min_thickness 0.25)
		(keepout
			(tracks not_allowed)
			(vias allowed)
			(pads allowed)
			(copperpour not_allowed)
			(footprints allowed)
		)
		(placement
			(enabled no)
			(sheetname "")
		)
		(fill yes
			(thermal_gap 0.5)
			(thermal_bridge_width 0.5)
			(island_removal_mode 0)
		)
		(polygon
			(pts
				(arc
					(start 293.049198 -314.821316)
					(mid 293.064077 -314.857237)
					(end 293.099998 -314.872116)
				)
				(arc
					(start 294.499538 -314.872116)
					(mid 294.535459 -314.857237)
					(end 294.550338 -314.821316)
				)
				(arc
					(start 294.550338 -314.412376)
					(mid 294.535459 -314.376455)
					(end 294.499538 -314.361576)
				)
				(arc
					(start 293.099998 -314.361576)
					(mid 293.064077 -314.376455)
					(end 293.049198 -314.412376)
				)
			)
		)
	)
	(zone
		(layers "In1.Cu" "In2.Cu")
		(hatch none 0.5)
		(connect_pads
			(clearance 0)
		)
		(min_thickness 0.25)
		(keepout
			(tracks not_allowed)
			(vias allowed)
			(pads allowed)
			(copperpour not_allowed)
			(footprints allowed)
		)
		(placement
			(enabled no)
			(sheetname "")
		)
		(fill yes
			(thermal_gap 0.5)
			(thermal_bridge_width 0.5)
			(island_removal_mode 0)
		)
		(polygon
			(pts
				(arc
					(start 26.577798 -272.321528)
					(mid 26.592677 -272.357449)
					(end 26.628598 -272.372328)
				)
				(arc
					(start 28.028138 -272.372328)
					(mid 28.064059 -272.357449)
					(end 28.078938 -272.321528)
				)
				(arc
					(start 28.078938 -271.912588)
					(mid 28.064059 -271.876667)
					(end 28.028138 -271.861788)
				)
				(arc
					(start 26.628598 -271.861788)
					(mid 26.592677 -271.876667)
					(end 26.577798 -271.912588)
				)
			)
		)
	)
	(zone
		(layers "In1.Cu" "In2.Cu")
		(hatch none 0.5)
		(connect_pads
			(clearance 0)
		)
		(min_thickness 0.25)
		(keepout
			(tracks not_allowed)
			(vias allowed)
			(pads allowed)
			(copperpour not_allowed)
			(footprints allowed)
		)
		(placement
			(enabled no)
			(sheetname "")
		)
		(fill yes
			(thermal_gap 0.5)
			(thermal_bridge_width 0.5)
			(island_removal_mode 0)
		)
		(polygon
			(pts
				(arc
					(start 184.794398 -197.521322)
					(mid 184.809277 -197.557243)
					(end 184.845198 -197.572122)
				)
				(arc
					(start 186.244738 -197.572122)
					(mid 186.280659 -197.557243)
					(end 186.295538 -197.521322)
				)
				(arc
					(start 186.295538 -197.112382)
					(mid 186.280659 -197.076461)
					(end 186.244738 -197.061582)
				)
				(arc
					(start 184.845198 -197.061582)
					(mid 184.809277 -197.076461)
					(end 184.794398 -197.112382)
				)
			)
		)
	)
	(zone
		(layers "In1.Cu" "In2.Cu")
		(hatch none 0.5)
		(connect_pads
			(clearance 0)
		)
		(min_thickness 0.25)
		(keepout
			(tracks not_allowed)
			(vias allowed)
			(pads allowed)
			(copperpour not_allowed)
			(footprints allowed)
		)
		(placement
			(enabled no)
			(sheetname "")
		)
		(fill yes
			(thermal_gap 0.5)
			(thermal_bridge_width 0.5)
			(island_removal_mode 0)
		)
		(polygon
			(pts
				(arc
					(start 177.250598 -293.571422)
					(mid 177.265477 -293.607343)
					(end 177.301398 -293.622222)
				)
				(arc
					(start 178.700938 -293.622222)
					(mid 178.736859 -293.607343)
					(end 178.751738 -293.571422)
				)
				(arc
					(start 178.751738 -293.162482)
					(mid 178.736859 -293.126561)
					(end 178.700938 -293.111682)
				)
				(arc
					(start 177.301398 -293.111682)
					(mid 177.265477 -293.126561)
					(end 177.250598 -293.162482)
				)
			)
		)
	)
	(zone
		(layers "In1.Cu" "In2.Cu")
		(hatch none 0.5)
		(connect_pads
			(clearance 0)
		)
		(min_thickness 0.25)
		(keepout
			(tracks not_allowed)
			(vias allowed)
			(pads allowed)
			(copperpour not_allowed)
			(footprints allowed)
		)
		(placement
			(enabled no)
			(sheetname "")
		)
		(fill yes
			(thermal_gap 0.5)
			(thermal_bridge_width 0.5)
			(island_removal_mode 0)
		)
		(polygon
			(pts
				(arc
					(start 64.296798 -214.521542)
					(mid 64.311677 -214.557463)
					(end 64.347598 -214.572342)
				)
				(arc
					(start 65.747138 -214.572342)
					(mid 65.783059 -214.557463)
					(end 65.797938 -214.521542)
				)
				(arc
					(start 65.797938 -214.112602)
					(mid 65.783059 -214.076681)
					(end 65.747138 -214.061802)
				)
				(arc
					(start 64.347598 -214.061802)
					(mid 64.311677 -214.076681)
					(end 64.296798 -214.112602)
				)
			)
		)
	)
	(zone
		(layers "In1.Cu" "In2.Cu")
		(hatch none 0.5)
		(connect_pads
			(clearance 0)
		)
		(min_thickness 0.25)
		(keepout
			(tracks not_allowed)
			(vias allowed)
			(pads allowed)
			(copperpour not_allowed)
			(footprints allowed)
		)
		(placement
			(enabled no)
			(sheetname "")
		)
		(fill yes
			(thermal_gap 0.5)
			(thermal_bridge_width 0.5)
			(island_removal_mode 0)
		)
		(polygon
			(pts
				(arc
					(start 180.69433 -243.421408)
					(mid 180.709209 -243.457329)
					(end 180.74513 -243.472208)
				)
				(arc
					(start 182.14467 -243.472208)
					(mid 182.180591 -243.457329)
					(end 182.19547 -243.421408)
				)
				(arc
					(start 182.19547 -243.012468)
					(mid 182.180591 -242.976547)
					(end 182.14467 -242.961668)
				)
				(arc
					(start 180.74513 -242.961668)
					(mid 180.709209 -242.976547)
					(end 180.69433 -243.012468)
				)
			)
		)
	)
	(zone
		(layers "In1.Cu" "In2.Cu")
		(hatch none 0.5)
		(connect_pads
			(clearance 0)
		)
		(min_thickness 0.25)
		(keepout
			(tracks not_allowed)
			(vias allowed)
			(pads allowed)
			(copperpour not_allowed)
			(footprints allowed)
		)
		(placement
			(enabled no)
			(sheetname "")
		)
		(fill yes
			(thermal_gap 0.5)
			(thermal_bridge_width 0.5)
			(island_removal_mode 0)
		)
		(polygon
			(pts
				(arc
					(start 11.490198 -229.821486)
					(mid 11.505077 -229.857407)
					(end 11.540998 -229.872286)
				)
				(arc
					(start 12.940538 -229.872286)
					(mid 12.976459 -229.857407)
					(end 12.991338 -229.821486)
				)
				(arc
					(start 12.991338 -229.412546)
					(mid 12.976459 -229.376625)
					(end 12.940538 -229.361746)
				)
				(arc
					(start 11.540998 -229.361746)
					(mid 11.505077 -229.376625)
					(end 11.490198 -229.412546)
				)
			)
		)
	)
	(zone
		(layers "In1.Cu" "In2.Cu")
		(hatch none 0.5)
		(connect_pads
			(clearance 0)
		)
		(min_thickness 0.25)
		(keepout
			(tracks not_allowed)
			(vias allowed)
			(pads allowed)
			(copperpour not_allowed)
			(footprints allowed)
		)
		(placement
			(enabled no)
			(sheetname "")
		)
		(fill yes
			(thermal_gap 0.5)
			(thermal_bridge_width 0.5)
			(island_removal_mode 0)
		)
		(polygon
			(pts
				(arc
					(start 180.69433 -264.671302)
					(mid 180.709209 -264.707223)
					(end 180.74513 -264.722102)
				)
				(arc
					(start 182.14467 -264.722102)
					(mid 182.180591 -264.707223)
					(end 182.19547 -264.671302)
				)
				(arc
					(start 182.19547 -264.262362)
					(mid 182.180591 -264.226441)
					(end 182.14467 -264.211562)
				)
				(arc
					(start 180.74513 -264.211562)
					(mid 180.709209 -264.226441)
					(end 180.69433 -264.262362)
				)
			)
		)
	)
	(zone
		(layers "In1.Cu" "In2.Cu")
		(hatch none 0.5)
		(connect_pads
			(clearance 0)
		)
		(min_thickness 0.25)
		(keepout
			(tracks not_allowed)
			(vias allowed)
			(pads allowed)
			(copperpour not_allowed)
			(footprints allowed)
		)
		(placement
			(enabled no)
			(sheetname "")
		)
		(fill yes
			(thermal_gap 0.5)
			(thermal_bridge_width 0.5)
			(island_removal_mode 0)
		)
		(polygon
			(pts
				(arc
					(start 255.330198 -232.371392)
					(mid 255.345077 -232.407313)
					(end 255.380998 -232.422192)
				)
				(arc
					(start 256.780538 -232.422192)
					(mid 256.816459 -232.407313)
					(end 256.831338 -232.371392)
				)
				(arc
					(start 256.831338 -231.962452)
					(mid 256.816459 -231.926531)
					(end 256.780538 -231.911652)
				)
				(arc
					(start 255.380998 -231.911652)
					(mid 255.345077 -231.926531)
					(end 255.330198 -231.962452)
				)
			)
		)
	)
	(zone
		(layers "In1.Cu" "In2.Cu")
		(hatch none 0.5)
		(connect_pads
			(clearance 0)
		)
		(min_thickness 0.25)
		(keepout
			(tracks not_allowed)
			(vias allowed)
			(pads allowed)
			(copperpour not_allowed)
			(footprints allowed)
		)
		(placement
			(enabled no)
			(sheetname "")
		)
		(fill yes
			(thermal_gap 0.5)
			(thermal_bridge_width 0.5)
			(island_removal_mode 0)
		)
		(polygon
			(pts
				(arc
					(start 293.049198 -200.071482)
					(mid 293.064077 -200.107403)
					(end 293.099998 -200.122282)
				)
				(arc
					(start 294.499538 -200.122282)
					(mid 294.535459 -200.107403)
					(end 294.550338 -200.071482)
				)
				(arc
					(start 294.550338 -199.662542)
					(mid 294.535459 -199.626621)
					(end 294.499538 -199.611742)
				)
				(arc
					(start 293.099998 -199.611742)
					(mid 293.064077 -199.626621)
					(end 293.049198 -199.662542)
				)
			)
		)
	)
	(zone
		(layers "In1.Cu" "In2.Cu")
		(hatch none 0.5)
		(connect_pads
			(clearance 0)
		)
		(min_thickness 0.25)
		(keepout
			(tracks not_allowed)
			(vias allowed)
			(pads allowed)
			(copperpour not_allowed)
			(footprints allowed)
		)
		(placement
			(enabled no)
			(sheetname "")
		)
		(fill yes
			(thermal_gap 0.5)
			(thermal_bridge_width 0.5)
			(island_removal_mode 0)
		)
		(polygon
			(pts
				(arc
					(start 443.721998 -224.72142)
					(mid 443.736877 -224.757341)
					(end 443.772798 -224.77222)
				)
				(arc
					(start 445.172338 -224.77222)
					(mid 445.208259 -224.757341)
					(end 445.223138 -224.72142)
				)
				(arc
					(start 445.223138 -224.31248)
					(mid 445.208259 -224.276559)
					(end 445.172338 -224.26168)
				)
				(arc
					(start 443.772798 -224.26168)
					(mid 443.736877 -224.276559)
					(end 443.721998 -224.31248)
				)
			)
		)
	)
	(zone
		(layers "In1.Cu" "In2.Cu")
		(hatch none 0.5)
		(connect_pads
			(clearance 0)
		)
		(min_thickness 0.25)
		(keepout
			(tracks not_allowed)
			(vias allowed)
			(pads allowed)
			(copperpour not_allowed)
			(footprints allowed)
		)
		(placement
			(enabled no)
			(sheetname "")
		)
		(fill yes
			(thermal_gap 0.5)
			(thermal_bridge_width 0.5)
			(island_removal_mode 0)
		)
		(polygon
			(pts
				(arc
					(start 173.15053 -241.721386)
					(mid 173.165409 -241.757307)
					(end 173.20133 -241.772186)
				)
				(arc
					(start 174.60087 -241.772186)
					(mid 174.636791 -241.757307)
					(end 174.65167 -241.721386)
				)
				(arc
					(start 174.65167 -241.312446)
					(mid 174.636791 -241.276525)
					(end 174.60087 -241.261646)
				)
				(arc
					(start 173.20133 -241.261646)
					(mid 173.165409 -241.276525)
					(end 173.15053 -241.312446)
				)
			)
		)
	)
	(zone
		(layers "In1.Cu" "In2.Cu")
		(hatch none 0.5)
		(connect_pads
			(clearance 0)
		)
		(min_thickness 0.25)
		(keepout
			(tracks not_allowed)
			(vias allowed)
			(pads allowed)
			(copperpour not_allowed)
			(footprints allowed)
		)
		(placement
			(enabled no)
			(sheetname "")
		)
		(fill yes
			(thermal_gap 0.5)
			(thermal_bridge_width 0.5)
			(island_removal_mode 0)
		)
		(polygon
			(pts
				(arc
					(start 173.15053 -234.071414)
					(mid 173.165409 -234.107335)
					(end 173.20133 -234.122214)
				)
				(arc
					(start 174.60087 -234.122214)
					(mid 174.636791 -234.107335)
					(end 174.65167 -234.071414)
				)
				(arc
					(start 174.65167 -233.662474)
					(mid 174.636791 -233.626553)
					(end 174.60087 -233.611674)
				)
				(arc
					(start 173.20133 -233.611674)
					(mid 173.165409 -233.626553)
					(end 173.15053 -233.662474)
				)
			)
		)
	)
	(zone
		(layers "In1.Cu" "In2.Cu")
		(hatch none 0.5)
		(connect_pads
			(clearance 0)
		)
		(min_thickness 0.25)
		(keepout
			(tracks not_allowed)
			(vias allowed)
			(pads allowed)
			(copperpour not_allowed)
			(footprints allowed)
		)
		(placement
			(enabled no)
			(sheetname "")
		)
		(fill yes
			(thermal_gap 0.5)
			(thermal_bridge_width 0.5)
			(island_removal_mode 0)
		)
		(polygon
			(pts
				(arc
					(start 184.794398 -311.421526)
					(mid 184.809277 -311.457447)
					(end 184.845198 -311.472326)
				)
				(arc
					(start 186.244738 -311.472326)
					(mid 186.280659 -311.457447)
					(end 186.295538 -311.421526)
				)
				(arc
					(start 186.295538 -311.012586)
					(mid 186.280659 -310.976665)
					(end 186.244738 -310.961786)
				)
				(arc
					(start 184.845198 -310.961786)
					(mid 184.809277 -310.976665)
					(end 184.794398 -311.012586)
				)
			)
		)
	)
	(zone
		(layers "In1.Cu" "In2.Cu")
		(hatch none 0.5)
		(connect_pads
			(clearance 0)
		)
		(min_thickness 0.25)
		(keepout
			(tracks not_allowed)
			(vias allowed)
			(pads allowed)
			(copperpour not_allowed)
			(footprints allowed)
		)
		(placement
			(enabled no)
			(sheetname "")
		)
		(fill yes
			(thermal_gap 0.5)
			(thermal_bridge_width 0.5)
			(island_removal_mode 0)
		)
		(polygon
			(pts
				(arc
					(start 7.39013 -228.121464)
					(mid 7.405009 -228.157385)
					(end 7.44093 -228.172264)
				)
				(arc
					(start 8.84047 -228.172264)
					(mid 8.876391 -228.157385)
					(end 8.89127 -228.121464)
				)
				(arc
					(start 8.89127 -227.712524)
					(mid 8.876391 -227.676603)
					(end 8.84047 -227.661724)
				)
				(arc
					(start 7.44093 -227.661724)
					(mid 7.405009 -227.676603)
					(end 7.39013 -227.712524)
				)
			)
		)
	)
	(zone
		(layers "In1.Cu" "In2.Cu")
		(hatch none 0.5)
		(connect_pads
			(clearance 0)
		)
		(min_thickness 0.25)
		(keepout
			(tracks not_allowed)
			(vias allowed)
			(pads allowed)
			(copperpour not_allowed)
			(footprints allowed)
		)
		(placement
			(enabled no)
			(sheetname "")
		)
		(fill yes
			(thermal_gap 0.5)
			(thermal_bridge_width 0.5)
			(island_removal_mode 0)
		)
		(polygon
			(pts
				(arc
					(start 312.236866 -291.021516)
					(mid 312.251745 -291.057437)
					(end 312.287666 -291.072316)
				)
				(arc
					(start 313.687206 -291.072316)
					(mid 313.723127 -291.057437)
					(end 313.738006 -291.021516)
				)
				(arc
					(start 313.738006 -290.612576)
					(mid 313.723127 -290.576655)
					(end 313.687206 -290.561776)
				)
				(arc
					(start 312.287666 -290.561776)
					(mid 312.251745 -290.576655)
					(end 312.236866 -290.612576)
				)
			)
		)
	)
	(zone
		(layers "In1.Cu" "In2.Cu")
		(hatch none 0.5)
		(connect_pads
			(clearance 0)
		)
		(min_thickness 0.25)
		(keepout
			(tracks not_allowed)
			(vias allowed)
			(pads allowed)
			(copperpour not_allowed)
			(footprints allowed)
		)
		(placement
			(enabled no)
			(sheetname "")
		)
		(fill yes
			(thermal_gap 0.5)
			(thermal_bridge_width 0.5)
			(island_removal_mode 0)
		)
		(polygon
			(pts
				(arc
					(start 158.06293 -310.571388)
					(mid 158.077809 -310.607309)
					(end 158.11373 -310.622188)
				)
				(arc
					(start 159.51327 -310.622188)
					(mid 159.549191 -310.607309)
					(end 159.56407 -310.571388)
				)
				(arc
					(start 159.56407 -310.162448)
					(mid 159.549191 -310.126527)
					(end 159.51327 -310.111648)
				)
				(arc
					(start 158.11373 -310.111648)
					(mid 158.077809 -310.126527)
					(end 158.06293 -310.162448)
				)
			)
		)
	)
	(zone
		(layers "In1.Cu" "In2.Cu")
		(hatch none 0.5)
		(connect_pads
			(clearance 0)
		)
		(min_thickness 0.25)
		(keepout
			(tracks not_allowed)
			(vias allowed)
			(pads allowed)
			(copperpour not_allowed)
			(footprints allowed)
		)
		(placement
			(enabled no)
			(sheetname "")
		)
		(fill yes
			(thermal_gap 0.5)
			(thermal_bridge_width 0.5)
			(island_removal_mode 0)
		)
		(polygon
			(pts
				(arc
					(start 60.19673 -219.621354)
					(mid 60.211609 -219.657275)
					(end 60.24753 -219.672154)
				)
				(arc
					(start 61.64707 -219.672154)
					(mid 61.682991 -219.657275)
					(end 61.69787 -219.621354)
				)
				(arc
					(start 61.69787 -219.212414)
					(mid 61.682991 -219.176493)
					(end 61.64707 -219.161614)
				)
				(arc
					(start 60.24753 -219.161614)
					(mid 60.211609 -219.176493)
					(end 60.19673 -219.212414)
				)
			)
		)
	)
	(zone
		(layers "In1.Cu" "In2.Cu")
		(hatch none 0.5)
		(connect_pads
			(clearance 0)
		)
		(min_thickness 0.25)
		(keepout
			(tracks not_allowed)
			(vias allowed)
			(pads allowed)
			(copperpour not_allowed)
			(footprints allowed)
		)
		(placement
			(enabled no)
			(sheetname "")
		)
		(fill yes
			(thermal_gap 0.5)
			(thermal_bridge_width 0.5)
			(island_removal_mode 0)
		)
		(polygon
			(pts
				(arc
					(start 49.209198 -246.821452)
					(mid 49.224077 -246.857373)
					(end 49.259998 -246.872252)
				)
				(arc
					(start 50.659538 -246.872252)
					(mid 50.695459 -246.857373)
					(end 50.710338 -246.821452)
				)
				(arc
					(start 50.710338 -246.412512)
					(mid 50.695459 -246.376591)
					(end 50.659538 -246.361712)
				)
				(arc
					(start 49.259998 -246.361712)
					(mid 49.224077 -246.376591)
					(end 49.209198 -246.412512)
				)
			)
		)
	)
	(zone
		(layers "In1.Cu" "In2.Cu")
		(hatch none 0.5)
		(connect_pads
			(clearance 0)
		)
		(min_thickness 0.25)
		(keepout
			(tracks not_allowed)
			(vias allowed)
			(pads allowed)
			(copperpour not_allowed)
			(footprints allowed)
		)
		(placement
			(enabled no)
			(sheetname "")
		)
		(fill yes
			(thermal_gap 0.5)
			(thermal_bridge_width 0.5)
			(island_removal_mode 0)
		)
		(polygon
			(pts
				(arc
					(start 214.969598 -268.921484)
					(mid 214.984477 -268.957405)
					(end 215.020398 -268.972284)
				)
				(arc
					(start 216.419938 -268.972284)
					(mid 216.455859 -268.957405)
					(end 216.470738 -268.921484)
				)
				(arc
					(start 216.470738 -268.512544)
					(mid 216.455859 -268.476623)
					(end 216.419938 -268.461744)
				)
				(arc
					(start 215.020398 -268.461744)
					(mid 214.984477 -268.476623)
					(end 214.969598 -268.512544)
				)
			)
		)
	)
	(zone
		(layers "In1.Cu" "In2.Cu")
		(hatch none 0.5)
		(connect_pads
			(clearance 0)
		)
		(min_thickness 0.25)
		(keepout
			(tracks not_allowed)
			(vias allowed)
			(pads allowed)
			(copperpour not_allowed)
			(footprints allowed)
		)
		(placement
			(enabled no)
			(sheetname "")
		)
		(fill yes
			(thermal_gap 0.5)
			(thermal_bridge_width 0.5)
			(island_removal_mode 0)
		)
		(polygon
			(pts
				(arc
					(start 165.60673 -299.521372)
					(mid 165.621609 -299.557293)
					(end 165.65753 -299.572172)
				)
				(arc
					(start 167.05707 -299.572172)
					(mid 167.092991 -299.557293)
					(end 167.10787 -299.521372)
				)
				(arc
					(start 167.10787 -299.112432)
					(mid 167.092991 -299.076511)
					(end 167.05707 -299.061632)
				)
				(arc
					(start 165.65753 -299.061632)
					(mid 165.621609 -299.076511)
					(end 165.60673 -299.112432)
				)
			)
		)
	)
	(zone
		(layers "In1.Cu" "In2.Cu")
		(hatch none 0.5)
		(connect_pads
			(clearance 0)
		)
		(min_thickness 0.25)
		(keepout
			(tracks not_allowed)
			(vias allowed)
			(pads allowed)
			(copperpour not_allowed)
			(footprints allowed)
		)
		(placement
			(enabled no)
			(sheetname "")
		)
		(fill yes
			(thermal_gap 0.5)
			(thermal_bridge_width 0.5)
			(island_removal_mode 0)
		)
		(polygon
			(pts
				(arc
					(start 455.365866 -248.521474)
					(mid 455.380745 -248.557395)
					(end 455.416666 -248.572274)
				)
				(arc
					(start 456.816206 -248.572274)
					(mid 456.852127 -248.557395)
					(end 456.867006 -248.521474)
				)
				(arc
					(start 456.867006 -248.112534)
					(mid 456.852127 -248.076613)
					(end 456.816206 -248.061734)
				)
				(arc
					(start 455.416666 -248.061734)
					(mid 455.380745 -248.076613)
					(end 455.365866 -248.112534)
				)
			)
		)
	)
	(zone
		(layers "In1.Cu" "In2.Cu")
		(hatch none 0.5)
		(connect_pads
			(clearance 0)
		)
		(min_thickness 0.25)
		(keepout
			(tracks not_allowed)
			(vias allowed)
			(pads allowed)
			(copperpour not_allowed)
			(footprints allowed)
		)
		(placement
			(enabled no)
			(sheetname "")
		)
		(fill yes
			(thermal_gap 0.5)
			(thermal_bridge_width 0.5)
			(island_removal_mode 0)
		)
		(polygon
			(pts
				(arc
					(start 56.752998 -260.421374)
					(mid 56.767877 -260.457295)
					(end 56.803798 -260.472174)
				)
				(arc
					(start 58.203338 -260.472174)
					(mid 58.239259 -260.457295)
					(end 58.254138 -260.421374)
				)
				(arc
					(start 58.254138 -260.012434)
					(mid 58.239259 -259.976513)
					(end 58.203338 -259.961634)
				)
				(arc
					(start 56.803798 -259.961634)
					(mid 56.767877 -259.976513)
					(end 56.752998 -260.012434)
				)
			)
		)
	)
	(zone
		(layers "In1.Cu" "In2.Cu")
		(hatch none 0.5)
		(connect_pads
			(clearance 0)
		)
		(min_thickness 0.25)
		(keepout
			(tracks not_allowed)
			(vias allowed)
			(pads allowed)
			(copperpour not_allowed)
			(footprints allowed)
		)
		(placement
			(enabled no)
			(sheetname "")
		)
		(fill yes
			(thermal_gap 0.5)
			(thermal_bridge_width 0.5)
			(island_removal_mode 0)
		)
		(polygon
			(pts
				(arc
					(start 169.706798 -279.9715)
					(mid 169.721677 -280.007421)
					(end 169.757598 -280.0223)
				)
				(arc
					(start 171.157138 -280.0223)
					(mid 171.193059 -280.007421)
					(end 171.207938 -279.9715)
				)
				(arc
					(start 171.207938 -279.56256)
					(mid 171.193059 -279.526639)
					(end 171.157138 -279.51176)
				)
				(arc
					(start 169.757598 -279.51176)
					(mid 169.721677 -279.526639)
					(end 169.706798 -279.56256)
				)
			)
		)
	)
	(zone
		(layers "In1.Cu" "In2.Cu")
		(hatch none 0.5)
		(connect_pads
			(clearance 0)
		)
		(min_thickness 0.25)
		(keepout
			(tracks not_allowed)
			(vias allowed)
			(pads allowed)
			(copperpour not_allowed)
			(footprints allowed)
		)
		(placement
			(enabled no)
			(sheetname "")
		)
		(fill yes
			(thermal_gap 0.5)
			(thermal_bridge_width 0.5)
			(island_removal_mode 0)
		)
		(polygon
			(pts
				(arc
					(start 308.136798 -247.671336)
					(mid 308.151677 -247.707257)
					(end 308.187598 -247.722136)
				)
				(arc
					(start 309.587138 -247.722136)
					(mid 309.623059 -247.707257)
					(end 309.637938 -247.671336)
				)
				(arc
					(start 309.637938 -247.262396)
					(mid 309.623059 -247.226475)
					(end 309.587138 -247.211596)
				)
				(arc
					(start 308.187598 -247.211596)
					(mid 308.151677 -247.226475)
					(end 308.136798 -247.262396)
				)
			)
		)
	)
	(zone
		(layers "In1.Cu" "In2.Cu")
		(hatch none 0.5)
		(connect_pads
			(clearance 0)
		)
		(min_thickness 0.25)
		(keepout
			(tracks not_allowed)
			(vias allowed)
			(pads allowed)
			(copperpour not_allowed)
			(footprints allowed)
		)
		(placement
			(enabled no)
			(sheetname "")
		)
		(fill yes
			(thermal_gap 0.5)
			(thermal_bridge_width 0.5)
			(island_removal_mode 0)
		)
		(polygon
			(pts
				(arc
					(start 308.136798 -297.82135)
					(mid 308.151677 -297.857271)
					(end 308.187598 -297.87215)
				)
				(arc
					(start 309.587138 -297.87215)
					(mid 309.623059 -297.857271)
					(end 309.637938 -297.82135)
				)
				(arc
					(start 309.637938 -297.41241)
					(mid 309.623059 -297.376489)
					(end 309.587138 -297.36161)
				)
				(arc
					(start 308.187598 -297.36161)
					(mid 308.151677 -297.376489)
					(end 308.136798 -297.41241)
				)
			)
		)
	)
	(zone
		(layers "In1.Cu" "In2.Cu")
		(hatch none 0.5)
		(connect_pads
			(clearance 0)
		)
		(min_thickness 0.25)
		(keepout
			(tracks not_allowed)
			(vias allowed)
			(pads allowed)
			(copperpour not_allowed)
			(footprints allowed)
		)
		(placement
			(enabled no)
			(sheetname "")
		)
		(fill yes
			(thermal_gap 0.5)
			(thermal_bridge_width 0.5)
			(island_removal_mode 0)
		)
		(polygon
			(pts
				(arc
					(start 195.78193 -279.121362)
					(mid 195.796809 -279.157283)
					(end 195.83273 -279.172162)
				)
				(arc
					(start 197.23227 -279.172162)
					(mid 197.268191 -279.157283)
					(end 197.28307 -279.121362)
				)
				(arc
					(start 197.28307 -278.712422)
					(mid 197.268191 -278.676501)
					(end 197.23227 -278.661622)
				)
				(arc
					(start 195.83273 -278.661622)
					(mid 195.796809 -278.676501)
					(end 195.78193 -278.712422)
				)
			)
		)
	)
	(zone
		(layers "In1.Cu" "In2.Cu")
		(hatch none 0.5)
		(connect_pads
			(clearance 0)
		)
		(min_thickness 0.25)
		(keepout
			(tracks not_allowed)
			(vias allowed)
			(pads allowed)
			(copperpour not_allowed)
			(footprints allowed)
		)
		(placement
			(enabled no)
			(sheetname "")
		)
		(fill yes
			(thermal_gap 0.5)
			(thermal_bridge_width 0.5)
			(island_removal_mode 0)
		)
		(polygon
			(pts
				(arc
					(start 19.033998 -228.121464)
					(mid 19.048877 -228.157385)
					(end 19.084798 -228.172264)
				)
				(arc
					(start 20.484338 -228.172264)
					(mid 20.520259 -228.157385)
					(end 20.535138 -228.121464)
				)
				(arc
					(start 20.535138 -227.712524)
					(mid 20.520259 -227.676603)
					(end 20.484338 -227.661724)
				)
				(arc
					(start 19.084798 -227.661724)
					(mid 19.048877 -227.676603)
					(end 19.033998 -227.712524)
				)
			)
		)
	)
	(zone
		(layers "In1.Cu" "In2.Cu")
		(hatch none 0.5)
		(connect_pads
			(clearance 0)
		)
		(min_thickness 0.25)
		(keepout
			(tracks not_allowed)
			(vias allowed)
			(pads allowed)
			(copperpour not_allowed)
			(footprints allowed)
		)
		(placement
			(enabled no)
			(sheetname "")
		)
		(fill yes
			(thermal_gap 0.5)
			(thermal_bridge_width 0.5)
			(island_removal_mode 0)
		)
		(polygon
			(pts
				(arc
					(start 259.430266 -195.821554)
					(mid 259.445145 -195.857475)
					(end 259.481066 -195.872354)
				)
				(arc
					(start 260.880606 -195.872354)
					(mid 260.916527 -195.857475)
					(end 260.931406 -195.821554)
				)
				(arc
					(start 260.931406 -195.412614)
					(mid 260.916527 -195.376693)
					(end 260.880606 -195.361814)
				)
				(arc
					(start 259.481066 -195.361814)
					(mid 259.445145 -195.376693)
					(end 259.430266 -195.412614)
				)
			)
		)
	)
	(zone
		(layers "In1.Cu" "In2.Cu")
		(hatch none 0.5)
		(connect_pads
			(clearance 0)
		)
		(min_thickness 0.25)
		(keepout
			(tracks not_allowed)
			(vias allowed)
			(pads allowed)
			(copperpour not_allowed)
			(footprints allowed)
		)
		(placement
			(enabled no)
			(sheetname "")
		)
		(fill yes
			(thermal_gap 0.5)
			(thermal_bridge_width 0.5)
			(island_removal_mode 0)
		)
		(polygon
			(pts
				(arc
					(start 180.69433 -316.521338)
					(mid 180.709209 -316.557259)
					(end 180.74513 -316.572138)
				)
				(arc
					(start 182.14467 -316.572138)
					(mid 182.180591 -316.557259)
					(end 182.19547 -316.521338)
				)
				(arc
					(start 182.19547 -316.112398)
					(mid 182.180591 -316.076477)
					(end 182.14467 -316.061598)
				)
				(arc
					(start 180.74513 -316.061598)
					(mid 180.709209 -316.076477)
					(end 180.69433 -316.112398)
				)
			)
		)
	)
	(zone
		(layers "In1.Cu" "In2.Cu")
		(hatch none 0.5)
		(connect_pads
			(clearance 0)
		)
		(min_thickness 0.25)
		(keepout
			(tracks not_allowed)
			(vias allowed)
			(pads allowed)
			(copperpour not_allowed)
			(footprints allowed)
		)
		(placement
			(enabled no)
			(sheetname "")
		)
		(fill yes
			(thermal_gap 0.5)
			(thermal_bridge_width 0.5)
			(island_removal_mode 0)
		)
		(polygon
			(pts
				(arc
					(start 297.149266 -276.571456)
					(mid 297.164145 -276.607377)
					(end 297.200066 -276.622256)
				)
				(arc
					(start 298.599606 -276.622256)
					(mid 298.635527 -276.607377)
					(end 298.650406 -276.571456)
				)
				(arc
					(start 298.650406 -276.162516)
					(mid 298.635527 -276.126595)
					(end 298.599606 -276.111716)
				)
				(arc
					(start 297.200066 -276.111716)
					(mid 297.164145 -276.126595)
					(end 297.149266 -276.162516)
				)
			)
		)
	)
	(zone
		(layers "In1.Cu" "In2.Cu")
		(hatch none 0.5)
		(connect_pads
			(clearance 0)
		)
		(min_thickness 0.25)
		(keepout
			(tracks not_allowed)
			(vias allowed)
			(pads allowed)
			(copperpour not_allowed)
			(footprints allowed)
		)
		(placement
			(enabled no)
			(sheetname "")
		)
		(fill yes
			(thermal_gap 0.5)
			(thermal_bridge_width 0.5)
			(island_removal_mode 0)
		)
		(polygon
			(pts
				(arc
					(start 180.69433 -291.8714)
					(mid 180.709209 -291.907321)
					(end 180.74513 -291.9222)
				)
				(arc
					(start 182.14467 -291.9222)
					(mid 182.180591 -291.907321)
					(end 182.19547 -291.8714)
				)
				(arc
					(start 182.19547 -291.46246)
					(mid 182.180591 -291.426539)
					(end 182.14467 -291.41166)
				)
				(arc
					(start 180.74513 -291.41166)
					(mid 180.709209 -291.426539)
					(end 180.69433 -291.46246)
				)
			)
		)
	)
	(zone
		(layers "In1.Cu" "In2.Cu")
		(hatch none 0.5)
		(connect_pads
			(clearance 0)
		)
		(min_thickness 0.25)
		(keepout
			(tracks not_allowed)
			(vias allowed)
			(pads allowed)
			(copperpour not_allowed)
			(footprints allowed)
		)
		(placement
			(enabled no)
			(sheetname "")
		)
		(fill yes
			(thermal_gap 0.5)
			(thermal_bridge_width 0.5)
			(island_removal_mode 0)
		)
		(polygon
			(pts
				(arc
					(start 173.15053 -247.671336)
					(mid 173.165409 -247.707257)
					(end 173.20133 -247.722136)
				)
				(arc
					(start 174.60087 -247.722136)
					(mid 174.636791 -247.707257)
					(end 174.65167 -247.671336)
				)
				(arc
					(start 174.65167 -247.262396)
					(mid 174.636791 -247.226475)
					(end 174.60087 -247.211596)
				)
				(arc
					(start 173.20133 -247.211596)
					(mid 173.165409 -247.226475)
					(end 173.15053 -247.262396)
				)
			)
		)
	)
	(zone
		(layers "In1.Cu" "In2.Cu")
		(hatch none 0.5)
		(connect_pads
			(clearance 0)
		)
		(min_thickness 0.25)
		(keepout
			(tracks not_allowed)
			(vias allowed)
			(pads allowed)
			(copperpour not_allowed)
			(footprints allowed)
		)
		(placement
			(enabled no)
			(sheetname "")
		)
		(fill yes
			(thermal_gap 0.5)
			(thermal_bridge_width 0.5)
			(island_removal_mode 0)
		)
		(polygon
			(pts
				(arc
					(start 293.049198 -249.371358)
					(mid 293.064077 -249.407279)
					(end 293.099998 -249.422158)
				)
				(arc
					(start 294.499538 -249.422158)
					(mid 294.535459 -249.407279)
					(end 294.550338 -249.371358)
				)
				(arc
					(start 294.550338 -248.962418)
					(mid 294.535459 -248.926497)
					(end 294.499538 -248.911618)
				)
				(arc
					(start 293.099998 -248.911618)
					(mid 293.064077 -248.926497)
					(end 293.049198 -248.962418)
				)
			)
		)
	)
	(zone
		(layers "In1.Cu" "In2.Cu")
		(hatch none 0.5)
		(connect_pads
			(clearance 0)
		)
		(min_thickness 0.25)
		(keepout
			(tracks not_allowed)
			(vias allowed)
			(pads allowed)
			(copperpour not_allowed)
			(footprints allowed)
		)
		(placement
			(enabled no)
			(sheetname "")
		)
		(fill yes
			(thermal_gap 0.5)
			(thermal_bridge_width 0.5)
			(island_removal_mode 0)
		)
		(polygon
			(pts
				(arc
					(start 428.634398 -241.721386)
					(mid 428.649277 -241.757307)
					(end 428.685198 -241.772186)
				)
				(arc
					(start 430.084738 -241.772186)
					(mid 430.120659 -241.757307)
					(end 430.135538 -241.721386)
				)
				(arc
					(start 430.135538 -241.312446)
					(mid 430.120659 -241.276525)
					(end 430.084738 -241.261646)
				)
				(arc
					(start 428.685198 -241.261646)
					(mid 428.649277 -241.276525)
					(end 428.634398 -241.312446)
				)
			)
		)
	)
	(zone
		(layers "In1.Cu" "In2.Cu")
		(hatch none 0.5)
		(connect_pads
			(clearance 0)
		)
		(min_thickness 0.25)
		(keepout
			(tracks not_allowed)
			(vias allowed)
			(pads allowed)
			(copperpour not_allowed)
			(footprints allowed)
		)
		(placement
			(enabled no)
			(sheetname "")
		)
		(fill yes
			(thermal_gap 0.5)
			(thermal_bridge_width 0.5)
			(island_removal_mode 0)
		)
		(polygon
			(pts
				(arc
					(start 214.969598 -246.821452)
					(mid 214.984477 -246.857373)
					(end 215.020398 -246.872252)
				)
				(arc
					(start 216.419938 -246.872252)
					(mid 216.455859 -246.857373)
					(end 216.470738 -246.821452)
				)
				(arc
					(start 216.470738 -246.412512)
					(mid 216.455859 -246.376591)
					(end 216.419938 -246.361712)
				)
				(arc
					(start 215.020398 -246.361712)
					(mid 214.984477 -246.376591)
					(end 214.969598 -246.412512)
				)
			)
		)
	)
	(zone
		(layers "In1.Cu" "In2.Cu")
		(hatch none 0.5)
		(connect_pads
			(clearance 0)
		)
		(min_thickness 0.25)
		(keepout
			(tracks not_allowed)
			(vias allowed)
			(pads allowed)
			(copperpour not_allowed)
			(footprints allowed)
		)
		(placement
			(enabled no)
			(sheetname "")
		)
		(fill yes
			(thermal_gap 0.5)
			(thermal_bridge_width 0.5)
			(island_removal_mode 0)
		)
		(polygon
			(pts
				(arc
					(start 274.517866 -206.871316)
					(mid 274.532745 -206.907237)
					(end 274.568666 -206.922116)
				)
				(arc
					(start 275.968206 -206.922116)
					(mid 276.004127 -206.907237)
					(end 276.019006 -206.871316)
				)
				(arc
					(start 276.019006 -206.462376)
					(mid 276.004127 -206.426455)
					(end 275.968206 -206.411576)
				)
				(arc
					(start 274.568666 -206.411576)
					(mid 274.532745 -206.426455)
					(end 274.517866 -206.462376)
				)
			)
		)
	)
	(zone
		(layers "In1.Cu" "In2.Cu")
		(hatch none 0.5)
		(connect_pads
			(clearance 0)
		)
		(min_thickness 0.25)
		(keepout
			(tracks not_allowed)
			(vias allowed)
			(pads allowed)
			(copperpour not_allowed)
			(footprints allowed)
		)
		(placement
			(enabled no)
			(sheetname "")
		)
		(fill yes
			(thermal_gap 0.5)
			(thermal_bridge_width 0.5)
			(island_removal_mode 0)
		)
		(polygon
			(pts
				(arc
					(start 259.430266 -211.121498)
					(mid 259.445145 -211.157419)
					(end 259.481066 -211.172298)
				)
				(arc
					(start 260.880606 -211.172298)
					(mid 260.916527 -211.157419)
					(end 260.931406 -211.121498)
				)
				(arc
					(start 260.931406 -210.712558)
					(mid 260.916527 -210.676637)
					(end 260.880606 -210.661758)
				)
				(arc
					(start 259.481066 -210.661758)
					(mid 259.445145 -210.676637)
					(end 259.430266 -210.712558)
				)
			)
		)
	)
	(zone
		(layers "In1.Cu" "In2.Cu")
		(hatch none 0.5)
		(connect_pads
			(clearance 0)
		)
		(min_thickness 0.25)
		(keepout
			(tracks not_allowed)
			(vias allowed)
			(pads allowed)
			(copperpour not_allowed)
			(footprints allowed)
		)
		(placement
			(enabled no)
			(sheetname "")
		)
		(fill yes
			(thermal_gap 0.5)
			(thermal_bridge_width 0.5)
			(island_removal_mode 0)
		)
		(polygon
			(pts
				(arc
					(start 255.330198 -284.221428)
					(mid 255.345077 -284.257349)
					(end 255.380998 -284.272228)
				)
				(arc
					(start 256.780538 -284.272228)
					(mid 256.816459 -284.257349)
					(end 256.831338 -284.221428)
				)
				(arc
					(start 256.831338 -283.812488)
					(mid 256.816459 -283.776567)
					(end 256.780538 -283.761688)
				)
				(arc
					(start 255.380998 -283.761688)
					(mid 255.345077 -283.776567)
					(end 255.330198 -283.812488)
				)
			)
		)
	)
	(zone
		(layers "In1.Cu" "In2.Cu")
		(hatch none 0.5)
		(connect_pads
			(clearance 0)
		)
		(min_thickness 0.25)
		(keepout
			(tracks not_allowed)
			(vias allowed)
			(pads allowed)
			(copperpour not_allowed)
			(footprints allowed)
		)
		(placement
			(enabled no)
			(sheetname "")
		)
		(fill yes
			(thermal_gap 0.5)
			(thermal_bridge_width 0.5)
			(island_removal_mode 0)
		)
		(polygon
			(pts
				(arc
					(start 30.02153 -268.071346)
					(mid 30.036409 -268.107267)
					(end 30.07233 -268.122146)
				)
				(arc
					(start 31.47187 -268.122146)
					(mid 31.507791 -268.107267)
					(end 31.52267 -268.071346)
				)
				(arc
					(start 31.52267 -267.662406)
					(mid 31.507791 -267.626485)
					(end 31.47187 -267.611606)
				)
				(arc
					(start 30.07233 -267.611606)
					(mid 30.036409 -267.626485)
					(end 30.02153 -267.662406)
				)
			)
		)
	)
	(zone
		(layers "In1.Cu" "In2.Cu")
		(hatch none 0.5)
		(connect_pads
			(clearance 0)
		)
		(min_thickness 0.25)
		(keepout
			(tracks not_allowed)
			(vias allowed)
			(pads allowed)
			(copperpour not_allowed)
			(footprints allowed)
		)
		(placement
			(enabled no)
			(sheetname "")
		)
		(fill yes
			(thermal_gap 0.5)
			(thermal_bridge_width 0.5)
			(island_removal_mode 0)
		)
		(polygon
			(pts
				(arc
					(start 14.93393 -196.671438)
					(mid 14.948809 -196.707359)
					(end 14.98473 -196.722238)
				)
				(arc
					(start 16.38427 -196.722238)
					(mid 16.420191 -196.707359)
					(end 16.43507 -196.671438)
				)
				(arc
					(start 16.43507 -196.262498)
					(mid 16.420191 -196.226577)
					(end 16.38427 -196.211698)
				)
				(arc
					(start 14.98473 -196.211698)
					(mid 14.948809 -196.226577)
					(end 14.93393 -196.262498)
				)
			)
		)
	)
	(zone
		(layers "In1.Cu" "In2.Cu")
		(hatch none 0.5)
		(connect_pads
			(clearance 0)
		)
		(min_thickness 0.25)
		(keepout
			(tracks not_allowed)
			(vias allowed)
			(pads allowed)
			(copperpour not_allowed)
			(footprints allowed)
		)
		(placement
			(enabled no)
			(sheetname "")
		)
		(fill yes
			(thermal_gap 0.5)
			(thermal_bridge_width 0.5)
			(island_removal_mode 0)
		)
		(polygon
			(pts
				(arc
					(start 285.505398 -285.071312)
					(mid 285.520277 -285.107233)
					(end 285.556198 -285.122112)
				)
				(arc
					(start 286.955738 -285.122112)
					(mid 286.991659 -285.107233)
					(end 287.006538 -285.071312)
				)
				(arc
					(start 287.006538 -284.662372)
					(mid 286.991659 -284.626451)
					(end 286.955738 -284.611572)
				)
				(arc
					(start 285.556198 -284.611572)
					(mid 285.520277 -284.626451)
					(end 285.505398 -284.662372)
				)
			)
		)
	)
	(zone
		(layers "In1.Cu" "In2.Cu")
		(hatch none 0.5)
		(connect_pads
			(clearance 0)
		)
		(min_thickness 0.25)
		(keepout
			(tracks not_allowed)
			(vias allowed)
			(pads allowed)
			(copperpour not_allowed)
			(footprints allowed)
		)
		(placement
			(enabled no)
			(sheetname "")
		)
		(fill yes
			(thermal_gap 0.5)
			(thermal_bridge_width 0.5)
			(island_removal_mode 0)
		)
		(polygon
			(pts
				(arc
					(start 199.881998 -260.421374)
					(mid 199.896877 -260.457295)
					(end 199.932798 -260.472174)
				)
				(arc
					(start 201.332338 -260.472174)
					(mid 201.368259 -260.457295)
					(end 201.383138 -260.421374)
				)
				(arc
					(start 201.383138 -260.012434)
					(mid 201.368259 -259.976513)
					(end 201.332338 -259.961634)
				)
				(arc
					(start 199.932798 -259.961634)
					(mid 199.896877 -259.976513)
					(end 199.881998 -260.012434)
				)
			)
		)
	)
	(zone
		(layers "In1.Cu" "In2.Cu")
		(hatch none 0.5)
		(connect_pads
			(clearance 0)
		)
		(min_thickness 0.25)
		(keepout
			(tracks not_allowed)
			(vias allowed)
			(pads allowed)
			(copperpour not_allowed)
			(footprints allowed)
		)
		(placement
			(enabled no)
			(sheetname "")
		)
		(fill yes
			(thermal_gap 0.5)
			(thermal_bridge_width 0.5)
			(island_removal_mode 0)
		)
		(polygon
			(pts
				(arc
					(start 192.338198 -227.271326)
					(mid 192.353077 -227.307247)
					(end 192.388998 -227.322126)
				)
				(arc
					(start 193.788538 -227.322126)
					(mid 193.824459 -227.307247)
					(end 193.839338 -227.271326)
				)
				(arc
					(start 193.839338 -226.862386)
					(mid 193.824459 -226.826465)
					(end 193.788538 -226.811586)
				)
				(arc
					(start 192.388998 -226.811586)
					(mid 192.353077 -226.826465)
					(end 192.338198 -226.862386)
				)
			)
		)
	)
	(zone
		(layers "In1.Cu" "In2.Cu")
		(hatch none 0.5)
		(connect_pads
			(clearance 0)
		)
		(min_thickness 0.25)
		(keepout
			(tracks not_allowed)
			(vias allowed)
			(pads allowed)
			(copperpour not_allowed)
			(footprints allowed)
		)
		(placement
			(enabled no)
			(sheetname "")
		)
		(fill yes
			(thermal_gap 0.5)
			(thermal_bridge_width 0.5)
			(island_removal_mode 0)
		)
		(polygon
			(pts
				(arc
					(start 274.517866 -292.721538)
					(mid 274.532745 -292.757459)
					(end 274.568666 -292.772338)
				)
				(arc
					(start 275.968206 -292.772338)
					(mid 276.004127 -292.757459)
					(end 276.019006 -292.721538)
				)
				(arc
					(start 276.019006 -292.312598)
					(mid 276.004127 -292.276677)
					(end 275.968206 -292.261798)
				)
				(arc
					(start 274.568666 -292.261798)
					(mid 274.532745 -292.276677)
					(end 274.517866 -292.312598)
				)
			)
		)
	)
	(zone
		(layers "In1.Cu" "In2.Cu")
		(hatch none 0.5)
		(connect_pads
			(clearance 0)
		)
		(min_thickness 0.25)
		(keepout
			(tracks not_allowed)
			(vias allowed)
			(pads allowed)
			(copperpour not_allowed)
			(footprints allowed)
		)
		(placement
			(enabled no)
			(sheetname "")
		)
		(fill yes
			(thermal_gap 0.5)
			(thermal_bridge_width 0.5)
			(island_removal_mode 0)
		)
		(polygon
			(pts
				(arc
					(start 192.338198 -313.971432)
					(mid 192.353077 -314.007353)
					(end 192.388998 -314.022232)
				)
				(arc
					(start 193.788538 -314.022232)
					(mid 193.824459 -314.007353)
					(end 193.839338 -313.971432)
				)
				(arc
					(start 193.839338 -313.562492)
					(mid 193.824459 -313.526571)
					(end 193.788538 -313.511692)
				)
				(arc
					(start 192.388998 -313.511692)
					(mid 192.353077 -313.526571)
					(end 192.338198 -313.562492)
				)
			)
		)
	)
	(zone
		(layers "In1.Cu" "In2.Cu")
		(hatch none 0.5)
		(connect_pads
			(clearance 0)
		)
		(min_thickness 0.25)
		(keepout
			(tracks not_allowed)
			(vias allowed)
			(pads allowed)
			(copperpour not_allowed)
			(footprints allowed)
		)
		(placement
			(enabled no)
			(sheetname "")
		)
		(fill yes
			(thermal_gap 0.5)
			(thermal_bridge_width 0.5)
			(island_removal_mode 0)
		)
		(polygon
			(pts
				(arc
					(start 165.60673 -221.321376)
					(mid 165.621609 -221.357297)
					(end 165.65753 -221.372176)
				)
				(arc
					(start 167.05707 -221.372176)
					(mid 167.092991 -221.357297)
					(end 167.10787 -221.321376)
				)
				(arc
					(start 167.10787 -220.912436)
					(mid 167.092991 -220.876515)
					(end 167.05707 -220.861636)
				)
				(arc
					(start 165.65753 -220.861636)
					(mid 165.621609 -220.876515)
					(end 165.60673 -220.912436)
				)
			)
		)
	)
	(zone
		(layers "In1.Cu" "In2.Cu")
		(hatch none 0.5)
		(connect_pads
			(clearance 0)
		)
		(min_thickness 0.25)
		(keepout
			(tracks not_allowed)
			(vias allowed)
			(pads allowed)
			(copperpour not_allowed)
			(footprints allowed)
		)
		(placement
			(enabled no)
			(sheetname "")
		)
		(fill yes
			(thermal_gap 0.5)
			(thermal_bridge_width 0.5)
			(island_removal_mode 0)
		)
		(polygon
			(pts
				(arc
					(start 45.10913 -316.521338)
					(mid 45.124009 -316.557259)
					(end 45.15993 -316.572138)
				)
				(arc
					(start 46.55947 -316.572138)
					(mid 46.595391 -316.557259)
					(end 46.61027 -316.521338)
				)
				(arc
					(start 46.61027 -316.112398)
					(mid 46.595391 -316.076477)
					(end 46.55947 -316.061598)
				)
				(arc
					(start 45.15993 -316.061598)
					(mid 45.124009 -316.076477)
					(end 45.10913 -316.112398)
				)
			)
		)
	)
	(zone
		(layers "In1.Cu" "In2.Cu")
		(hatch none 0.5)
		(connect_pads
			(clearance 0)
		)
		(min_thickness 0.25)
		(keepout
			(tracks not_allowed)
			(vias allowed)
			(pads allowed)
			(copperpour not_allowed)
			(footprints allowed)
		)
		(placement
			(enabled no)
			(sheetname "")
		)
		(fill yes
			(thermal_gap 0.5)
			(thermal_bridge_width 0.5)
			(island_removal_mode 0)
		)
		(polygon
			(pts
				(arc
					(start 312.236866 -293.571422)
					(mid 312.251745 -293.607343)
					(end 312.287666 -293.622222)
				)
				(arc
					(start 313.687206 -293.622222)
					(mid 313.723127 -293.607343)
					(end 313.738006 -293.571422)
				)
				(arc
					(start 313.738006 -293.162482)
					(mid 313.723127 -293.126561)
					(end 313.687206 -293.111682)
				)
				(arc
					(start 312.287666 -293.111682)
					(mid 312.251745 -293.126561)
					(end 312.236866 -293.162482)
				)
			)
		)
	)
	(zone
		(layers "In1.Cu" "In2.Cu")
		(hatch none 0.5)
		(connect_pads
			(clearance 0)
		)
		(min_thickness 0.25)
		(keepout
			(tracks not_allowed)
			(vias allowed)
			(pads allowed)
			(copperpour not_allowed)
			(footprints allowed)
		)
		(placement
			(enabled no)
			(sheetname "")
		)
		(fill yes
			(thermal_gap 0.5)
			(thermal_bridge_width 0.5)
			(island_removal_mode 0)
		)
		(polygon
			(pts
				(arc
					(start 49.209198 -239.17148)
					(mid 49.224077 -239.207401)
					(end 49.259998 -239.22228)
				)
				(arc
					(start 50.659538 -239.22228)
					(mid 50.695459 -239.207401)
					(end 50.710338 -239.17148)
				)
				(arc
					(start 50.710338 -238.76254)
					(mid 50.695459 -238.726619)
					(end 50.659538 -238.71174)
				)
				(arc
					(start 49.259998 -238.71174)
					(mid 49.224077 -238.726619)
					(end 49.209198 -238.76254)
				)
			)
		)
	)
	(zone
		(layers "In1.Cu" "In2.Cu")
		(hatch none 0.5)
		(connect_pads
			(clearance 0)
		)
		(min_thickness 0.25)
		(keepout
			(tracks not_allowed)
			(vias allowed)
			(pads allowed)
			(copperpour not_allowed)
			(footprints allowed)
		)
		(placement
			(enabled no)
			(sheetname "")
		)
		(fill yes
			(thermal_gap 0.5)
			(thermal_bridge_width 0.5)
			(island_removal_mode 0)
		)
		(polygon
			(pts
				(arc
					(start 440.278266 -217.921332)
					(mid 440.293145 -217.957253)
					(end 440.329066 -217.972132)
				)
				(arc
					(start 441.728606 -217.972132)
					(mid 441.764527 -217.957253)
					(end 441.779406 -217.921332)
				)
				(arc
					(start 441.779406 -217.512392)
					(mid 441.764527 -217.476471)
					(end 441.728606 -217.461592)
				)
				(arc
					(start 440.329066 -217.461592)
					(mid 440.293145 -217.476471)
					(end 440.278266 -217.512392)
				)
			)
		)
	)
	(zone
		(layers "In1.Cu" "In2.Cu")
		(hatch none 0.5)
		(connect_pads
			(clearance 0)
		)
		(min_thickness 0.25)
		(keepout
			(tracks not_allowed)
			(vias allowed)
			(pads allowed)
			(copperpour not_allowed)
			(footprints allowed)
		)
		(placement
			(enabled no)
			(sheetname "")
		)
		(fill yes
			(thermal_gap 0.5)
			(thermal_bridge_width 0.5)
			(island_removal_mode 0)
		)
		(polygon
			(pts
				(arc
					(start 184.794398 -237.471458)
					(mid 184.809277 -237.507379)
					(end 184.845198 -237.522258)
				)
				(arc
					(start 186.244738 -237.522258)
					(mid 186.280659 -237.507379)
					(end 186.295538 -237.471458)
				)
				(arc
					(start 186.295538 -237.062518)
					(mid 186.280659 -237.026597)
					(end 186.244738 -237.011718)
				)
				(arc
					(start 184.845198 -237.011718)
					(mid 184.809277 -237.026597)
					(end 184.794398 -237.062518)
				)
			)
		)
	)
	(zone
		(layers "In1.Cu" "In2.Cu")
		(hatch none 0.5)
		(connect_pads
			(clearance 0)
		)
		(min_thickness 0.25)
		(keepout
			(tracks not_allowed)
			(vias allowed)
			(pads allowed)
			(copperpour not_allowed)
			(footprints allowed)
		)
		(placement
			(enabled no)
			(sheetname "")
		)
		(fill yes
			(thermal_gap 0.5)
			(thermal_bridge_width 0.5)
			(island_removal_mode 0)
		)
		(polygon
			(pts
				(arc
					(start 406.002998 -200.071482)
					(mid 406.017877 -200.107403)
					(end 406.053798 -200.122282)
				)
				(arc
					(start 407.453338 -200.122282)
					(mid 407.489259 -200.107403)
					(end 407.504138 -200.071482)
				)
				(arc
					(start 407.504138 -199.662542)
					(mid 407.489259 -199.626621)
					(end 407.453338 -199.611742)
				)
				(arc
					(start 406.053798 -199.611742)
					(mid 406.017877 -199.626621)
					(end 406.002998 -199.662542)
				)
			)
		)
	)
	(zone
		(layers "In1.Cu" "In2.Cu")
		(hatch none 0.5)
		(connect_pads
			(clearance 0)
		)
		(min_thickness 0.25)
		(keepout
			(tracks not_allowed)
			(vias allowed)
			(pads allowed)
			(copperpour not_allowed)
			(footprints allowed)
		)
		(placement
			(enabled no)
			(sheetname "")
		)
		(fill yes
			(thermal_gap 0.5)
			(thermal_bridge_width 0.5)
			(island_removal_mode 0)
		)
		(polygon
			(pts
				(arc
					(start 274.517866 -260.421374)
					(mid 274.532745 -260.457295)
					(end 274.568666 -260.472174)
				)
				(arc
					(start 275.968206 -260.472174)
					(mid 276.004127 -260.457295)
					(end 276.019006 -260.421374)
				)
				(arc
					(start 276.019006 -260.012434)
					(mid 276.004127 -259.976513)
					(end 275.968206 -259.961634)
				)
				(arc
					(start 274.568666 -259.961634)
					(mid 274.532745 -259.976513)
					(end 274.517866 -260.012434)
				)
			)
		)
	)
	(zone
		(layers "In1.Cu" "In2.Cu")
		(hatch none 0.5)
		(connect_pads
			(clearance 0)
		)
		(min_thickness 0.25)
		(keepout
			(tracks not_allowed)
			(vias allowed)
			(pads allowed)
			(copperpour not_allowed)
			(footprints allowed)
		)
		(placement
			(enabled no)
			(sheetname "")
		)
		(fill yes
			(thermal_gap 0.5)
			(thermal_bridge_width 0.5)
			(island_removal_mode 0)
		)
		(polygon
			(pts
				(arc
					(start 293.049198 -228.971348)
					(mid 293.064077 -229.007269)
					(end 293.099998 -229.022148)
				)
				(arc
					(start 294.499538 -229.022148)
					(mid 294.535459 -229.007269)
					(end 294.550338 -228.971348)
				)
				(arc
					(start 294.550338 -228.562408)
					(mid 294.535459 -228.526487)
					(end 294.499538 -228.511608)
				)
				(arc
					(start 293.099998 -228.511608)
					(mid 293.064077 -228.526487)
					(end 293.049198 -228.562408)
				)
			)
		)
	)
	(zone
		(layers "In1.Cu" "In2.Cu")
		(hatch none 0.5)
		(connect_pads
			(clearance 0)
		)
		(min_thickness 0.25)
		(keepout
			(tracks not_allowed)
			(vias allowed)
			(pads allowed)
			(copperpour not_allowed)
			(footprints allowed)
		)
		(placement
			(enabled no)
			(sheetname "")
		)
		(fill yes
			(thermal_gap 0.5)
			(thermal_bridge_width 0.5)
			(island_removal_mode 0)
		)
		(polygon
			(pts
				(arc
					(start 30.02153 -301.221394)
					(mid 30.036409 -301.257315)
					(end 30.07233 -301.272194)
				)
				(arc
					(start 31.47187 -301.272194)
					(mid 31.507791 -301.257315)
					(end 31.52267 -301.221394)
				)
				(arc
					(start 31.52267 -300.812454)
					(mid 31.507791 -300.776533)
					(end 31.47187 -300.761654)
				)
				(arc
					(start 30.07233 -300.761654)
					(mid 30.036409 -300.776533)
					(end 30.02153 -300.812454)
				)
			)
		)
	)
	(zone
		(layers "In1.Cu" "In2.Cu")
		(hatch none 0.5)
		(connect_pads
			(clearance 0)
		)
		(min_thickness 0.25)
		(keepout
			(tracks not_allowed)
			(vias allowed)
			(pads allowed)
			(copperpour not_allowed)
			(footprints allowed)
		)
		(placement
			(enabled no)
			(sheetname "")
		)
		(fill yes
			(thermal_gap 0.5)
			(thermal_bridge_width 0.5)
			(island_removal_mode 0)
		)
		(polygon
			(pts
				(arc
					(start 428.634398 -302.921416)
					(mid 428.649277 -302.957337)
					(end 428.685198 -302.972216)
				)
				(arc
					(start 430.084738 -302.972216)
					(mid 430.120659 -302.957337)
					(end 430.135538 -302.921416)
				)
				(arc
					(start 430.135538 -302.512476)
					(mid 430.120659 -302.476555)
					(end 430.084738 -302.461676)
				)
				(arc
					(start 428.685198 -302.461676)
					(mid 428.649277 -302.476555)
					(end 428.634398 -302.512476)
				)
			)
		)
	)
	(zone
		(layers "In1.Cu" "In2.Cu")
		(hatch none 0.5)
		(connect_pads
			(clearance 0)
		)
		(min_thickness 0.25)
		(keepout
			(tracks not_allowed)
			(vias allowed)
			(pads allowed)
			(copperpour not_allowed)
			(footprints allowed)
		)
		(placement
			(enabled no)
			(sheetname "")
		)
		(fill yes
			(thermal_gap 0.5)
			(thermal_bridge_width 0.5)
			(island_removal_mode 0)
		)
		(polygon
			(pts
				(arc
					(start 26.577798 -208.571338)
					(mid 26.592677 -208.607259)
					(end 26.628598 -208.622138)
				)
				(arc
					(start 28.028138 -208.622138)
					(mid 28.064059 -208.607259)
					(end 28.078938 -208.571338)
				)
				(arc
					(start 28.078938 -208.162398)
					(mid 28.064059 -208.126477)
					(end 28.028138 -208.111598)
				)
				(arc
					(start 26.628598 -208.111598)
					(mid 26.592677 -208.126477)
					(end 26.577798 -208.162398)
				)
			)
		)
	)
	(zone
		(layers "In1.Cu" "In2.Cu")
		(hatch none 0.5)
		(connect_pads
			(clearance 0)
		)
		(min_thickness 0.25)
		(keepout
			(tracks not_allowed)
			(vias allowed)
			(pads allowed)
			(copperpour not_allowed)
			(footprints allowed)
		)
		(placement
			(enabled no)
			(sheetname "")
		)
		(fill yes
			(thermal_gap 0.5)
			(thermal_bridge_width 0.5)
			(island_removal_mode 0)
		)
		(polygon
			(pts
				(arc
					(start 285.505398 -277.42134)
					(mid 285.520277 -277.457261)
					(end 285.556198 -277.47214)
				)
				(arc
					(start 286.955738 -277.47214)
					(mid 286.991659 -277.457261)
					(end 287.006538 -277.42134)
				)
				(arc
					(start 287.006538 -277.0124)
					(mid 286.991659 -276.976479)
					(end 286.955738 -276.9616)
				)
				(arc
					(start 285.556198 -276.9616)
					(mid 285.520277 -276.976479)
					(end 285.505398 -277.0124)
				)
			)
		)
	)
	(zone
		(layers "In1.Cu" "In2.Cu")
		(hatch none 0.5)
		(connect_pads
			(clearance 0)
		)
		(min_thickness 0.25)
		(keepout
			(tracks not_allowed)
			(vias allowed)
			(pads allowed)
			(copperpour not_allowed)
			(footprints allowed)
		)
		(placement
			(enabled no)
			(sheetname "")
		)
		(fill yes
			(thermal_gap 0.5)
			(thermal_bridge_width 0.5)
			(island_removal_mode 0)
		)
		(polygon
			(pts
				(arc
					(start 262.873998 -245.971314)
					(mid 262.888877 -246.007235)
					(end 262.924798 -246.022114)
				)
				(arc
					(start 264.324338 -246.022114)
					(mid 264.360259 -246.007235)
					(end 264.375138 -245.971314)
				)
				(arc
					(start 264.375138 -245.562374)
					(mid 264.360259 -245.526453)
					(end 264.324338 -245.511574)
				)
				(arc
					(start 262.924798 -245.511574)
					(mid 262.888877 -245.526453)
					(end 262.873998 -245.562374)
				)
			)
		)
	)
	(zone
		(layers "In1.Cu" "In2.Cu")
		(hatch none 0.5)
		(connect_pads
			(clearance 0)
		)
		(min_thickness 0.25)
		(keepout
			(tracks not_allowed)
			(vias allowed)
			(pads allowed)
			(copperpour not_allowed)
			(footprints allowed)
		)
		(placement
			(enabled no)
			(sheetname "")
		)
		(fill yes
			(thermal_gap 0.5)
			(thermal_bridge_width 0.5)
			(island_removal_mode 0)
		)
		(polygon
			(pts
				(arc
					(start 162.162998 -306.32146)
					(mid 162.177877 -306.357381)
					(end 162.213798 -306.37226)
				)
				(arc
					(start 163.613338 -306.37226)
					(mid 163.649259 -306.357381)
					(end 163.664138 -306.32146)
				)
				(arc
					(start 163.664138 -305.91252)
					(mid 163.649259 -305.876599)
					(end 163.613338 -305.86172)
				)
				(arc
					(start 162.213798 -305.86172)
					(mid 162.177877 -305.876599)
					(end 162.162998 -305.91252)
				)
			)
		)
	)
	(zone
		(layers "In1.Cu" "In2.Cu")
		(hatch none 0.5)
		(connect_pads
			(clearance 0)
		)
		(min_thickness 0.25)
		(keepout
			(tracks not_allowed)
			(vias allowed)
			(pads allowed)
			(copperpour not_allowed)
			(footprints allowed)
		)
		(placement
			(enabled no)
			(sheetname "")
		)
		(fill yes
			(thermal_gap 0.5)
			(thermal_bridge_width 0.5)
			(island_removal_mode 0)
		)
		(polygon
			(pts
				(arc
					(start 436.178198 -211.971382)
					(mid 436.193077 -212.007303)
					(end 436.228998 -212.022182)
				)
				(arc
					(start 437.628538 -212.022182)
					(mid 437.664459 -212.007303)
					(end 437.679338 -211.971382)
				)
				(arc
					(start 437.679338 -211.562442)
					(mid 437.664459 -211.526521)
					(end 437.628538 -211.511642)
				)
				(arc
					(start 436.228998 -211.511642)
					(mid 436.193077 -211.526521)
					(end 436.178198 -211.562442)
				)
			)
		)
	)
	(zone
		(layers "In1.Cu" "In2.Cu")
		(hatch none 0.5)
		(connect_pads
			(clearance 0)
		)
		(min_thickness 0.25)
		(keepout
			(tracks not_allowed)
			(vias allowed)
			(pads allowed)
			(copperpour not_allowed)
			(footprints allowed)
		)
		(placement
			(enabled no)
			(sheetname "")
		)
		(fill yes
			(thermal_gap 0.5)
			(thermal_bridge_width 0.5)
			(island_removal_mode 0)
		)
		(polygon
			(pts
				(arc
					(start 312.236866 -250.221496)
					(mid 312.251745 -250.257417)
					(end 312.287666 -250.272296)
				)
				(arc
					(start 313.687206 -250.272296)
					(mid 313.723127 -250.257417)
					(end 313.738006 -250.221496)
				)
				(arc
					(start 313.738006 -249.812556)
					(mid 313.723127 -249.776635)
					(end 313.687206 -249.761756)
				)
				(arc
					(start 312.287666 -249.761756)
					(mid 312.251745 -249.776635)
					(end 312.236866 -249.812556)
				)
			)
		)
	)
	(zone
		(layers "In1.Cu" "In2.Cu")
		(hatch none 0.5)
		(connect_pads
			(clearance 0)
		)
		(min_thickness 0.25)
		(keepout
			(tracks not_allowed)
			(vias allowed)
			(pads allowed)
			(copperpour not_allowed)
			(footprints allowed)
		)
		(placement
			(enabled no)
			(sheetname "")
		)
		(fill yes
			(thermal_gap 0.5)
			(thermal_bridge_width 0.5)
			(island_removal_mode 0)
		)
		(polygon
			(pts
				(arc
					(start 312.236866 -245.12143)
					(mid 312.251745 -245.157351)
					(end 312.287666 -245.17223)
				)
				(arc
					(start 313.687206 -245.17223)
					(mid 313.723127 -245.157351)
					(end 313.738006 -245.12143)
				)
				(arc
					(start 313.738006 -244.71249)
					(mid 313.723127 -244.676569)
					(end 313.687206 -244.66169)
				)
				(arc
					(start 312.287666 -244.66169)
					(mid 312.251745 -244.676569)
					(end 312.236866 -244.71249)
				)
			)
		)
	)
	(zone
		(layers "In1.Cu" "In2.Cu")
		(hatch none 0.5)
		(connect_pads
			(clearance 0)
		)
		(min_thickness 0.25)
		(keepout
			(tracks not_allowed)
			(vias allowed)
			(pads allowed)
			(copperpour not_allowed)
			(footprints allowed)
		)
		(placement
			(enabled no)
			(sheetname "")
		)
		(fill yes
			(thermal_gap 0.5)
			(thermal_bridge_width 0.5)
			(island_removal_mode 0)
		)
		(polygon
			(pts
				(arc
					(start 285.505398 -282.521406)
					(mid 285.520277 -282.557327)
					(end 285.556198 -282.572206)
				)
				(arc
					(start 286.955738 -282.572206)
					(mid 286.991659 -282.557327)
					(end 287.006538 -282.521406)
				)
				(arc
					(start 287.006538 -282.112466)
					(mid 286.991659 -282.076545)
					(end 286.955738 -282.061666)
				)
				(arc
					(start 285.556198 -282.061666)
					(mid 285.520277 -282.076545)
					(end 285.505398 -282.112466)
				)
			)
		)
	)
	(zone
		(layers "In1.Cu" "In2.Cu")
		(hatch none 0.5)
		(connect_pads
			(clearance 0)
		)
		(min_thickness 0.25)
		(keepout
			(tracks not_allowed)
			(vias allowed)
			(pads allowed)
			(copperpour not_allowed)
			(footprints allowed)
		)
		(placement
			(enabled no)
			(sheetname "")
		)
		(fill yes
			(thermal_gap 0.5)
			(thermal_bridge_width 0.5)
			(island_removal_mode 0)
		)
		(polygon
			(pts
				(arc
					(start 60.19673 -196.671438)
					(mid 60.211609 -196.707359)
					(end 60.24753 -196.722238)
				)
				(arc
					(start 61.64707 -196.722238)
					(mid 61.682991 -196.707359)
					(end 61.69787 -196.671438)
				)
				(arc
					(start 61.69787 -196.262498)
					(mid 61.682991 -196.226577)
					(end 61.64707 -196.211698)
				)
				(arc
					(start 60.24753 -196.211698)
					(mid 60.211609 -196.226577)
					(end 60.19673 -196.262498)
				)
			)
		)
	)
	(zone
		(layers "In1.Cu" "In2.Cu")
		(hatch none 0.5)
		(connect_pads
			(clearance 0)
		)
		(min_thickness 0.25)
		(keepout
			(tracks not_allowed)
			(vias allowed)
			(pads allowed)
			(copperpour not_allowed)
			(footprints allowed)
		)
		(placement
			(enabled no)
			(sheetname "")
		)
		(fill yes
			(thermal_gap 0.5)
			(thermal_bridge_width 0.5)
			(island_removal_mode 0)
		)
		(polygon
			(pts
				(arc
					(start 22.47773 -224.72142)
					(mid 22.492609 -224.757341)
					(end 22.52853 -224.77222)
				)
				(arc
					(start 23.92807 -224.77222)
					(mid 23.963991 -224.757341)
					(end 23.97887 -224.72142)
				)
				(arc
					(start 23.97887 -224.31248)
					(mid 23.963991 -224.276559)
					(end 23.92807 -224.26168)
				)
				(arc
					(start 22.52853 -224.26168)
					(mid 22.492609 -224.276559)
					(end 22.47773 -224.31248)
				)
			)
		)
	)
	(zone
		(layers "In1.Cu" "In2.Cu")
		(hatch none 0.5)
		(connect_pads
			(clearance 0)
		)
		(min_thickness 0.25)
		(keepout
			(tracks not_allowed)
			(vias allowed)
			(pads allowed)
			(copperpour not_allowed)
			(footprints allowed)
		)
		(placement
			(enabled no)
			(sheetname "")
		)
		(fill yes
			(thermal_gap 0.5)
			(thermal_bridge_width 0.5)
			(island_removal_mode 0)
		)
		(polygon
			(pts
				(arc
					(start 432.734466 -220.471492)
					(mid 432.749345 -220.507413)
					(end 432.785266 -220.522292)
				)
				(arc
					(start 434.184806 -220.522292)
					(mid 434.220727 -220.507413)
					(end 434.235606 -220.471492)
				)
				(arc
					(start 434.235606 -220.062552)
					(mid 434.220727 -220.026631)
					(end 434.184806 -220.011752)
				)
				(arc
					(start 432.785266 -220.011752)
					(mid 432.749345 -220.026631)
					(end 432.734466 -220.062552)
				)
			)
		)
	)
	(zone
		(layers "In1.Cu" "In2.Cu")
		(hatch none 0.5)
		(connect_pads
			(clearance 0)
		)
		(min_thickness 0.25)
		(keepout
			(tracks not_allowed)
			(vias allowed)
			(pads allowed)
			(copperpour not_allowed)
			(footprints allowed)
		)
		(placement
			(enabled no)
			(sheetname "")
		)
		(fill yes
			(thermal_gap 0.5)
			(thermal_bridge_width 0.5)
			(island_removal_mode 0)
		)
		(polygon
			(pts
				(arc
					(start 165.60673 -262.971534)
					(mid 165.621609 -263.007455)
					(end 165.65753 -263.022334)
				)
				(arc
					(start 167.05707 -263.022334)
					(mid 167.092991 -263.007455)
					(end 167.10787 -262.971534)
				)
				(arc
					(start 167.10787 -262.562594)
					(mid 167.092991 -262.526673)
					(end 167.05707 -262.511794)
				)
				(arc
					(start 165.65753 -262.511794)
					(mid 165.621609 -262.526673)
					(end 165.60673 -262.562594)
				)
			)
		)
	)
	(zone
		(layers "In1.Cu" "In2.Cu")
		(hatch none 0.5)
		(connect_pads
			(clearance 0)
		)
		(min_thickness 0.25)
		(keepout
			(tracks not_allowed)
			(vias allowed)
			(pads allowed)
			(copperpour not_allowed)
			(footprints allowed)
		)
		(placement
			(enabled no)
			(sheetname "")
		)
		(fill yes
			(thermal_gap 0.5)
			(thermal_bridge_width 0.5)
			(island_removal_mode 0)
		)
		(polygon
			(pts
				(arc
					(start 37.56533 -285.071312)
					(mid 37.580209 -285.107233)
					(end 37.61613 -285.122112)
				)
				(arc
					(start 39.01567 -285.122112)
					(mid 39.051591 -285.107233)
					(end 39.06647 -285.071312)
				)
				(arc
					(start 39.06647 -284.662372)
					(mid 39.051591 -284.626451)
					(end 39.01567 -284.611572)
				)
				(arc
					(start 37.61613 -284.611572)
					(mid 37.580209 -284.626451)
					(end 37.56533 -284.662372)
				)
			)
		)
	)
	(zone
		(layers "In1.Cu" "In2.Cu")
		(hatch none 0.5)
		(connect_pads
			(clearance 0)
		)
		(min_thickness 0.25)
		(keepout
			(tracks not_allowed)
			(vias allowed)
			(pads allowed)
			(copperpour not_allowed)
			(footprints allowed)
		)
		(placement
			(enabled no)
			(sheetname "")
		)
		(fill yes
			(thermal_gap 0.5)
			(thermal_bridge_width 0.5)
			(island_removal_mode 0)
		)
		(polygon
			(pts
				(arc
					(start 428.634398 -217.071448)
					(mid 428.649277 -217.107369)
					(end 428.685198 -217.122248)
				)
				(arc
					(start 430.084738 -217.122248)
					(mid 430.120659 -217.107369)
					(end 430.135538 -217.071448)
				)
				(arc
					(start 430.135538 -216.662508)
					(mid 430.120659 -216.626587)
					(end 430.084738 -216.611708)
				)
				(arc
					(start 428.685198 -216.611708)
					(mid 428.649277 -216.626587)
					(end 428.634398 -216.662508)
				)
			)
		)
	)
	(zone
		(layers "In1.Cu" "In2.Cu")
		(hatch none 0.5)
		(connect_pads
			(clearance 0)
		)
		(min_thickness 0.25)
		(keepout
			(tracks not_allowed)
			(vias allowed)
			(pads allowed)
			(copperpour not_allowed)
			(footprints allowed)
		)
		(placement
			(enabled no)
			(sheetname "")
		)
		(fill yes
			(thermal_gap 0.5)
			(thermal_bridge_width 0.5)
			(island_removal_mode 0)
		)
		(polygon
			(pts
				(arc
					(start 421.090598 -247.671336)
					(mid 421.105477 -247.707257)
					(end 421.141398 -247.722136)
				)
				(arc
					(start 422.540938 -247.722136)
					(mid 422.576859 -247.707257)
					(end 422.591738 -247.671336)
				)
				(arc
					(start 422.591738 -247.262396)
					(mid 422.576859 -247.226475)
					(end 422.540938 -247.211596)
				)
				(arc
					(start 421.141398 -247.211596)
					(mid 421.105477 -247.226475)
					(end 421.090598 -247.262396)
				)
			)
		)
	)
	(zone
		(layers "In1.Cu" "In2.Cu")
		(hatch none 0.5)
		(connect_pads
			(clearance 0)
		)
		(min_thickness 0.25)
		(keepout
			(tracks not_allowed)
			(vias allowed)
			(pads allowed)
			(copperpour not_allowed)
			(footprints allowed)
		)
		(placement
			(enabled no)
			(sheetname "")
		)
		(fill yes
			(thermal_gap 0.5)
			(thermal_bridge_width 0.5)
			(island_removal_mode 0)
		)
		(polygon
			(pts
				(arc
					(start 14.93393 -202.621388)
					(mid 14.948809 -202.657309)
					(end 14.98473 -202.672188)
				)
				(arc
					(start 16.38427 -202.672188)
					(mid 16.420191 -202.657309)
					(end 16.43507 -202.621388)
				)
				(arc
					(start 16.43507 -202.212448)
					(mid 16.420191 -202.176527)
					(end 16.38427 -202.161648)
				)
				(arc
					(start 14.98473 -202.161648)
					(mid 14.948809 -202.176527)
					(end 14.93393 -202.212448)
				)
			)
		)
	)
	(zone
		(layers "In1.Cu" "In2.Cu")
		(hatch none 0.5)
		(connect_pads
			(clearance 0)
		)
		(min_thickness 0.25)
		(keepout
			(tracks not_allowed)
			(vias allowed)
			(pads allowed)
			(copperpour not_allowed)
			(footprints allowed)
		)
		(placement
			(enabled no)
			(sheetname "")
		)
		(fill yes
			(thermal_gap 0.5)
			(thermal_bridge_width 0.5)
			(island_removal_mode 0)
		)
		(polygon
			(pts
				(arc
					(start 188.23813 -280.821384)
					(mid 188.253009 -280.857305)
					(end 188.28893 -280.872184)
				)
				(arc
					(start 189.68847 -280.872184)
					(mid 189.724391 -280.857305)
					(end 189.73927 -280.821384)
				)
				(arc
					(start 189.73927 -280.412444)
					(mid 189.724391 -280.376523)
					(end 189.68847 -280.361644)
				)
				(arc
					(start 188.28893 -280.361644)
					(mid 188.253009 -280.376523)
					(end 188.23813 -280.412444)
				)
			)
		)
	)
	(zone
		(layers "In1.Cu" "In2.Cu")
		(hatch none 0.5)
		(connect_pads
			(clearance 0)
		)
		(min_thickness 0.25)
		(keepout
			(tracks not_allowed)
			(vias allowed)
			(pads allowed)
			(copperpour not_allowed)
			(footprints allowed)
		)
		(placement
			(enabled no)
			(sheetname "")
		)
		(fill yes
			(thermal_gap 0.5)
			(thermal_bridge_width 0.5)
			(island_removal_mode 0)
		)
		(polygon
			(pts
				(arc
					(start 49.209198 -263.821418)
					(mid 49.224077 -263.857339)
					(end 49.259998 -263.872218)
				)
				(arc
					(start 50.659538 -263.872218)
					(mid 50.695459 -263.857339)
					(end 50.710338 -263.821418)
				)
				(arc
					(start 50.710338 -263.412478)
					(mid 50.695459 -263.376557)
					(end 50.659538 -263.361678)
				)
				(arc
					(start 49.259998 -263.361678)
					(mid 49.224077 -263.376557)
					(end 49.209198 -263.412478)
				)
			)
		)
	)
	(zone
		(layers "In1.Cu" "In2.Cu")
		(hatch none 0.5)
		(connect_pads
			(clearance 0)
		)
		(min_thickness 0.25)
		(keepout
			(tracks not_allowed)
			(vias allowed)
			(pads allowed)
			(copperpour not_allowed)
			(footprints allowed)
		)
		(placement
			(enabled no)
			(sheetname "")
		)
		(fill yes
			(thermal_gap 0.5)
			(thermal_bridge_width 0.5)
			(island_removal_mode 0)
		)
		(polygon
			(pts
				(arc
					(start 297.149266 -212.82152)
					(mid 297.164145 -212.857441)
					(end 297.200066 -212.87232)
				)
				(arc
					(start 298.599606 -212.87232)
					(mid 298.635527 -212.857441)
					(end 298.650406 -212.82152)
				)
				(arc
					(start 298.650406 -212.41258)
					(mid 298.635527 -212.376659)
					(end 298.599606 -212.36178)
				)
				(arc
					(start 297.200066 -212.36178)
					(mid 297.164145 -212.376659)
					(end 297.149266 -212.41258)
				)
			)
		)
	)
	(zone
		(layers "In1.Cu" "In2.Cu")
		(hatch none 0.5)
		(connect_pads
			(clearance 0)
		)
		(min_thickness 0.25)
		(keepout
			(tracks not_allowed)
			(vias allowed)
			(pads allowed)
			(copperpour not_allowed)
			(footprints allowed)
		)
		(placement
			(enabled no)
			(sheetname "")
		)
		(fill yes
			(thermal_gap 0.5)
			(thermal_bridge_width 0.5)
			(island_removal_mode 0)
		)
		(polygon
			(pts
				(arc
					(start 297.149266 -311.421526)
					(mid 297.164145 -311.457447)
					(end 297.200066 -311.472326)
				)
				(arc
					(start 298.599606 -311.472326)
					(mid 298.635527 -311.457447)
					(end 298.650406 -311.421526)
				)
				(arc
					(start 298.650406 -311.012586)
					(mid 298.635527 -310.976665)
					(end 298.599606 -310.961786)
				)
				(arc
					(start 297.200066 -310.961786)
					(mid 297.164145 -310.976665)
					(end 297.149266 -311.012586)
				)
			)
		)
	)
	(zone
		(layers "In1.Cu" "In2.Cu")
		(hatch none 0.5)
		(connect_pads
			(clearance 0)
		)
		(min_thickness 0.25)
		(keepout
			(tracks not_allowed)
			(vias allowed)
			(pads allowed)
			(copperpour not_allowed)
			(footprints allowed)
		)
		(placement
			(enabled no)
			(sheetname "")
		)
		(fill yes
			(thermal_gap 0.5)
			(thermal_bridge_width 0.5)
			(island_removal_mode 0)
		)
		(polygon
			(pts
				(arc
					(start 297.149266 -239.17148)
					(mid 297.164145 -239.207401)
					(end 297.200066 -239.22228)
				)
				(arc
					(start 298.599606 -239.22228)
					(mid 298.635527 -239.207401)
					(end 298.650406 -239.17148)
				)
				(arc
					(start 298.650406 -238.76254)
					(mid 298.635527 -238.726619)
					(end 298.599606 -238.71174)
				)
				(arc
					(start 297.200066 -238.71174)
					(mid 297.164145 -238.726619)
					(end 297.149266 -238.76254)
				)
			)
		)
	)
	(zone
		(layers "In1.Cu" "In2.Cu")
		(hatch none 0.5)
		(connect_pads
			(clearance 0)
		)
		(min_thickness 0.25)
		(keepout
			(tracks not_allowed)
			(vias allowed)
			(pads allowed)
			(copperpour not_allowed)
			(footprints allowed)
		)
		(placement
			(enabled no)
			(sheetname "")
		)
		(fill yes
			(thermal_gap 0.5)
			(thermal_bridge_width 0.5)
			(island_removal_mode 0)
		)
		(polygon
			(pts
				(arc
					(start 49.209198 -302.071532)
					(mid 49.224077 -302.107453)
					(end 49.259998 -302.122332)
				)
				(arc
					(start 50.659538 -302.122332)
					(mid 50.695459 -302.107453)
					(end 50.710338 -302.071532)
				)
				(arc
					(start 50.710338 -301.662592)
					(mid 50.695459 -301.626671)
					(end 50.659538 -301.611792)
				)
				(arc
					(start 49.259998 -301.611792)
					(mid 49.224077 -301.626671)
					(end 49.209198 -301.662592)
				)
			)
		)
	)
	(zone
		(layers "In1.Cu" "In2.Cu")
		(hatch none 0.5)
		(connect_pads
			(clearance 0)
		)
		(min_thickness 0.25)
		(keepout
			(tracks not_allowed)
			(vias allowed)
			(pads allowed)
			(copperpour not_allowed)
			(footprints allowed)
		)
		(placement
			(enabled no)
			(sheetname "")
		)
		(fill yes
			(thermal_gap 0.5)
			(thermal_bridge_width 0.5)
			(island_removal_mode 0)
		)
		(polygon
			(pts
				(arc
					(start 447.822066 -218.77147)
					(mid 447.836945 -218.807391)
					(end 447.872866 -218.82227)
				)
				(arc
					(start 449.272406 -218.82227)
					(mid 449.308327 -218.807391)
					(end 449.323206 -218.77147)
				)
				(arc
					(start 449.323206 -218.36253)
					(mid 449.308327 -218.326609)
					(end 449.272406 -218.31173)
				)
				(arc
					(start 447.872866 -218.31173)
					(mid 447.836945 -218.326609)
					(end 447.822066 -218.36253)
				)
			)
		)
	)
	(zone
		(layers "In1.Cu" "In2.Cu")
		(hatch none 0.5)
		(connect_pads
			(clearance 0)
		)
		(min_thickness 0.25)
		(keepout
			(tracks not_allowed)
			(vias allowed)
			(pads allowed)
			(copperpour not_allowed)
			(footprints allowed)
		)
		(placement
			(enabled no)
			(sheetname "")
		)
		(fill yes
			(thermal_gap 0.5)
			(thermal_bridge_width 0.5)
			(island_removal_mode 0)
		)
		(polygon
			(pts
				(arc
					(start 451.265798 -310.571388)
					(mid 451.280677 -310.607309)
					(end 451.316598 -310.622188)
				)
				(arc
					(start 452.716138 -310.622188)
					(mid 452.752059 -310.607309)
					(end 452.766938 -310.571388)
				)
				(arc
					(start 452.766938 -310.162448)
					(mid 452.752059 -310.126527)
					(end 452.716138 -310.111648)
				)
				(arc
					(start 451.316598 -310.111648)
					(mid 451.280677 -310.126527)
					(end 451.265798 -310.162448)
				)
			)
		)
	)
	(zone
		(layers "In1.Cu" "In2.Cu")
		(hatch none 0.5)
		(connect_pads
			(clearance 0)
		)
		(min_thickness 0.25)
		(keepout
			(tracks not_allowed)
			(vias allowed)
			(pads allowed)
			(copperpour not_allowed)
			(footprints allowed)
		)
		(placement
			(enabled no)
			(sheetname "")
		)
		(fill yes
			(thermal_gap 0.5)
			(thermal_bridge_width 0.5)
			(island_removal_mode 0)
		)
		(polygon
			(pts
				(arc
					(start 297.149266 -218.77147)
					(mid 297.164145 -218.807391)
					(end 297.200066 -218.82227)
				)
				(arc
					(start 298.599606 -218.82227)
					(mid 298.635527 -218.807391)
					(end 298.650406 -218.77147)
				)
				(arc
					(start 298.650406 -218.36253)
					(mid 298.635527 -218.326609)
					(end 298.599606 -218.31173)
				)
				(arc
					(start 297.200066 -218.31173)
					(mid 297.164145 -218.326609)
					(end 297.149266 -218.36253)
				)
			)
		)
	)
	(zone
		(layers "In1.Cu" "In2.Cu")
		(hatch none 0.5)
		(connect_pads
			(clearance 0)
		)
		(min_thickness 0.25)
		(keepout
			(tracks not_allowed)
			(vias allowed)
			(pads allowed)
			(copperpour not_allowed)
			(footprints allowed)
		)
		(placement
			(enabled no)
			(sheetname "")
		)
		(fill yes
			(thermal_gap 0.5)
			(thermal_bridge_width 0.5)
			(island_removal_mode 0)
		)
		(polygon
			(pts
				(arc
					(start 455.365866 -278.271478)
					(mid 455.380745 -278.307399)
					(end 455.416666 -278.322278)
				)
				(arc
					(start 456.816206 -278.322278)
					(mid 456.852127 -278.307399)
					(end 456.867006 -278.271478)
				)
				(arc
					(start 456.867006 -277.862538)
					(mid 456.852127 -277.826617)
					(end 456.816206 -277.811738)
				)
				(arc
					(start 455.416666 -277.811738)
					(mid 455.380745 -277.826617)
					(end 455.365866 -277.862538)
				)
			)
		)
	)
	(zone
		(layers "In1.Cu" "In2.Cu")
		(hatch none 0.5)
		(connect_pads
			(clearance 0)
		)
		(min_thickness 0.25)
		(keepout
			(tracks not_allowed)
			(vias allowed)
			(pads allowed)
			(copperpour not_allowed)
			(footprints allowed)
		)
		(placement
			(enabled no)
			(sheetname "")
		)
		(fill yes
			(thermal_gap 0.5)
			(thermal_bridge_width 0.5)
			(island_removal_mode 0)
		)
		(polygon
			(pts
				(arc
					(start 203.32573 -234.071414)
					(mid 203.340609 -234.107335)
					(end 203.37653 -234.122214)
				)
				(arc
					(start 204.77607 -234.122214)
					(mid 204.811991 -234.107335)
					(end 204.82687 -234.071414)
				)
				(arc
					(start 204.82687 -233.662474)
					(mid 204.811991 -233.626553)
					(end 204.77607 -233.611674)
				)
				(arc
					(start 203.37653 -233.611674)
					(mid 203.340609 -233.626553)
					(end 203.32573 -233.662474)
				)
			)
		)
	)
	(zone
		(layers "In1.Cu" "In2.Cu")
		(hatch none 0.5)
		(connect_pads
			(clearance 0)
		)
		(min_thickness 0.25)
		(keepout
			(tracks not_allowed)
			(vias allowed)
			(pads allowed)
			(copperpour not_allowed)
			(footprints allowed)
		)
		(placement
			(enabled no)
			(sheetname "")
		)
		(fill yes
			(thermal_gap 0.5)
			(thermal_bridge_width 0.5)
			(island_removal_mode 0)
		)
		(polygon
			(pts
				(arc
					(start 455.365866 -274.871434)
					(mid 455.380745 -274.907355)
					(end 455.416666 -274.922234)
				)
				(arc
					(start 456.816206 -274.922234)
					(mid 456.852127 -274.907355)
					(end 456.867006 -274.871434)
				)
				(arc
					(start 456.867006 -274.462494)
					(mid 456.852127 -274.426573)
					(end 456.816206 -274.411694)
				)
				(arc
					(start 455.416666 -274.411694)
					(mid 455.380745 -274.426573)
					(end 455.365866 -274.462494)
				)
			)
		)
	)
	(zone
		(layers "In1.Cu" "In2.Cu")
		(hatch none 0.5)
		(connect_pads
			(clearance 0)
		)
		(min_thickness 0.25)
		(keepout
			(tracks not_allowed)
			(vias allowed)
			(pads allowed)
			(copperpour not_allowed)
			(footprints allowed)
		)
		(placement
			(enabled no)
			(sheetname "")
		)
		(fill yes
			(thermal_gap 0.5)
			(thermal_bridge_width 0.5)
			(island_removal_mode 0)
		)
		(polygon
			(pts
				(arc
					(start 274.517866 -312.27141)
					(mid 274.532745 -312.307331)
					(end 274.568666 -312.32221)
				)
				(arc
					(start 275.968206 -312.32221)
					(mid 276.004127 -312.307331)
					(end 276.019006 -312.27141)
				)
				(arc
					(start 276.019006 -311.86247)
					(mid 276.004127 -311.826549)
					(end 275.968206 -311.81167)
				)
				(arc
					(start 274.568666 -311.81167)
					(mid 274.532745 -311.826549)
					(end 274.517866 -311.86247)
				)
			)
		)
	)
	(zone
		(layers "In1.Cu" "In2.Cu")
		(hatch none 0.5)
		(connect_pads
			(clearance 0)
		)
		(min_thickness 0.25)
		(keepout
			(tracks not_allowed)
			(vias allowed)
			(pads allowed)
			(copperpour not_allowed)
			(footprints allowed)
		)
		(placement
			(enabled no)
			(sheetname "")
		)
		(fill yes
			(thermal_gap 0.5)
			(thermal_bridge_width 0.5)
			(island_removal_mode 0)
		)
		(polygon
			(pts
				(arc
					(start 451.265798 -266.371324)
					(mid 451.280677 -266.407245)
					(end 451.316598 -266.422124)
				)
				(arc
					(start 452.716138 -266.422124)
					(mid 452.752059 -266.407245)
					(end 452.766938 -266.371324)
				)
				(arc
					(start 452.766938 -265.962384)
					(mid 452.752059 -265.926463)
					(end 452.716138 -265.911584)
				)
				(arc
					(start 451.316598 -265.911584)
					(mid 451.280677 -265.926463)
					(end 451.265798 -265.962384)
				)
			)
		)
	)
	(zone
		(layers "In1.Cu" "In2.Cu")
		(hatch none 0.5)
		(connect_pads
			(clearance 0)
		)
		(min_thickness 0.25)
		(keepout
			(tracks not_allowed)
			(vias allowed)
			(pads allowed)
			(copperpour not_allowed)
			(footprints allowed)
		)
		(placement
			(enabled no)
			(sheetname "")
		)
		(fill yes
			(thermal_gap 0.5)
			(thermal_bridge_width 0.5)
			(island_removal_mode 0)
		)
		(polygon
			(pts
				(arc
					(start 45.10913 -280.821384)
					(mid 45.124009 -280.857305)
					(end 45.15993 -280.872184)
				)
				(arc
					(start 46.55947 -280.872184)
					(mid 46.595391 -280.857305)
					(end 46.61027 -280.821384)
				)
				(arc
					(start 46.61027 -280.412444)
					(mid 46.595391 -280.376523)
					(end 46.55947 -280.361644)
				)
				(arc
					(start 45.15993 -280.361644)
					(mid 45.124009 -280.376523)
					(end 45.10913 -280.412444)
				)
			)
		)
	)
	(zone
		(layers "In1.Cu" "In2.Cu")
		(hatch none 0.5)
		(connect_pads
			(clearance 0)
		)
		(min_thickness 0.25)
		(keepout
			(tracks not_allowed)
			(vias allowed)
			(pads allowed)
			(copperpour not_allowed)
			(footprints allowed)
		)
		(placement
			(enabled no)
			(sheetname "")
		)
		(fill yes
			(thermal_gap 0.5)
			(thermal_bridge_width 0.5)
			(island_removal_mode 0)
		)
		(polygon
			(pts
				(arc
					(start 41.665398 -245.12143)
					(mid 41.680277 -245.157351)
					(end 41.716198 -245.17223)
				)
				(arc
					(start 43.115738 -245.17223)
					(mid 43.151659 -245.157351)
					(end 43.166538 -245.12143)
				)
				(arc
					(start 43.166538 -244.71249)
					(mid 43.151659 -244.676569)
					(end 43.115738 -244.66169)
				)
				(arc
					(start 41.716198 -244.66169)
					(mid 41.680277 -244.676569)
					(end 41.665398 -244.71249)
				)
			)
		)
	)
	(zone
		(layers "In1.Cu" "In2.Cu")
		(hatch none 0.5)
		(connect_pads
			(clearance 0)
		)
		(min_thickness 0.25)
		(keepout
			(tracks not_allowed)
			(vias allowed)
			(pads allowed)
			(copperpour not_allowed)
			(footprints allowed)
		)
		(placement
			(enabled no)
			(sheetname "")
		)
		(fill yes
			(thermal_gap 0.5)
			(thermal_bridge_width 0.5)
			(island_removal_mode 0)
		)
		(polygon
			(pts
				(arc
					(start 41.665398 -229.821486)
					(mid 41.680277 -229.857407)
					(end 41.716198 -229.872286)
				)
				(arc
					(start 43.115738 -229.872286)
					(mid 43.151659 -229.857407)
					(end 43.166538 -229.821486)
				)
				(arc
					(start 43.166538 -229.412546)
					(mid 43.151659 -229.376625)
					(end 43.115738 -229.361746)
				)
				(arc
					(start 41.716198 -229.361746)
					(mid 41.680277 -229.376625)
					(end 41.665398 -229.412546)
				)
			)
		)
	)
	(zone
		(layers "In1.Cu" "In2.Cu")
		(hatch none 0.5)
		(connect_pads
			(clearance 0)
		)
		(min_thickness 0.25)
		(keepout
			(tracks not_allowed)
			(vias allowed)
			(pads allowed)
			(copperpour not_allowed)
			(footprints allowed)
		)
		(placement
			(enabled no)
			(sheetname "")
		)
		(fill yes
			(thermal_gap 0.5)
			(thermal_bridge_width 0.5)
			(island_removal_mode 0)
		)
		(polygon
			(pts
				(arc
					(start 308.136798 -305.471322)
					(mid 308.151677 -305.507243)
					(end 308.187598 -305.522122)
				)
				(arc
					(start 309.587138 -305.522122)
					(mid 309.623059 -305.507243)
					(end 309.637938 -305.471322)
				)
				(arc
					(start 309.637938 -305.062382)
					(mid 309.623059 -305.026461)
					(end 309.587138 -305.011582)
				)
				(arc
					(start 308.187598 -305.011582)
					(mid 308.151677 -305.026461)
					(end 308.136798 -305.062382)
				)
			)
		)
	)
	(zone
		(layers "In1.Cu" "In2.Cu")
		(hatch none 0.5)
		(connect_pads
			(clearance 0)
		)
		(min_thickness 0.25)
		(keepout
			(tracks not_allowed)
			(vias allowed)
			(pads allowed)
			(copperpour not_allowed)
			(footprints allowed)
		)
		(placement
			(enabled no)
			(sheetname "")
		)
		(fill yes
			(thermal_gap 0.5)
			(thermal_bridge_width 0.5)
			(island_removal_mode 0)
		)
		(polygon
			(pts
				(arc
					(start 180.69433 -275.721318)
					(mid 180.709209 -275.757239)
					(end 180.74513 -275.772118)
				)
				(arc
					(start 182.14467 -275.772118)
					(mid 182.180591 -275.757239)
					(end 182.19547 -275.721318)
				)
				(arc
					(start 182.19547 -275.312378)
					(mid 182.180591 -275.276457)
					(end 182.14467 -275.261578)
				)
				(arc
					(start 180.74513 -275.261578)
					(mid 180.709209 -275.276457)
					(end 180.69433 -275.312378)
				)
			)
		)
	)
	(zone
		(layers "In1.Cu" "In2.Cu")
		(hatch none 0.5)
		(connect_pads
			(clearance 0)
		)
		(min_thickness 0.25)
		(keepout
			(tracks not_allowed)
			(vias allowed)
			(pads allowed)
			(copperpour not_allowed)
			(footprints allowed)
		)
		(placement
			(enabled no)
			(sheetname "")
		)
		(fill yes
			(thermal_gap 0.5)
			(thermal_bridge_width 0.5)
			(island_removal_mode 0)
		)
		(polygon
			(pts
				(arc
					(start 199.881998 -200.071482)
					(mid 199.896877 -200.107403)
					(end 199.932798 -200.122282)
				)
				(arc
					(start 201.332338 -200.122282)
					(mid 201.368259 -200.107403)
					(end 201.383138 -200.071482)
				)
				(arc
					(start 201.383138 -199.662542)
					(mid 201.368259 -199.626621)
					(end 201.332338 -199.611742)
				)
				(arc
					(start 199.932798 -199.611742)
					(mid 199.896877 -199.626621)
					(end 199.881998 -199.662542)
				)
			)
		)
	)
	(zone
		(layers "In1.Cu" "In2.Cu")
		(hatch none 0.5)
		(connect_pads
			(clearance 0)
		)
		(min_thickness 0.25)
		(keepout
			(tracks not_allowed)
			(vias allowed)
			(pads allowed)
			(copperpour not_allowed)
			(footprints allowed)
		)
		(placement
			(enabled no)
			(sheetname "")
		)
		(fill yes
			(thermal_gap 0.5)
			(thermal_bridge_width 0.5)
			(island_removal_mode 0)
		)
		(polygon
			(pts
				(arc
					(start 22.47773 -271.47139)
					(mid 22.492609 -271.507311)
					(end 22.52853 -271.52219)
				)
				(arc
					(start 23.92807 -271.52219)
					(mid 23.963991 -271.507311)
					(end 23.97887 -271.47139)
				)
				(arc
					(start 23.97887 -271.06245)
					(mid 23.963991 -271.026529)
					(end 23.92807 -271.01165)
				)
				(arc
					(start 22.52853 -271.01165)
					(mid 22.492609 -271.026529)
					(end 22.47773 -271.06245)
				)
			)
		)
	)
	(zone
		(layers "In1.Cu" "In2.Cu")
		(hatch none 0.5)
		(connect_pads
			(clearance 0)
		)
		(min_thickness 0.25)
		(keepout
			(tracks not_allowed)
			(vias allowed)
			(pads allowed)
			(copperpour not_allowed)
			(footprints allowed)
		)
		(placement
			(enabled no)
			(sheetname "")
		)
		(fill yes
			(thermal_gap 0.5)
			(thermal_bridge_width 0.5)
			(island_removal_mode 0)
		)
		(polygon
			(pts
				(arc
					(start 270.417798 -224.72142)
					(mid 270.432677 -224.757341)
					(end 270.468598 -224.77222)
				)
				(arc
					(start 271.868138 -224.77222)
					(mid 271.904059 -224.757341)
					(end 271.918938 -224.72142)
				)
				(arc
					(start 271.918938 -224.31248)
					(mid 271.904059 -224.276559)
					(end 271.868138 -224.26168)
				)
				(arc
					(start 270.468598 -224.26168)
					(mid 270.432677 -224.276559)
					(end 270.417798 -224.31248)
				)
			)
		)
	)
	(zone
		(layers "In1.Cu" "In2.Cu")
		(hatch none 0.5)
		(connect_pads
			(clearance 0)
		)
		(min_thickness 0.25)
		(keepout
			(tracks not_allowed)
			(vias allowed)
			(pads allowed)
			(copperpour not_allowed)
			(footprints allowed)
		)
		(placement
			(enabled no)
			(sheetname "")
		)
		(fill yes
			(thermal_gap 0.5)
			(thermal_bridge_width 0.5)
			(island_removal_mode 0)
		)
		(polygon
			(pts
				(arc
					(start 451.265798 -279.121362)
					(mid 451.280677 -279.157283)
					(end 451.316598 -279.172162)
				)
				(arc
					(start 452.716138 -279.172162)
					(mid 452.752059 -279.157283)
					(end 452.766938 -279.121362)
				)
				(arc
					(start 452.766938 -278.712422)
					(mid 452.752059 -278.676501)
					(end 452.716138 -278.661622)
				)
				(arc
					(start 451.316598 -278.661622)
					(mid 451.280677 -278.676501)
					(end 451.265798 -278.712422)
				)
			)
		)
	)
	(zone
		(layers "In1.Cu" "In2.Cu")
		(hatch none 0.5)
		(connect_pads
			(clearance 0)
		)
		(min_thickness 0.25)
		(keepout
			(tracks not_allowed)
			(vias allowed)
			(pads allowed)
			(copperpour not_allowed)
			(footprints allowed)
		)
		(placement
			(enabled no)
			(sheetname "")
		)
		(fill yes
			(thermal_gap 0.5)
			(thermal_bridge_width 0.5)
			(island_removal_mode 0)
		)
		(polygon
			(pts
				(arc
					(start 207.425798 -239.17148)
					(mid 207.440677 -239.207401)
					(end 207.476598 -239.22228)
				)
				(arc
					(start 208.876138 -239.22228)
					(mid 208.912059 -239.207401)
					(end 208.926938 -239.17148)
				)
				(arc
					(start 208.926938 -238.76254)
					(mid 208.912059 -238.726619)
					(end 208.876138 -238.71174)
				)
				(arc
					(start 207.476598 -238.71174)
					(mid 207.440677 -238.726619)
					(end 207.425798 -238.76254)
				)
			)
		)
	)
	(zone
		(layers "In1.Cu" "In2.Cu")
		(hatch none 0.5)
		(connect_pads
			(clearance 0)
		)
		(min_thickness 0.25)
		(keepout
			(tracks not_allowed)
			(vias allowed)
			(pads allowed)
			(copperpour not_allowed)
			(footprints allowed)
		)
		(placement
			(enabled no)
			(sheetname "")
		)
		(fill yes
			(thermal_gap 0.5)
			(thermal_bridge_width 0.5)
			(island_removal_mode 0)
		)
		(polygon
			(pts
				(arc
					(start 274.517866 -233.22153)
					(mid 274.532745 -233.257451)
					(end 274.568666 -233.27233)
				)
				(arc
					(start 275.968206 -233.27233)
					(mid 276.004127 -233.257451)
					(end 276.019006 -233.22153)
				)
				(arc
					(start 276.019006 -232.81259)
					(mid 276.004127 -232.776669)
					(end 275.968206 -232.76179)
				)
				(arc
					(start 274.568666 -232.76179)
					(mid 274.532745 -232.776669)
					(end 274.517866 -232.81259)
				)
			)
		)
	)
	(zone
		(layers "In1.Cu" "In2.Cu")
		(hatch none 0.5)
		(connect_pads
			(clearance 0)
		)
		(min_thickness 0.25)
		(keepout
			(tracks not_allowed)
			(vias allowed)
			(pads allowed)
			(copperpour not_allowed)
			(footprints allowed)
		)
		(placement
			(enabled no)
			(sheetname "")
		)
		(fill yes
			(thermal_gap 0.5)
			(thermal_bridge_width 0.5)
			(island_removal_mode 0)
		)
		(polygon
			(pts
				(arc
					(start 60.19673 -316.521338)
					(mid 60.211609 -316.557259)
					(end 60.24753 -316.572138)
				)
				(arc
					(start 61.64707 -316.572138)
					(mid 61.682991 -316.557259)
					(end 61.69787 -316.521338)
				)
				(arc
					(start 61.69787 -316.112398)
					(mid 61.682991 -316.076477)
					(end 61.64707 -316.061598)
				)
				(arc
					(start 60.24753 -316.061598)
					(mid 60.211609 -316.076477)
					(end 60.19673 -316.112398)
				)
			)
		)
	)
	(zone
		(layers "In1.Cu" "In2.Cu")
		(hatch none 0.5)
		(connect_pads
			(clearance 0)
		)
		(min_thickness 0.25)
		(keepout
			(tracks not_allowed)
			(vias allowed)
			(pads allowed)
			(copperpour not_allowed)
			(footprints allowed)
		)
		(placement
			(enabled no)
			(sheetname "")
		)
		(fill yes
			(thermal_gap 0.5)
			(thermal_bridge_width 0.5)
			(island_removal_mode 0)
		)
		(polygon
			(pts
				(arc
					(start 462.909666 -199.221344)
					(mid 462.924545 -199.257265)
					(end 462.960466 -199.272144)
				)
				(arc
					(start 464.360006 -199.272144)
					(mid 464.395927 -199.257265)
					(end 464.410806 -199.221344)
				)
				(arc
					(start 464.410806 -198.812404)
					(mid 464.395927 -198.776483)
					(end 464.360006 -198.761604)
				)
				(arc
					(start 462.960466 -198.761604)
					(mid 462.924545 -198.776483)
					(end 462.909666 -198.812404)
				)
			)
		)
	)
	(zone
		(layers "In1.Cu" "In2.Cu")
		(hatch none 0.5)
		(connect_pads
			(clearance 0)
		)
		(min_thickness 0.25)
		(keepout
			(tracks not_allowed)
			(vias allowed)
			(pads allowed)
			(copperpour not_allowed)
			(footprints allowed)
		)
		(placement
			(enabled no)
			(sheetname "")
		)
		(fill yes
			(thermal_gap 0.5)
			(thermal_bridge_width 0.5)
			(island_removal_mode 0)
		)
		(polygon
			(pts
				(arc
					(start 259.430266 -236.62132)
					(mid 259.445145 -236.657241)
					(end 259.481066 -236.67212)
				)
				(arc
					(start 260.880606 -236.67212)
					(mid 260.916527 -236.657241)
					(end 260.931406 -236.62132)
				)
				(arc
					(start 260.931406 -236.21238)
					(mid 260.916527 -236.176459)
					(end 260.880606 -236.16158)
				)
				(arc
					(start 259.481066 -236.16158)
					(mid 259.445145 -236.176459)
					(end 259.430266 -236.21238)
				)
			)
		)
	)
	(zone
		(layers "In1.Cu" "In2.Cu")
		(hatch none 0.5)
		(connect_pads
			(clearance 0)
		)
		(min_thickness 0.25)
		(keepout
			(tracks not_allowed)
			(vias allowed)
			(pads allowed)
			(copperpour not_allowed)
			(footprints allowed)
		)
		(placement
			(enabled no)
			(sheetname "")
		)
		(fill yes
			(thermal_gap 0.5)
			(thermal_bridge_width 0.5)
			(island_removal_mode 0)
		)
		(polygon
			(pts
				(arc
					(start 7.39013 -307.171344)
					(mid 7.405009 -307.207265)
					(end 7.44093 -307.222144)
				)
				(arc
					(start 8.84047 -307.222144)
					(mid 8.876391 -307.207265)
					(end 8.89127 -307.171344)
				)
				(arc
					(start 8.89127 -306.762404)
					(mid 8.876391 -306.726483)
					(end 8.84047 -306.711604)
				)
				(arc
					(start 7.44093 -306.711604)
					(mid 7.405009 -306.726483)
					(end 7.39013 -306.762404)
				)
			)
		)
	)
	(zone
		(layers "In1.Cu" "In2.Cu")
		(hatch none 0.5)
		(connect_pads
			(clearance 0)
		)
		(min_thickness 0.25)
		(keepout
			(tracks not_allowed)
			(vias allowed)
			(pads allowed)
			(copperpour not_allowed)
			(footprints allowed)
		)
		(placement
			(enabled no)
			(sheetname "")
		)
		(fill yes
			(thermal_gap 0.5)
			(thermal_bridge_width 0.5)
			(island_removal_mode 0)
		)
		(polygon
			(pts
				(arc
					(start 440.278266 -214.521542)
					(mid 440.293145 -214.557463)
					(end 440.329066 -214.572342)
				)
				(arc
					(start 441.728606 -214.572342)
					(mid 441.764527 -214.557463)
					(end 441.779406 -214.521542)
				)
				(arc
					(start 441.779406 -214.112602)
					(mid 441.764527 -214.076681)
					(end 441.728606 -214.061802)
				)
				(arc
					(start 440.329066 -214.061802)
					(mid 440.293145 -214.076681)
					(end 440.278266 -214.112602)
				)
			)
		)
	)
	(zone
		(layers "In1.Cu" "In2.Cu")
		(hatch none 0.5)
		(connect_pads
			(clearance 0)
		)
		(min_thickness 0.25)
		(keepout
			(tracks not_allowed)
			(vias allowed)
			(pads allowed)
			(copperpour not_allowed)
			(footprints allowed)
		)
		(placement
			(enabled no)
			(sheetname "")
		)
		(fill yes
			(thermal_gap 0.5)
			(thermal_bridge_width 0.5)
			(island_removal_mode 0)
		)
		(polygon
			(pts
				(arc
					(start 184.794398 -285.92145)
					(mid 184.809277 -285.957371)
					(end 184.845198 -285.97225)
				)
				(arc
					(start 186.244738 -285.97225)
					(mid 186.280659 -285.957371)
					(end 186.295538 -285.92145)
				)
				(arc
					(start 186.295538 -285.51251)
					(mid 186.280659 -285.476589)
					(end 186.244738 -285.46171)
				)
				(arc
					(start 184.845198 -285.46171)
					(mid 184.809277 -285.476589)
					(end 184.794398 -285.51251)
				)
			)
		)
	)
	(zone
		(layers "In1.Cu" "In2.Cu")
		(hatch none 0.5)
		(connect_pads
			(clearance 0)
		)
		(min_thickness 0.25)
		(keepout
			(tracks not_allowed)
			(vias allowed)
			(pads allowed)
			(copperpour not_allowed)
			(footprints allowed)
		)
		(placement
			(enabled no)
			(sheetname "")
		)
		(fill yes
			(thermal_gap 0.5)
			(thermal_bridge_width 0.5)
			(island_removal_mode 0)
		)
		(polygon
			(pts
				(arc
					(start 440.278266 -216.22131)
					(mid 440.293145 -216.257231)
					(end 440.329066 -216.27211)
				)
				(arc
					(start 441.728606 -216.27211)
					(mid 441.764527 -216.257231)
					(end 441.779406 -216.22131)
				)
				(arc
					(start 441.779406 -215.81237)
					(mid 441.764527 -215.776449)
					(end 441.728606 -215.76157)
				)
				(arc
					(start 440.329066 -215.76157)
					(mid 440.293145 -215.776449)
					(end 440.278266 -215.81237)
				)
			)
		)
	)
	(zone
		(layers "In1.Cu" "In2.Cu")
		(hatch none 0.5)
		(connect_pads
			(clearance 0)
		)
		(min_thickness 0.25)
		(keepout
			(tracks not_allowed)
			(vias allowed)
			(pads allowed)
			(copperpour not_allowed)
			(footprints allowed)
		)
		(placement
			(enabled no)
			(sheetname "")
		)
		(fill yes
			(thermal_gap 0.5)
			(thermal_bridge_width 0.5)
			(island_removal_mode 0)
		)
		(polygon
			(pts
				(arc
					(start 462.909666 -285.92145)
					(mid 462.924545 -285.957371)
					(end 462.960466 -285.97225)
				)
				(arc
					(start 464.360006 -285.97225)
					(mid 464.395927 -285.957371)
					(end 464.410806 -285.92145)
				)
				(arc
					(start 464.410806 -285.51251)
					(mid 464.395927 -285.476589)
					(end 464.360006 -285.46171)
				)
				(arc
					(start 462.960466 -285.46171)
					(mid 462.924545 -285.476589)
					(end 462.909666 -285.51251)
				)
			)
		)
	)
	(zone
		(layers "In1.Cu" "In2.Cu")
		(hatch none 0.5)
		(connect_pads
			(clearance 0)
		)
		(min_thickness 0.25)
		(keepout
			(tracks not_allowed)
			(vias allowed)
			(pads allowed)
			(copperpour not_allowed)
			(footprints allowed)
		)
		(placement
			(enabled no)
			(sheetname "")
		)
		(fill yes
			(thermal_gap 0.5)
			(thermal_bridge_width 0.5)
			(island_removal_mode 0)
		)
		(polygon
			(pts
				(arc
					(start 173.15053 -299.521372)
					(mid 173.165409 -299.557293)
					(end 173.20133 -299.572172)
				)
				(arc
					(start 174.60087 -299.572172)
					(mid 174.636791 -299.557293)
					(end 174.65167 -299.521372)
				)
				(arc
					(start 174.65167 -299.112432)
					(mid 174.636791 -299.076511)
					(end 174.60087 -299.061632)
				)
				(arc
					(start 173.20133 -299.061632)
					(mid 173.165409 -299.076511)
					(end 173.15053 -299.112432)
				)
			)
		)
	)
	(zone
		(layers "In1.Cu" "In2.Cu")
		(hatch none 0.5)
		(connect_pads
			(clearance 0)
		)
		(min_thickness 0.25)
		(keepout
			(tracks not_allowed)
			(vias allowed)
			(pads allowed)
			(copperpour not_allowed)
			(footprints allowed)
		)
		(placement
			(enabled no)
			(sheetname "")
		)
		(fill yes
			(thermal_gap 0.5)
			(thermal_bridge_width 0.5)
			(island_removal_mode 0)
		)
		(polygon
			(pts
				(arc
					(start 289.605466 -279.9715)
					(mid 289.620345 -280.007421)
					(end 289.656266 -280.0223)
				)
				(arc
					(start 291.055806 -280.0223)
					(mid 291.091727 -280.007421)
					(end 291.106606 -279.9715)
				)
				(arc
					(start 291.106606 -279.56256)
					(mid 291.091727 -279.526639)
					(end 291.055806 -279.51176)
				)
				(arc
					(start 289.656266 -279.51176)
					(mid 289.620345 -279.526639)
					(end 289.605466 -279.56256)
				)
			)
		)
	)
	(zone
		(layers "In1.Cu" "In2.Cu")
		(hatch none 0.5)
		(connect_pads
			(clearance 0)
		)
		(min_thickness 0.25)
		(keepout
			(tracks not_allowed)
			(vias allowed)
			(pads allowed)
			(copperpour not_allowed)
			(footprints allowed)
		)
		(placement
			(enabled no)
			(sheetname "")
		)
		(fill yes
			(thermal_gap 0.5)
			(thermal_bridge_width 0.5)
			(island_removal_mode 0)
		)
		(polygon
			(pts
				(arc
					(start 440.278266 -197.521322)
					(mid 440.293145 -197.557243)
					(end 440.329066 -197.572122)
				)
				(arc
					(start 441.728606 -197.572122)
					(mid 441.764527 -197.557243)
					(end 441.779406 -197.521322)
				)
				(arc
					(start 441.779406 -197.112382)
					(mid 441.764527 -197.076461)
					(end 441.728606 -197.061582)
				)
				(arc
					(start 440.329066 -197.061582)
					(mid 440.293145 -197.076461)
					(end 440.278266 -197.112382)
				)
			)
		)
	)
	(zone
		(layers "In1.Cu" "In2.Cu")
		(hatch none 0.5)
		(connect_pads
			(clearance 0)
		)
		(min_thickness 0.25)
		(keepout
			(tracks not_allowed)
			(vias allowed)
			(pads allowed)
			(copperpour not_allowed)
			(footprints allowed)
		)
		(placement
			(enabled no)
			(sheetname "")
		)
		(fill yes
			(thermal_gap 0.5)
			(thermal_bridge_width 0.5)
			(island_removal_mode 0)
		)
		(polygon
			(pts
				(arc
					(start 56.752998 -268.921484)
					(mid 56.767877 -268.957405)
					(end 56.803798 -268.972284)
				)
				(arc
					(start 58.203338 -268.972284)
					(mid 58.239259 -268.957405)
					(end 58.254138 -268.921484)
				)
				(arc
					(start 58.254138 -268.512544)
					(mid 58.239259 -268.476623)
					(end 58.203338 -268.461744)
				)
				(arc
					(start 56.803798 -268.461744)
					(mid 56.767877 -268.476623)
					(end 56.752998 -268.512544)
				)
			)
		)
	)
	(zone
		(layers "In1.Cu" "In2.Cu")
		(hatch none 0.5)
		(connect_pads
			(clearance 0)
		)
		(min_thickness 0.25)
		(keepout
			(tracks not_allowed)
			(vias allowed)
			(pads allowed)
			(copperpour not_allowed)
			(footprints allowed)
		)
		(placement
			(enabled no)
			(sheetname "")
		)
		(fill yes
			(thermal_gap 0.5)
			(thermal_bridge_width 0.5)
			(island_removal_mode 0)
		)
		(polygon
			(pts
				(arc
					(start 169.706798 -203.471526)
					(mid 169.721677 -203.507447)
					(end 169.757598 -203.522326)
				)
				(arc
					(start 171.157138 -203.522326)
					(mid 171.193059 -203.507447)
					(end 171.207938 -203.471526)
				)
				(arc
					(start 171.207938 -203.062586)
					(mid 171.193059 -203.026665)
					(end 171.157138 -203.011786)
				)
				(arc
					(start 169.757598 -203.011786)
					(mid 169.721677 -203.026665)
					(end 169.706798 -203.062586)
				)
			)
		)
	)
	(zone
		(layers "In1.Cu" "In2.Cu")
		(hatch none 0.5)
		(connect_pads
			(clearance 0)
		)
		(min_thickness 0.25)
		(keepout
			(tracks not_allowed)
			(vias allowed)
			(pads allowed)
			(copperpour not_allowed)
			(footprints allowed)
		)
		(placement
			(enabled no)
			(sheetname "")
		)
		(fill yes
			(thermal_gap 0.5)
			(thermal_bridge_width 0.5)
			(island_removal_mode 0)
		)
		(polygon
			(pts
				(arc
					(start 304.693066 -267.221462)
					(mid 304.707945 -267.257383)
					(end 304.743866 -267.272262)
				)
				(arc
					(start 306.143406 -267.272262)
					(mid 306.179327 -267.257383)
					(end 306.194206 -267.221462)
				)
				(arc
					(start 306.194206 -266.812522)
					(mid 306.179327 -266.776601)
					(end 306.143406 -266.761722)
				)
				(arc
					(start 304.743866 -266.761722)
					(mid 304.707945 -266.776601)
					(end 304.693066 -266.812522)
				)
			)
		)
	)
	(zone
		(layers "In1.Cu" "In2.Cu")
		(hatch none 0.5)
		(connect_pads
			(clearance 0)
		)
		(min_thickness 0.25)
		(keepout
			(tracks not_allowed)
			(vias allowed)
			(pads allowed)
			(copperpour not_allowed)
			(footprints allowed)
		)
		(placement
			(enabled no)
			(sheetname "")
		)
		(fill yes
			(thermal_gap 0.5)
			(thermal_bridge_width 0.5)
			(island_removal_mode 0)
		)
		(polygon
			(pts
				(arc
					(start 195.78193 -234.071414)
					(mid 195.796809 -234.107335)
					(end 195.83273 -234.122214)
				)
				(arc
					(start 197.23227 -234.122214)
					(mid 197.268191 -234.107335)
					(end 197.28307 -234.071414)
				)
				(arc
					(start 197.28307 -233.662474)
					(mid 197.268191 -233.626553)
					(end 197.23227 -233.611674)
				)
				(arc
					(start 195.83273 -233.611674)
					(mid 195.796809 -233.626553)
					(end 195.78193 -233.662474)
				)
			)
		)
	)
	(zone
		(layers "In1.Cu" "In2.Cu")
		(hatch none 0.5)
		(connect_pads
			(clearance 0)
		)
		(min_thickness 0.25)
		(keepout
			(tracks not_allowed)
			(vias allowed)
			(pads allowed)
			(copperpour not_allowed)
			(footprints allowed)
		)
		(placement
			(enabled no)
			(sheetname "")
		)
		(fill yes
			(thermal_gap 0.5)
			(thermal_bridge_width 0.5)
			(island_removal_mode 0)
		)
		(polygon
			(pts
				(arc
					(start 188.23813 -305.471322)
					(mid 188.253009 -305.507243)
					(end 188.28893 -305.522122)
				)
				(arc
					(start 189.68847 -305.522122)
					(mid 189.724391 -305.507243)
					(end 189.73927 -305.471322)
				)
				(arc
					(start 189.73927 -305.062382)
					(mid 189.724391 -305.026461)
					(end 189.68847 -305.011582)
				)
				(arc
					(start 188.28893 -305.011582)
					(mid 188.253009 -305.026461)
					(end 188.23813 -305.062382)
				)
			)
		)
	)
	(zone
		(layers "In1.Cu" "In2.Cu")
		(hatch none 0.5)
		(connect_pads
			(clearance 0)
		)
		(min_thickness 0.25)
		(keepout
			(tracks not_allowed)
			(vias allowed)
			(pads allowed)
			(copperpour not_allowed)
			(footprints allowed)
		)
		(placement
			(enabled no)
			(sheetname "")
		)
		(fill yes
			(thermal_gap 0.5)
			(thermal_bridge_width 0.5)
			(island_removal_mode 0)
		)
		(polygon
			(pts
				(arc
					(start 410.103066 -312.27141)
					(mid 410.117945 -312.307331)
					(end 410.153866 -312.32221)
				)
				(arc
					(start 411.553406 -312.32221)
					(mid 411.589327 -312.307331)
					(end 411.604206 -312.27141)
				)
				(arc
					(start 411.604206 -311.86247)
					(mid 411.589327 -311.826549)
					(end 411.553406 -311.81167)
				)
				(arc
					(start 410.153866 -311.81167)
					(mid 410.117945 -311.826549)
					(end 410.103066 -311.86247)
				)
			)
		)
	)
	(zone
		(layers "In1.Cu" "In2.Cu")
		(hatch none 0.5)
		(connect_pads
			(clearance 0)
		)
		(min_thickness 0.25)
		(keepout
			(tracks not_allowed)
			(vias allowed)
			(pads allowed)
			(copperpour not_allowed)
			(footprints allowed)
		)
		(placement
			(enabled no)
			(sheetname "")
		)
		(fill yes
			(thermal_gap 0.5)
			(thermal_bridge_width 0.5)
			(island_removal_mode 0)
		)
		(polygon
			(pts
				(arc
					(start 266.974066 -283.371544)
					(mid 266.988945 -283.407465)
					(end 267.024866 -283.422344)
				)
				(arc
					(start 268.424406 -283.422344)
					(mid 268.460327 -283.407465)
					(end 268.475206 -283.371544)
				)
				(arc
					(start 268.475206 -282.962604)
					(mid 268.460327 -282.926683)
					(end 268.424406 -282.911804)
				)
				(arc
					(start 267.024866 -282.911804)
					(mid 266.988945 -282.926683)
					(end 266.974066 -282.962604)
				)
			)
		)
	)
	(zone
		(layers "In1.Cu" "In2.Cu")
		(hatch none 0.5)
		(connect_pads
			(clearance 0)
		)
		(min_thickness 0.25)
		(keepout
			(tracks not_allowed)
			(vias allowed)
			(pads allowed)
			(copperpour not_allowed)
			(footprints allowed)
		)
		(placement
			(enabled no)
			(sheetname "")
		)
		(fill yes
			(thermal_gap 0.5)
			(thermal_bridge_width 0.5)
			(island_removal_mode 0)
		)
		(polygon
			(pts
				(arc
					(start 289.605466 -267.221462)
					(mid 289.620345 -267.257383)
					(end 289.656266 -267.272262)
				)
				(arc
					(start 291.055806 -267.272262)
					(mid 291.091727 -267.257383)
					(end 291.106606 -267.221462)
				)
				(arc
					(start 291.106606 -266.812522)
					(mid 291.091727 -266.776601)
					(end 291.055806 -266.761722)
				)
				(arc
					(start 289.656266 -266.761722)
					(mid 289.620345 -266.776601)
					(end 289.605466 -266.812522)
				)
			)
		)
	)
	(zone
		(layers "In1.Cu" "In2.Cu")
		(hatch none 0.5)
		(connect_pads
			(clearance 0)
		)
		(min_thickness 0.25)
		(keepout
			(tracks not_allowed)
			(vias allowed)
			(pads allowed)
			(copperpour not_allowed)
			(footprints allowed)
		)
		(placement
			(enabled no)
			(sheetname "")
		)
		(fill yes
			(thermal_gap 0.5)
			(thermal_bridge_width 0.5)
			(island_removal_mode 0)
		)
		(polygon
			(pts
				(arc
					(start 462.909666 -211.121498)
					(mid 462.924545 -211.157419)
					(end 462.960466 -211.172298)
				)
				(arc
					(start 464.360006 -211.172298)
					(mid 464.395927 -211.157419)
					(end 464.410806 -211.121498)
				)
				(arc
					(start 464.410806 -210.712558)
					(mid 464.395927 -210.676637)
					(end 464.360006 -210.661758)
				)
				(arc
					(start 462.960466 -210.661758)
					(mid 462.924545 -210.676637)
					(end 462.909666 -210.712558)
				)
			)
		)
	)
	(zone
		(layers "In1.Cu" "In2.Cu")
		(hatch none 0.5)
		(connect_pads
			(clearance 0)
		)
		(min_thickness 0.25)
		(keepout
			(tracks not_allowed)
			(vias allowed)
			(pads allowed)
			(copperpour not_allowed)
			(footprints allowed)
		)
		(placement
			(enabled no)
			(sheetname "")
		)
		(fill yes
			(thermal_gap 0.5)
			(thermal_bridge_width 0.5)
			(island_removal_mode 0)
		)
		(polygon
			(pts
				(arc
					(start 184.794398 -281.671522)
					(mid 184.809277 -281.707443)
					(end 184.845198 -281.722322)
				)
				(arc
					(start 186.244738 -281.722322)
					(mid 186.280659 -281.707443)
					(end 186.295538 -281.671522)
				)
				(arc
					(start 186.295538 -281.262582)
					(mid 186.280659 -281.226661)
					(end 186.244738 -281.211782)
				)
				(arc
					(start 184.845198 -281.211782)
					(mid 184.809277 -281.226661)
					(end 184.794398 -281.262582)
				)
			)
		)
	)
	(zone
		(layers "In1.Cu" "In2.Cu")
		(hatch none 0.5)
		(connect_pads
			(clearance 0)
		)
		(min_thickness 0.25)
		(keepout
			(tracks not_allowed)
			(vias allowed)
			(pads allowed)
			(copperpour not_allowed)
			(footprints allowed)
		)
		(placement
			(enabled no)
			(sheetname "")
		)
		(fill yes
			(thermal_gap 0.5)
			(thermal_bridge_width 0.5)
			(island_removal_mode 0)
		)
		(polygon
			(pts
				(arc
					(start 203.32573 -223.021398)
					(mid 203.340609 -223.057319)
					(end 203.37653 -223.072198)
				)
				(arc
					(start 204.77607 -223.072198)
					(mid 204.811991 -223.057319)
					(end 204.82687 -223.021398)
				)
				(arc
					(start 204.82687 -222.612458)
					(mid 204.811991 -222.576537)
					(end 204.77607 -222.561658)
				)
				(arc
					(start 203.37653 -222.561658)
					(mid 203.340609 -222.576537)
					(end 203.32573 -222.612458)
				)
			)
		)
	)
	(zone
		(layers "In1.Cu" "In2.Cu")
		(hatch none 0.5)
		(connect_pads
			(clearance 0)
		)
		(min_thickness 0.25)
		(keepout
			(tracks not_allowed)
			(vias allowed)
			(pads allowed)
			(copperpour not_allowed)
			(footprints allowed)
		)
		(placement
			(enabled no)
			(sheetname "")
		)
		(fill yes
			(thermal_gap 0.5)
			(thermal_bridge_width 0.5)
			(island_removal_mode 0)
		)
		(polygon
			(pts
				(arc
					(start 203.32573 -206.021432)
					(mid 203.340609 -206.057353)
					(end 203.37653 -206.072232)
				)
				(arc
					(start 204.77607 -206.072232)
					(mid 204.811991 -206.057353)
					(end 204.82687 -206.021432)
				)
				(arc
					(start 204.82687 -205.612492)
					(mid 204.811991 -205.576571)
					(end 204.77607 -205.561692)
				)
				(arc
					(start 203.37653 -205.561692)
					(mid 203.340609 -205.576571)
					(end 203.32573 -205.612492)
				)
			)
		)
	)
	(zone
		(layers "In1.Cu" "In2.Cu")
		(hatch none 0.5)
		(connect_pads
			(clearance 0)
		)
		(min_thickness 0.25)
		(keepout
			(tracks not_allowed)
			(vias allowed)
			(pads allowed)
			(copperpour not_allowed)
			(footprints allowed)
		)
		(placement
			(enabled no)
			(sheetname "")
		)
		(fill yes
			(thermal_gap 0.5)
			(thermal_bridge_width 0.5)
			(island_removal_mode 0)
		)
		(polygon
			(pts
				(arc
					(start 255.330198 -310.571388)
					(mid 255.345077 -310.607309)
					(end 255.380998 -310.622188)
				)
				(arc
					(start 256.780538 -310.622188)
					(mid 256.816459 -310.607309)
					(end 256.831338 -310.571388)
				)
				(arc
					(start 256.831338 -310.162448)
					(mid 256.816459 -310.126527)
					(end 256.780538 -310.111648)
				)
				(arc
					(start 255.380998 -310.111648)
					(mid 255.345077 -310.126527)
					(end 255.330198 -310.162448)
				)
			)
		)
	)
	(zone
		(layers "In1.Cu" "In2.Cu")
		(hatch none 0.5)
		(connect_pads
			(clearance 0)
		)
		(min_thickness 0.25)
		(keepout
			(tracks not_allowed)
			(vias allowed)
			(pads allowed)
			(copperpour not_allowed)
			(footprints allowed)
		)
		(placement
			(enabled no)
			(sheetname "")
		)
		(fill yes
			(thermal_gap 0.5)
			(thermal_bridge_width 0.5)
			(island_removal_mode 0)
		)
		(polygon
			(pts
				(arc
					(start 451.265798 -213.671404)
					(mid 451.280677 -213.707325)
					(end 451.316598 -213.722204)
				)
				(arc
					(start 452.716138 -213.722204)
					(mid 452.752059 -213.707325)
					(end 452.766938 -213.671404)
				)
				(arc
					(start 452.766938 -213.262464)
					(mid 452.752059 -213.226543)
					(end 452.716138 -213.211664)
				)
				(arc
					(start 451.316598 -213.211664)
					(mid 451.280677 -213.226543)
					(end 451.265798 -213.262464)
				)
			)
		)
	)
	(zone
		(layers "In1.Cu" "In2.Cu")
		(hatch none 0.5)
		(connect_pads
			(clearance 0)
		)
		(min_thickness 0.25)
		(keepout
			(tracks not_allowed)
			(vias allowed)
			(pads allowed)
			(copperpour not_allowed)
			(footprints allowed)
		)
		(placement
			(enabled no)
			(sheetname "")
		)
		(fill yes
			(thermal_gap 0.5)
			(thermal_bridge_width 0.5)
			(island_removal_mode 0)
		)
		(polygon
			(pts
				(arc
					(start 432.734466 -216.22131)
					(mid 432.749345 -216.257231)
					(end 432.785266 -216.27211)
				)
				(arc
					(start 434.184806 -216.27211)
					(mid 434.220727 -216.257231)
					(end 434.235606 -216.22131)
				)
				(arc
					(start 434.235606 -215.81237)
					(mid 434.220727 -215.776449)
					(end 434.184806 -215.76157)
				)
				(arc
					(start 432.785266 -215.76157)
					(mid 432.749345 -215.776449)
					(end 432.734466 -215.81237)
				)
			)
		)
	)
	(zone
		(layers "In1.Cu" "In2.Cu")
		(hatch none 0.5)
		(connect_pads
			(clearance 0)
		)
		(min_thickness 0.25)
		(keepout
			(tracks not_allowed)
			(vias allowed)
			(pads allowed)
			(copperpour not_allowed)
			(footprints allowed)
		)
		(placement
			(enabled no)
			(sheetname "")
		)
		(fill yes
			(thermal_gap 0.5)
			(thermal_bridge_width 0.5)
			(island_removal_mode 0)
		)
		(polygon
			(pts
				(arc
					(start 52.65293 -210.27136)
					(mid 52.667809 -210.307281)
					(end 52.70373 -210.32216)
				)
				(arc
					(start 54.10327 -210.32216)
					(mid 54.139191 -210.307281)
					(end 54.15407 -210.27136)
				)
				(arc
					(start 54.15407 -209.86242)
					(mid 54.139191 -209.826499)
					(end 54.10327 -209.81162)
				)
				(arc
					(start 52.70373 -209.81162)
					(mid 52.667809 -209.826499)
					(end 52.65293 -209.86242)
				)
			)
		)
	)
	(zone
		(layers "In1.Cu" "In2.Cu")
		(hatch none 0.5)
		(connect_pads
			(clearance 0)
		)
		(min_thickness 0.25)
		(keepout
			(tracks not_allowed)
			(vias allowed)
			(pads allowed)
			(copperpour not_allowed)
			(footprints allowed)
		)
		(placement
			(enabled no)
			(sheetname "")
		)
		(fill yes
			(thermal_gap 0.5)
			(thermal_bridge_width 0.5)
			(island_removal_mode 0)
		)
		(polygon
			(pts
				(arc
					(start 22.47773 -198.37146)
					(mid 22.492609 -198.407381)
					(end 22.52853 -198.42226)
				)
				(arc
					(start 23.92807 -198.42226)
					(mid 23.963991 -198.407381)
					(end 23.97887 -198.37146)
				)
				(arc
					(start 23.97887 -197.96252)
					(mid 23.963991 -197.926599)
					(end 23.92807 -197.91172)
				)
				(arc
					(start 22.52853 -197.91172)
					(mid 22.492609 -197.926599)
					(end 22.47773 -197.96252)
				)
			)
		)
	)
	(zone
		(layers "In1.Cu" "In2.Cu")
		(hatch none 0.5)
		(connect_pads
			(clearance 0)
		)
		(min_thickness 0.25)
		(keepout
			(tracks not_allowed)
			(vias allowed)
			(pads allowed)
			(copperpour not_allowed)
			(footprints allowed)
		)
		(placement
			(enabled no)
			(sheetname "")
		)
		(fill yes
			(thermal_gap 0.5)
			(thermal_bridge_width 0.5)
			(island_removal_mode 0)
		)
		(polygon
			(pts
				(arc
					(start 34.121598 -237.471458)
					(mid 34.136477 -237.507379)
					(end 34.172398 -237.522258)
				)
				(arc
					(start 35.571938 -237.522258)
					(mid 35.607859 -237.507379)
					(end 35.622738 -237.471458)
				)
				(arc
					(start 35.622738 -237.062518)
					(mid 35.607859 -237.026597)
					(end 35.571938 -237.011718)
				)
				(arc
					(start 34.172398 -237.011718)
					(mid 34.136477 -237.026597)
					(end 34.121598 -237.062518)
				)
			)
		)
	)
	(zone
		(layers "In1.Cu" "In2.Cu")
		(hatch none 0.5)
		(connect_pads
			(clearance 0)
		)
		(min_thickness 0.25)
		(keepout
			(tracks not_allowed)
			(vias allowed)
			(pads allowed)
			(copperpour not_allowed)
			(footprints allowed)
		)
		(placement
			(enabled no)
			(sheetname "")
		)
		(fill yes
			(thermal_gap 0.5)
			(thermal_bridge_width 0.5)
			(island_removal_mode 0)
		)
		(polygon
			(pts
				(arc
					(start 203.32573 -217.071448)
					(mid 203.340609 -217.107369)
					(end 203.37653 -217.122248)
				)
				(arc
					(start 204.77607 -217.122248)
					(mid 204.811991 -217.107369)
					(end 204.82687 -217.071448)
				)
				(arc
					(start 204.82687 -216.662508)
					(mid 204.811991 -216.626587)
					(end 204.77607 -216.611708)
				)
				(arc
					(start 203.37653 -216.611708)
					(mid 203.340609 -216.626587)
					(end 203.32573 -216.662508)
				)
			)
		)
	)
	(zone
		(layers "In1.Cu" "In2.Cu")
		(hatch none 0.5)
		(connect_pads
			(clearance 0)
		)
		(min_thickness 0.25)
		(keepout
			(tracks not_allowed)
			(vias allowed)
			(pads allowed)
			(copperpour not_allowed)
			(footprints allowed)
		)
		(placement
			(enabled no)
			(sheetname "")
		)
		(fill yes
			(thermal_gap 0.5)
			(thermal_bridge_width 0.5)
			(island_removal_mode 0)
		)
		(polygon
			(pts
				(arc
					(start 14.93393 -314.821316)
					(mid 14.948809 -314.857237)
					(end 14.98473 -314.872116)
				)
				(arc
					(start 16.38427 -314.872116)
					(mid 16.420191 -314.857237)
					(end 16.43507 -314.821316)
				)
				(arc
					(start 16.43507 -314.412376)
					(mid 16.420191 -314.376455)
					(end 16.38427 -314.361576)
				)
				(arc
					(start 14.98473 -314.361576)
					(mid 14.948809 -314.376455)
					(end 14.93393 -314.412376)
				)
			)
		)
	)
	(zone
		(layers "In1.Cu" "In2.Cu")
		(hatch none 0.5)
		(connect_pads
			(clearance 0)
		)
		(min_thickness 0.25)
		(keepout
			(tracks not_allowed)
			(vias allowed)
			(pads allowed)
			(copperpour not_allowed)
			(footprints allowed)
		)
		(placement
			(enabled no)
			(sheetname "")
		)
		(fill yes
			(thermal_gap 0.5)
			(thermal_bridge_width 0.5)
			(island_removal_mode 0)
		)
		(polygon
			(pts
				(arc
					(start 210.86953 -237.471458)
					(mid 210.884409 -237.507379)
					(end 210.92033 -237.522258)
				)
				(arc
					(start 212.31987 -237.522258)
					(mid 212.355791 -237.507379)
					(end 212.37067 -237.471458)
				)
				(arc
					(start 212.37067 -237.062518)
					(mid 212.355791 -237.026597)
					(end 212.31987 -237.011718)
				)
				(arc
					(start 210.92033 -237.011718)
					(mid 210.884409 -237.026597)
					(end 210.86953 -237.062518)
				)
			)
		)
	)
	(zone
		(layers "In1.Cu" "In2.Cu")
		(hatch none 0.5)
		(connect_pads
			(clearance 0)
		)
		(min_thickness 0.25)
		(keepout
			(tracks not_allowed)
			(vias allowed)
			(pads allowed)
			(copperpour not_allowed)
			(footprints allowed)
		)
		(placement
			(enabled no)
			(sheetname "")
		)
		(fill yes
			(thermal_gap 0.5)
			(thermal_bridge_width 0.5)
			(island_removal_mode 0)
		)
		(polygon
			(pts
				(arc
					(start 262.873998 -196.671438)
					(mid 262.888877 -196.707359)
					(end 262.924798 -196.722238)
				)
				(arc
					(start 264.324338 -196.722238)
					(mid 264.360259 -196.707359)
					(end 264.375138 -196.671438)
				)
				(arc
					(start 264.375138 -196.262498)
					(mid 264.360259 -196.226577)
					(end 264.324338 -196.211698)
				)
				(arc
					(start 262.924798 -196.211698)
					(mid 262.888877 -196.226577)
					(end 262.873998 -196.262498)
				)
			)
		)
	)
	(zone
		(layers "In1.Cu" "In2.Cu")
		(hatch none 0.5)
		(connect_pads
			(clearance 0)
		)
		(min_thickness 0.25)
		(keepout
			(tracks not_allowed)
			(vias allowed)
			(pads allowed)
			(copperpour not_allowed)
			(footprints allowed)
		)
		(placement
			(enabled no)
			(sheetname "")
		)
		(fill yes
			(thermal_gap 0.5)
			(thermal_bridge_width 0.5)
			(island_removal_mode 0)
		)
		(polygon
			(pts
				(arc
					(start 455.365866 -260.421374)
					(mid 455.380745 -260.457295)
					(end 455.416666 -260.472174)
				)
				(arc
					(start 456.816206 -260.472174)
					(mid 456.852127 -260.457295)
					(end 456.867006 -260.421374)
				)
				(arc
					(start 456.867006 -260.012434)
					(mid 456.852127 -259.976513)
					(end 456.816206 -259.961634)
				)
				(arc
					(start 455.416666 -259.961634)
					(mid 455.380745 -259.976513)
					(end 455.365866 -260.012434)
				)
			)
		)
	)
	(zone
		(layers "In1.Cu" "In2.Cu")
		(hatch none 0.5)
		(connect_pads
			(clearance 0)
		)
		(min_thickness 0.25)
		(keepout
			(tracks not_allowed)
			(vias allowed)
			(pads allowed)
			(copperpour not_allowed)
			(footprints allowed)
		)
		(placement
			(enabled no)
			(sheetname "")
		)
		(fill yes
			(thermal_gap 0.5)
			(thermal_bridge_width 0.5)
			(island_removal_mode 0)
		)
		(polygon
			(pts
				(arc
					(start 270.417798 -290.171378)
					(mid 270.432677 -290.207299)
					(end 270.468598 -290.222178)
				)
				(arc
					(start 271.868138 -290.222178)
					(mid 271.904059 -290.207299)
					(end 271.918938 -290.171378)
				)
				(arc
					(start 271.918938 -289.762438)
					(mid 271.904059 -289.726517)
					(end 271.868138 -289.711638)
				)
				(arc
					(start 270.468598 -289.711638)
					(mid 270.432677 -289.726517)
					(end 270.417798 -289.762438)
				)
			)
		)
	)
	(zone
		(layers "In1.Cu" "In2.Cu")
		(hatch none 0.5)
		(connect_pads
			(clearance 0)
		)
		(min_thickness 0.25)
		(keepout
			(tracks not_allowed)
			(vias allowed)
			(pads allowed)
			(copperpour not_allowed)
			(footprints allowed)
		)
		(placement
			(enabled no)
			(sheetname "")
		)
		(fill yes
			(thermal_gap 0.5)
			(thermal_bridge_width 0.5)
			(island_removal_mode 0)
		)
		(polygon
			(pts
				(arc
					(start 417.646866 -203.471526)
					(mid 417.661745 -203.507447)
					(end 417.697666 -203.522326)
				)
				(arc
					(start 419.097206 -203.522326)
					(mid 419.133127 -203.507447)
					(end 419.148006 -203.471526)
				)
				(arc
					(start 419.148006 -203.062586)
					(mid 419.133127 -203.026665)
					(end 419.097206 -203.011786)
				)
				(arc
					(start 417.697666 -203.011786)
					(mid 417.661745 -203.026665)
					(end 417.646866 -203.062586)
				)
			)
		)
	)
	(zone
		(layers "In1.Cu" "In2.Cu")
		(hatch none 0.5)
		(connect_pads
			(clearance 0)
		)
		(min_thickness 0.25)
		(keepout
			(tracks not_allowed)
			(vias allowed)
			(pads allowed)
			(copperpour not_allowed)
			(footprints allowed)
		)
		(placement
			(enabled no)
			(sheetname "")
		)
		(fill yes
			(thermal_gap 0.5)
			(thermal_bridge_width 0.5)
			(island_removal_mode 0)
		)
		(polygon
			(pts
				(arc
					(start 447.822066 -283.371544)
					(mid 447.836945 -283.407465)
					(end 447.872866 -283.422344)
				)
				(arc
					(start 449.272406 -283.422344)
					(mid 449.308327 -283.407465)
					(end 449.323206 -283.371544)
				)
				(arc
					(start 449.323206 -282.962604)
					(mid 449.308327 -282.926683)
					(end 449.272406 -282.911804)
				)
				(arc
					(start 447.872866 -282.911804)
					(mid 447.836945 -282.926683)
					(end 447.822066 -282.962604)
				)
			)
		)
	)
	(zone
		(layers "In1.Cu" "In2.Cu")
		(hatch none 0.5)
		(connect_pads
			(clearance 0)
		)
		(min_thickness 0.25)
		(keepout
			(tracks not_allowed)
			(vias allowed)
			(pads allowed)
			(copperpour not_allowed)
			(footprints allowed)
		)
		(placement
			(enabled no)
			(sheetname "")
		)
		(fill yes
			(thermal_gap 0.5)
			(thermal_bridge_width 0.5)
			(island_removal_mode 0)
		)
		(polygon
			(pts
				(arc
					(start 19.033998 -220.471492)
					(mid 19.048877 -220.507413)
					(end 19.084798 -220.522292)
				)
				(arc
					(start 20.484338 -220.522292)
					(mid 20.520259 -220.507413)
					(end 20.535138 -220.471492)
				)
				(arc
					(start 20.535138 -220.062552)
					(mid 20.520259 -220.026631)
					(end 20.484338 -220.011752)
				)
				(arc
					(start 19.084798 -220.011752)
					(mid 19.048877 -220.026631)
					(end 19.033998 -220.062552)
				)
			)
		)
	)
	(zone
		(layers "In1.Cu" "In2.Cu")
		(hatch none 0.5)
		(connect_pads
			(clearance 0)
		)
		(min_thickness 0.25)
		(keepout
			(tracks not_allowed)
			(vias allowed)
			(pads allowed)
			(copperpour not_allowed)
			(footprints allowed)
		)
		(placement
			(enabled no)
			(sheetname "")
		)
		(fill yes
			(thermal_gap 0.5)
			(thermal_bridge_width 0.5)
			(island_removal_mode 0)
		)
		(polygon
			(pts
				(arc
					(start 11.490198 -276.571456)
					(mid 11.505077 -276.607377)
					(end 11.540998 -276.622256)
				)
				(arc
					(start 12.940538 -276.622256)
					(mid 12.976459 -276.607377)
					(end 12.991338 -276.571456)
				)
				(arc
					(start 12.991338 -276.162516)
					(mid 12.976459 -276.126595)
					(end 12.940538 -276.111716)
				)
				(arc
					(start 11.540998 -276.111716)
					(mid 11.505077 -276.126595)
					(end 11.490198 -276.162516)
				)
			)
		)
	)
	(zone
		(layers "In1.Cu" "In2.Cu")
		(hatch none 0.5)
		(connect_pads
			(clearance 0)
		)
		(min_thickness 0.25)
		(keepout
			(tracks not_allowed)
			(vias allowed)
			(pads allowed)
			(copperpour not_allowed)
			(footprints allowed)
		)
		(placement
			(enabled no)
			(sheetname "")
		)
		(fill yes
			(thermal_gap 0.5)
			(thermal_bridge_width 0.5)
			(island_removal_mode 0)
		)
		(polygon
			(pts
				(arc
					(start 425.190666 -311.421526)
					(mid 425.205545 -311.457447)
					(end 425.241466 -311.472326)
				)
				(arc
					(start 426.641006 -311.472326)
					(mid 426.676927 -311.457447)
					(end 426.691806 -311.421526)
				)
				(arc
					(start 426.691806 -311.012586)
					(mid 426.676927 -310.976665)
					(end 426.641006 -310.961786)
				)
				(arc
					(start 425.241466 -310.961786)
					(mid 425.205545 -310.976665)
					(end 425.190666 -311.012586)
				)
			)
		)
	)
	(zone
		(layers "In1.Cu" "In2.Cu")
		(hatch none 0.5)
		(connect_pads
			(clearance 0)
		)
		(min_thickness 0.25)
		(keepout
			(tracks not_allowed)
			(vias allowed)
			(pads allowed)
			(copperpour not_allowed)
			(footprints allowed)
		)
		(placement
			(enabled no)
			(sheetname "")
		)
		(fill yes
			(thermal_gap 0.5)
			(thermal_bridge_width 0.5)
			(island_removal_mode 0)
		)
		(polygon
			(pts
				(arc
					(start 421.090598 -219.621354)
					(mid 421.105477 -219.657275)
					(end 421.141398 -219.672154)
				)
				(arc
					(start 422.540938 -219.672154)
					(mid 422.576859 -219.657275)
					(end 422.591738 -219.621354)
				)
				(arc
					(start 422.591738 -219.212414)
					(mid 422.576859 -219.176493)
					(end 422.540938 -219.161614)
				)
				(arc
					(start 421.141398 -219.161614)
					(mid 421.105477 -219.176493)
					(end 421.090598 -219.212414)
				)
			)
		)
	)
	(zone
		(layers "In1.Cu" "In2.Cu")
		(hatch none 0.5)
		(connect_pads
			(clearance 0)
		)
		(min_thickness 0.25)
		(keepout
			(tracks not_allowed)
			(vias allowed)
			(pads allowed)
			(copperpour not_allowed)
			(footprints allowed)
		)
		(placement
			(enabled no)
			(sheetname "")
		)
		(fill yes
			(thermal_gap 0.5)
			(thermal_bridge_width 0.5)
			(island_removal_mode 0)
		)
		(polygon
			(pts
				(arc
					(start 300.592998 -273.171412)
					(mid 300.607877 -273.207333)
					(end 300.643798 -273.222212)
				)
				(arc
					(start 302.043338 -273.222212)
					(mid 302.079259 -273.207333)
					(end 302.094138 -273.171412)
				)
				(arc
					(start 302.094138 -272.762472)
					(mid 302.079259 -272.726551)
					(end 302.043338 -272.711672)
				)
				(arc
					(start 300.643798 -272.711672)
					(mid 300.607877 -272.726551)
					(end 300.592998 -272.762472)
				)
			)
		)
	)
	(zone
		(layers "In1.Cu" "In2.Cu")
		(hatch none 0.5)
		(connect_pads
			(clearance 0)
		)
		(min_thickness 0.25)
		(keepout
			(tracks not_allowed)
			(vias allowed)
			(pads allowed)
			(copperpour not_allowed)
			(footprints allowed)
		)
		(placement
			(enabled no)
			(sheetname "")
		)
		(fill yes
			(thermal_gap 0.5)
			(thermal_bridge_width 0.5)
			(island_removal_mode 0)
		)
		(polygon
			(pts
				(arc
					(start 192.338198 -292.721538)
					(mid 192.353077 -292.757459)
					(end 192.388998 -292.772338)
				)
				(arc
					(start 193.788538 -292.772338)
					(mid 193.824459 -292.757459)
					(end 193.839338 -292.721538)
				)
				(arc
					(start 193.839338 -292.312598)
					(mid 193.824459 -292.276677)
					(end 193.788538 -292.261798)
				)
				(arc
					(start 192.388998 -292.261798)
					(mid 192.353077 -292.276677)
					(end 192.338198 -292.312598)
				)
			)
		)
	)
	(zone
		(layers "In1.Cu" "In2.Cu")
		(hatch none 0.5)
		(connect_pads
			(clearance 0)
		)
		(min_thickness 0.25)
		(keepout
			(tracks not_allowed)
			(vias allowed)
			(pads allowed)
			(copperpour not_allowed)
			(footprints allowed)
		)
		(placement
			(enabled no)
			(sheetname "")
		)
		(fill yes
			(thermal_gap 0.5)
			(thermal_bridge_width 0.5)
			(island_removal_mode 0)
		)
		(polygon
			(pts
				(arc
					(start 165.60673 -301.221394)
					(mid 165.621609 -301.257315)
					(end 165.65753 -301.272194)
				)
				(arc
					(start 167.05707 -301.272194)
					(mid 167.092991 -301.257315)
					(end 167.10787 -301.221394)
				)
				(arc
					(start 167.10787 -300.812454)
					(mid 167.092991 -300.776533)
					(end 167.05707 -300.761654)
				)
				(arc
					(start 165.65753 -300.761654)
					(mid 165.621609 -300.776533)
					(end 165.60673 -300.812454)
				)
			)
		)
	)
	(zone
		(layers "In1.Cu" "In2.Cu")
		(hatch none 0.5)
		(connect_pads
			(clearance 0)
		)
		(min_thickness 0.25)
		(keepout
			(tracks not_allowed)
			(vias allowed)
			(pads allowed)
			(copperpour not_allowed)
			(footprints allowed)
		)
		(placement
			(enabled no)
			(sheetname "")
		)
		(fill yes
			(thermal_gap 0.5)
			(thermal_bridge_width 0.5)
			(island_removal_mode 0)
		)
		(polygon
			(pts
				(arc
					(start 34.121598 -214.521542)
					(mid 34.136477 -214.557463)
					(end 34.172398 -214.572342)
				)
				(arc
					(start 35.571938 -214.572342)
					(mid 35.607859 -214.557463)
					(end 35.622738 -214.521542)
				)
				(arc
					(start 35.622738 -214.112602)
					(mid 35.607859 -214.076681)
					(end 35.571938 -214.061802)
				)
				(arc
					(start 34.172398 -214.061802)
					(mid 34.136477 -214.076681)
					(end 34.121598 -214.112602)
				)
			)
		)
	)
	(zone
		(layers "In1.Cu" "In2.Cu")
		(hatch none 0.5)
		(connect_pads
			(clearance 0)
		)
		(min_thickness 0.25)
		(keepout
			(tracks not_allowed)
			(vias allowed)
			(pads allowed)
			(copperpour not_allowed)
			(footprints allowed)
		)
		(placement
			(enabled no)
			(sheetname "")
		)
		(fill yes
			(thermal_gap 0.5)
			(thermal_bridge_width 0.5)
			(island_removal_mode 0)
		)
		(polygon
			(pts
				(arc
					(start 274.517866 -270.621506)
					(mid 274.532745 -270.657427)
					(end 274.568666 -270.672306)
				)
				(arc
					(start 275.968206 -270.672306)
					(mid 276.004127 -270.657427)
					(end 276.019006 -270.621506)
				)
				(arc
					(start 276.019006 -270.212566)
					(mid 276.004127 -270.176645)
					(end 275.968206 -270.161766)
				)
				(arc
					(start 274.568666 -270.161766)
					(mid 274.532745 -270.176645)
					(end 274.517866 -270.212566)
				)
			)
		)
	)
	(zone
		(layers "In1.Cu" "In2.Cu")
		(hatch none 0.5)
		(connect_pads
			(clearance 0)
		)
		(min_thickness 0.25)
		(keepout
			(tracks not_allowed)
			(vias allowed)
			(pads allowed)
			(copperpour not_allowed)
			(footprints allowed)
		)
		(placement
			(enabled no)
			(sheetname "")
		)
		(fill yes
			(thermal_gap 0.5)
			(thermal_bridge_width 0.5)
			(island_removal_mode 0)
		)
		(polygon
			(pts
				(arc
					(start 308.136798 -261.271512)
					(mid 308.151677 -261.307433)
					(end 308.187598 -261.322312)
				)
				(arc
					(start 309.587138 -261.322312)
					(mid 309.623059 -261.307433)
					(end 309.637938 -261.271512)
				)
				(arc
					(start 309.637938 -260.862572)
					(mid 309.623059 -260.826651)
					(end 309.587138 -260.811772)
				)
				(arc
					(start 308.187598 -260.811772)
					(mid 308.151677 -260.826651)
					(end 308.136798 -260.862572)
				)
			)
		)
	)
	(zone
		(layers "In1.Cu" "In2.Cu")
		(hatch none 0.5)
		(connect_pads
			(clearance 0)
		)
		(min_thickness 0.25)
		(keepout
			(tracks not_allowed)
			(vias allowed)
			(pads allowed)
			(copperpour not_allowed)
			(footprints allowed)
		)
		(placement
			(enabled no)
			(sheetname "")
		)
		(fill yes
			(thermal_gap 0.5)
			(thermal_bridge_width 0.5)
			(island_removal_mode 0)
		)
		(polygon
			(pts
				(arc
					(start 184.794398 -265.52144)
					(mid 184.809277 -265.557361)
					(end 184.845198 -265.57224)
				)
				(arc
					(start 186.244738 -265.57224)
					(mid 186.280659 -265.557361)
					(end 186.295538 -265.52144)
				)
				(arc
					(start 186.295538 -265.1125)
					(mid 186.280659 -265.076579)
					(end 186.244738 -265.0617)
				)
				(arc
					(start 184.845198 -265.0617)
					(mid 184.809277 -265.076579)
					(end 184.794398 -265.1125)
				)
			)
		)
	)
	(zone
		(layers "In1.Cu" "In2.Cu")
		(hatch none 0.5)
		(connect_pads
			(clearance 0)
		)
		(min_thickness 0.25)
		(keepout
			(tracks not_allowed)
			(vias allowed)
			(pads allowed)
			(copperpour not_allowed)
			(footprints allowed)
		)
		(placement
			(enabled no)
			(sheetname "")
		)
		(fill yes
			(thermal_gap 0.5)
			(thermal_bridge_width 0.5)
			(island_removal_mode 0)
		)
		(polygon
			(pts
				(arc
					(start 169.706798 -291.021516)
					(mid 169.721677 -291.057437)
					(end 169.757598 -291.072316)
				)
				(arc
					(start 171.157138 -291.072316)
					(mid 171.193059 -291.057437)
					(end 171.207938 -291.021516)
				)
				(arc
					(start 171.207938 -290.612576)
					(mid 171.193059 -290.576655)
					(end 171.157138 -290.561776)
				)
				(arc
					(start 169.757598 -290.561776)
					(mid 169.721677 -290.576655)
					(end 169.706798 -290.612576)
				)
			)
		)
	)
	(zone
		(layers "In1.Cu" "In2.Cu")
		(hatch none 0.5)
		(connect_pads
			(clearance 0)
		)
		(min_thickness 0.25)
		(keepout
			(tracks not_allowed)
			(vias allowed)
			(pads allowed)
			(copperpour not_allowed)
			(footprints allowed)
		)
		(placement
			(enabled no)
			(sheetname "")
		)
		(fill yes
			(thermal_gap 0.5)
			(thermal_bridge_width 0.5)
			(island_removal_mode 0)
		)
		(polygon
			(pts
				(arc
					(start 56.752998 -195.821554)
					(mid 56.767877 -195.857475)
					(end 56.803798 -195.872354)
				)
				(arc
					(start 58.203338 -195.872354)
					(mid 58.239259 -195.857475)
					(end 58.254138 -195.821554)
				)
				(arc
					(start 58.254138 -195.412614)
					(mid 58.239259 -195.376693)
					(end 58.203338 -195.361814)
				)
				(arc
					(start 56.803798 -195.361814)
					(mid 56.767877 -195.376693)
					(end 56.752998 -195.412614)
				)
			)
		)
	)
	(zone
		(layers "In1.Cu" "In2.Cu")
		(hatch none 0.5)
		(connect_pads
			(clearance 0)
		)
		(min_thickness 0.25)
		(keepout
			(tracks not_allowed)
			(vias allowed)
			(pads allowed)
			(copperpour not_allowed)
			(footprints allowed)
		)
		(placement
			(enabled no)
			(sheetname "")
		)
		(fill yes
			(thermal_gap 0.5)
			(thermal_bridge_width 0.5)
			(island_removal_mode 0)
		)
		(polygon
			(pts
				(arc
					(start 293.049198 -215.371426)
					(mid 293.064077 -215.407347)
					(end 293.099998 -215.422226)
				)
				(arc
					(start 294.499538 -215.422226)
					(mid 294.535459 -215.407347)
					(end 294.550338 -215.371426)
				)
				(arc
					(start 294.550338 -214.962486)
					(mid 294.535459 -214.926565)
					(end 294.499538 -214.911686)
				)
				(arc
					(start 293.099998 -214.911686)
					(mid 293.064077 -214.926565)
					(end 293.049198 -214.962486)
				)
			)
		)
	)
	(zone
		(layers "In1.Cu" "In2.Cu")
		(hatch none 0.5)
		(connect_pads
			(clearance 0)
		)
		(min_thickness 0.25)
		(keepout
			(tracks not_allowed)
			(vias allowed)
			(pads allowed)
			(copperpour not_allowed)
			(footprints allowed)
		)
		(placement
			(enabled no)
			(sheetname "")
		)
		(fill yes
			(thermal_gap 0.5)
			(thermal_bridge_width 0.5)
			(island_removal_mode 0)
		)
		(polygon
			(pts
				(arc
					(start 455.365866 -195.821554)
					(mid 455.380745 -195.857475)
					(end 455.416666 -195.872354)
				)
				(arc
					(start 456.816206 -195.872354)
					(mid 456.852127 -195.857475)
					(end 456.867006 -195.821554)
				)
				(arc
					(start 456.867006 -195.412614)
					(mid 456.852127 -195.376693)
					(end 456.816206 -195.361814)
				)
				(arc
					(start 455.416666 -195.361814)
					(mid 455.380745 -195.376693)
					(end 455.365866 -195.412614)
				)
			)
		)
	)
	(zone
		(layers "In1.Cu" "In2.Cu")
		(hatch none 0.5)
		(connect_pads
			(clearance 0)
		)
		(min_thickness 0.25)
		(keepout
			(tracks not_allowed)
			(vias allowed)
			(pads allowed)
			(copperpour not_allowed)
			(footprints allowed)
		)
		(placement
			(enabled no)
			(sheetname "")
		)
		(fill yes
			(thermal_gap 0.5)
			(thermal_bridge_width 0.5)
			(island_removal_mode 0)
		)
		(polygon
			(pts
				(arc
					(start 207.425798 -206.871316)
					(mid 207.440677 -206.907237)
					(end 207.476598 -206.922116)
				)
				(arc
					(start 208.876138 -206.922116)
					(mid 208.912059 -206.907237)
					(end 208.926938 -206.871316)
				)
				(arc
					(start 208.926938 -206.462376)
					(mid 208.912059 -206.426455)
					(end 208.876138 -206.411576)
				)
				(arc
					(start 207.476598 -206.411576)
					(mid 207.440677 -206.426455)
					(end 207.425798 -206.462376)
				)
			)
		)
	)
	(zone
		(layers "In1.Cu" "In2.Cu")
		(hatch none 0.5)
		(connect_pads
			(clearance 0)
		)
		(min_thickness 0.25)
		(keepout
			(tracks not_allowed)
			(vias allowed)
			(pads allowed)
			(copperpour not_allowed)
			(footprints allowed)
		)
		(placement
			(enabled no)
			(sheetname "")
		)
		(fill yes
			(thermal_gap 0.5)
			(thermal_bridge_width 0.5)
			(island_removal_mode 0)
		)
		(polygon
			(pts
				(arc
					(start 312.236866 -236.62132)
					(mid 312.251745 -236.657241)
					(end 312.287666 -236.67212)
				)
				(arc
					(start 313.687206 -236.67212)
					(mid 313.723127 -236.657241)
					(end 313.738006 -236.62132)
				)
				(arc
					(start 313.738006 -236.21238)
					(mid 313.723127 -236.176459)
					(end 313.687206 -236.16158)
				)
				(arc
					(start 312.287666 -236.16158)
					(mid 312.251745 -236.176459)
					(end 312.236866 -236.21238)
				)
			)
		)
	)
	(zone
		(layers "In1.Cu" "In2.Cu")
		(hatch none 0.5)
		(connect_pads
			(clearance 0)
		)
		(min_thickness 0.25)
		(keepout
			(tracks not_allowed)
			(vias allowed)
			(pads allowed)
			(copperpour not_allowed)
			(footprints allowed)
		)
		(placement
			(enabled no)
			(sheetname "")
		)
		(fill yes
			(thermal_gap 0.5)
			(thermal_bridge_width 0.5)
			(island_removal_mode 0)
		)
		(polygon
			(pts
				(arc
					(start 421.090598 -252.771402)
					(mid 421.105477 -252.807323)
					(end 421.141398 -252.822202)
				)
				(arc
					(start 422.540938 -252.822202)
					(mid 422.576859 -252.807323)
					(end 422.591738 -252.771402)
				)
				(arc
					(start 422.591738 -252.362462)
					(mid 422.576859 -252.326541)
					(end 422.540938 -252.311662)
				)
				(arc
					(start 421.141398 -252.311662)
					(mid 421.105477 -252.326541)
					(end 421.090598 -252.362462)
				)
			)
		)
	)
	(zone
		(layers "In1.Cu" "In2.Cu")
		(hatch none 0.5)
		(connect_pads
			(clearance 0)
		)
		(min_thickness 0.25)
		(keepout
			(tracks not_allowed)
			(vias allowed)
			(pads allowed)
			(copperpour not_allowed)
			(footprints allowed)
		)
		(placement
			(enabled no)
			(sheetname "")
		)
		(fill yes
			(thermal_gap 0.5)
			(thermal_bridge_width 0.5)
			(island_removal_mode 0)
		)
		(polygon
			(pts
				(arc
					(start 436.178198 -264.671302)
					(mid 436.193077 -264.707223)
					(end 436.228998 -264.722102)
				)
				(arc
					(start 437.628538 -264.722102)
					(mid 437.664459 -264.707223)
					(end 437.679338 -264.671302)
				)
				(arc
					(start 437.679338 -264.262362)
					(mid 437.664459 -264.226441)
					(end 437.628538 -264.211562)
				)
				(arc
					(start 436.228998 -264.211562)
					(mid 436.193077 -264.226441)
					(end 436.178198 -264.262362)
				)
			)
		)
	)
	(zone
		(layers "In1.Cu" "In2.Cu")
		(hatch none 0.5)
		(connect_pads
			(clearance 0)
		)
		(min_thickness 0.25)
		(keepout
			(tracks not_allowed)
			(vias allowed)
			(pads allowed)
			(copperpour not_allowed)
			(footprints allowed)
		)
		(placement
			(enabled no)
			(sheetname "")
		)
		(fill yes
			(thermal_gap 0.5)
			(thermal_bridge_width 0.5)
			(island_removal_mode 0)
		)
		(polygon
			(pts
				(arc
					(start 45.10913 -207.721454)
					(mid 45.124009 -207.757375)
					(end 45.15993 -207.772254)
				)
				(arc
					(start 46.55947 -207.772254)
					(mid 46.595391 -207.757375)
					(end 46.61027 -207.721454)
				)
				(arc
					(start 46.61027 -207.312514)
					(mid 46.595391 -207.276593)
					(end 46.55947 -207.261714)
				)
				(arc
					(start 45.15993 -207.261714)
					(mid 45.124009 -207.276593)
					(end 45.10913 -207.312514)
				)
			)
		)
	)
	(zone
		(layers "In1.Cu" "In2.Cu")
		(hatch none 0.5)
		(connect_pads
			(clearance 0)
		)
		(min_thickness 0.25)
		(keepout
			(tracks not_allowed)
			(vias allowed)
			(pads allowed)
			(copperpour not_allowed)
			(footprints allowed)
		)
		(placement
			(enabled no)
			(sheetname "")
		)
		(fill yes
			(thermal_gap 0.5)
			(thermal_bridge_width 0.5)
			(island_removal_mode 0)
		)
		(polygon
			(pts
				(arc
					(start 417.646866 -245.12143)
					(mid 417.661745 -245.157351)
					(end 417.697666 -245.17223)
				)
				(arc
					(start 419.097206 -245.17223)
					(mid 419.133127 -245.157351)
					(end 419.148006 -245.12143)
				)
				(arc
					(start 419.148006 -244.71249)
					(mid 419.133127 -244.676569)
					(end 419.097206 -244.66169)
				)
				(arc
					(start 417.697666 -244.66169)
					(mid 417.661745 -244.676569)
					(end 417.646866 -244.71249)
				)
			)
		)
	)
	(zone
		(layers "In1.Cu" "In2.Cu")
		(hatch none 0.5)
		(connect_pads
			(clearance 0)
		)
		(min_thickness 0.25)
		(keepout
			(tracks not_allowed)
			(vias allowed)
			(pads allowed)
			(copperpour not_allowed)
			(footprints allowed)
		)
		(placement
			(enabled no)
			(sheetname "")
		)
		(fill yes
			(thermal_gap 0.5)
			(thermal_bridge_width 0.5)
			(island_removal_mode 0)
		)
		(polygon
			(pts
				(arc
					(start 417.646866 -295.271444)
					(mid 417.661745 -295.307365)
					(end 417.697666 -295.322244)
				)
				(arc
					(start 419.097206 -295.322244)
					(mid 419.133127 -295.307365)
					(end 419.148006 -295.271444)
				)
				(arc
					(start 419.148006 -294.862504)
					(mid 419.133127 -294.826583)
					(end 419.097206 -294.811704)
				)
				(arc
					(start 417.697666 -294.811704)
					(mid 417.661745 -294.826583)
					(end 417.646866 -294.862504)
				)
			)
		)
	)
	(zone
		(layers "In1.Cu" "In2.Cu")
		(hatch none 0.5)
		(connect_pads
			(clearance 0)
		)
		(min_thickness 0.25)
		(keepout
			(tracks not_allowed)
			(vias allowed)
			(pads allowed)
			(copperpour not_allowed)
			(footprints allowed)
		)
		(placement
			(enabled no)
			(sheetname "")
		)
		(fill yes
			(thermal_gap 0.5)
			(thermal_bridge_width 0.5)
			(island_removal_mode 0)
		)
		(polygon
			(pts
				(arc
					(start 214.969598 -214.521542)
					(mid 214.984477 -214.557463)
					(end 215.020398 -214.572342)
				)
				(arc
					(start 216.419938 -214.572342)
					(mid 216.455859 -214.557463)
					(end 216.470738 -214.521542)
				)
				(arc
					(start 216.470738 -214.112602)
					(mid 216.455859 -214.076681)
					(end 216.419938 -214.061802)
				)
				(arc
					(start 215.020398 -214.061802)
					(mid 214.984477 -214.076681)
					(end 214.969598 -214.112602)
				)
			)
		)
	)
	(zone
		(layers "In1.Cu" "In2.Cu")
		(hatch none 0.5)
		(connect_pads
			(clearance 0)
		)
		(min_thickness 0.25)
		(keepout
			(tracks not_allowed)
			(vias allowed)
			(pads allowed)
			(copperpour not_allowed)
			(footprints allowed)
		)
		(placement
			(enabled no)
			(sheetname "")
		)
		(fill yes
			(thermal_gap 0.5)
			(thermal_bridge_width 0.5)
			(island_removal_mode 0)
		)
		(polygon
			(pts
				(arc
					(start 203.32573 -202.621388)
					(mid 203.340609 -202.657309)
					(end 203.37653 -202.672188)
				)
				(arc
					(start 204.77607 -202.672188)
					(mid 204.811991 -202.657309)
					(end 204.82687 -202.621388)
				)
				(arc
					(start 204.82687 -202.212448)
					(mid 204.811991 -202.176527)
					(end 204.77607 -202.161648)
				)
				(arc
					(start 203.37653 -202.161648)
					(mid 203.340609 -202.176527)
					(end 203.32573 -202.212448)
				)
			)
		)
	)
	(zone
		(layers "In1.Cu" "In2.Cu")
		(hatch none 0.5)
		(connect_pads
			(clearance 0)
		)
		(min_thickness 0.25)
		(keepout
			(tracks not_allowed)
			(vias allowed)
			(pads allowed)
			(copperpour not_allowed)
			(footprints allowed)
		)
		(placement
			(enabled no)
			(sheetname "")
		)
		(fill yes
			(thermal_gap 0.5)
			(thermal_bridge_width 0.5)
			(island_removal_mode 0)
		)
		(polygon
			(pts
				(arc
					(start 22.47773 -245.971314)
					(mid 22.492609 -246.007235)
					(end 22.52853 -246.022114)
				)
				(arc
					(start 23.92807 -246.022114)
					(mid 23.963991 -246.007235)
					(end 23.97887 -245.971314)
				)
				(arc
					(start 23.97887 -245.562374)
					(mid 23.963991 -245.526453)
					(end 23.92807 -245.511574)
				)
				(arc
					(start 22.52853 -245.511574)
					(mid 22.492609 -245.526453)
					(end 22.47773 -245.562374)
				)
			)
		)
	)
	(zone
		(layers "In1.Cu" "In2.Cu")
		(hatch none 0.5)
		(connect_pads
			(clearance 0)
		)
		(min_thickness 0.25)
		(keepout
			(tracks not_allowed)
			(vias allowed)
			(pads allowed)
			(copperpour not_allowed)
			(footprints allowed)
		)
		(placement
			(enabled no)
			(sheetname "")
		)
		(fill yes
			(thermal_gap 0.5)
			(thermal_bridge_width 0.5)
			(island_removal_mode 0)
		)
		(polygon
			(pts
				(arc
					(start 462.909666 -240.871502)
					(mid 462.924545 -240.907423)
					(end 462.960466 -240.922302)
				)
				(arc
					(start 464.360006 -240.922302)
					(mid 464.395927 -240.907423)
					(end 464.410806 -240.871502)
				)
				(arc
					(start 464.410806 -240.462562)
					(mid 464.395927 -240.426641)
					(end 464.360006 -240.411762)
				)
				(arc
					(start 462.960466 -240.411762)
					(mid 462.924545 -240.426641)
					(end 462.909666 -240.462562)
				)
			)
		)
	)
	(zone
		(layers "In1.Cu" "In2.Cu")
		(hatch none 0.5)
		(connect_pads
			(clearance 0)
		)
		(min_thickness 0.25)
		(keepout
			(tracks not_allowed)
			(vias allowed)
			(pads allowed)
			(copperpour not_allowed)
			(footprints allowed)
		)
		(placement
			(enabled no)
			(sheetname "")
		)
		(fill yes
			(thermal_gap 0.5)
			(thermal_bridge_width 0.5)
			(island_removal_mode 0)
		)
		(polygon
			(pts
				(arc
					(start 188.23813 -209.421476)
					(mid 188.253009 -209.457397)
					(end 188.28893 -209.472276)
				)
				(arc
					(start 189.68847 -209.472276)
					(mid 189.724391 -209.457397)
					(end 189.73927 -209.421476)
				)
				(arc
					(start 189.73927 -209.012536)
					(mid 189.724391 -208.976615)
					(end 189.68847 -208.961736)
				)
				(arc
					(start 188.28893 -208.961736)
					(mid 188.253009 -208.976615)
					(end 188.23813 -209.012536)
				)
			)
		)
	)
	(zone
		(layers "In1.Cu" "In2.Cu")
		(hatch none 0.5)
		(connect_pads
			(clearance 0)
		)
		(min_thickness 0.25)
		(keepout
			(tracks not_allowed)
			(vias allowed)
			(pads allowed)
			(copperpour not_allowed)
			(footprints allowed)
		)
		(placement
			(enabled no)
			(sheetname "")
		)
		(fill yes
			(thermal_gap 0.5)
			(thermal_bridge_width 0.5)
			(island_removal_mode 0)
		)
		(polygon
			(pts
				(arc
					(start 188.23813 -206.021432)
					(mid 188.253009 -206.057353)
					(end 188.28893 -206.072232)
				)
				(arc
					(start 189.68847 -206.072232)
					(mid 189.724391 -206.057353)
					(end 189.73927 -206.021432)
				)
				(arc
					(start 189.73927 -205.612492)
					(mid 189.724391 -205.576571)
					(end 189.68847 -205.561692)
				)
				(arc
					(start 188.28893 -205.561692)
					(mid 188.253009 -205.576571)
					(end 188.23813 -205.612492)
				)
			)
		)
	)
	(zone
		(layers "In1.Cu" "In2.Cu")
		(hatch none 0.5)
		(connect_pads
			(clearance 0)
		)
		(min_thickness 0.25)
		(keepout
			(tracks not_allowed)
			(vias allowed)
			(pads allowed)
			(copperpour not_allowed)
			(footprints allowed)
		)
		(placement
			(enabled no)
			(sheetname "")
		)
		(fill yes
			(thermal_gap 0.5)
			(thermal_bridge_width 0.5)
			(island_removal_mode 0)
		)
		(polygon
			(pts
				(arc
					(start 262.873998 -219.621354)
					(mid 262.888877 -219.657275)
					(end 262.924798 -219.672154)
				)
				(arc
					(start 264.324338 -219.672154)
					(mid 264.360259 -219.657275)
					(end 264.375138 -219.621354)
				)
				(arc
					(start 264.375138 -219.212414)
					(mid 264.360259 -219.176493)
					(end 264.324338 -219.161614)
				)
				(arc
					(start 262.924798 -219.161614)
					(mid 262.888877 -219.176493)
					(end 262.873998 -219.212414)
				)
			)
		)
	)
	(zone
		(layers "In1.Cu" "In2.Cu")
		(hatch none 0.5)
		(connect_pads
			(clearance 0)
		)
		(min_thickness 0.25)
		(keepout
			(tracks not_allowed)
			(vias allowed)
			(pads allowed)
			(copperpour not_allowed)
			(footprints allowed)
		)
		(placement
			(enabled no)
			(sheetname "")
		)
		(fill yes
			(thermal_gap 0.5)
			(thermal_bridge_width 0.5)
			(island_removal_mode 0)
		)
		(polygon
			(pts
				(arc
					(start 289.605466 -315.671454)
					(mid 289.620345 -315.707375)
					(end 289.656266 -315.722254)
				)
				(arc
					(start 291.055806 -315.722254)
					(mid 291.091727 -315.707375)
					(end 291.106606 -315.671454)
				)
				(arc
					(start 291.106606 -315.262514)
					(mid 291.091727 -315.226593)
					(end 291.055806 -315.211714)
				)
				(arc
					(start 289.656266 -315.211714)
					(mid 289.620345 -315.226593)
					(end 289.605466 -315.262514)
				)
			)
		)
	)
	(zone
		(layers "In1.Cu" "In2.Cu")
		(hatch none 0.5)
		(connect_pads
			(clearance 0)
		)
		(min_thickness 0.25)
		(keepout
			(tracks not_allowed)
			(vias allowed)
			(pads allowed)
			(copperpour not_allowed)
			(footprints allowed)
		)
		(placement
			(enabled no)
			(sheetname "")
		)
		(fill yes
			(thermal_gap 0.5)
			(thermal_bridge_width 0.5)
			(island_removal_mode 0)
		)
		(polygon
			(pts
				(arc
					(start 413.546798 -312.27141)
					(mid 413.561677 -312.307331)
					(end 413.597598 -312.32221)
				)
				(arc
					(start 414.997138 -312.32221)
					(mid 415.033059 -312.307331)
					(end 415.047938 -312.27141)
				)
				(arc
					(start 415.047938 -311.86247)
					(mid 415.033059 -311.826549)
					(end 414.997138 -311.81167)
				)
				(arc
					(start 413.597598 -311.81167)
					(mid 413.561677 -311.826549)
					(end 413.546798 -311.86247)
				)
			)
		)
	)
	(zone
		(layers "In1.Cu" "In2.Cu")
		(hatch none 0.5)
		(connect_pads
			(clearance 0)
		)
		(min_thickness 0.25)
		(keepout
			(tracks not_allowed)
			(vias allowed)
			(pads allowed)
			(copperpour not_allowed)
			(footprints allowed)
		)
		(placement
			(enabled no)
			(sheetname "")
		)
		(fill yes
			(thermal_gap 0.5)
			(thermal_bridge_width 0.5)
			(island_removal_mode 0)
		)
		(polygon
			(pts
				(arc
					(start 406.002998 -247.671336)
					(mid 406.017877 -247.707257)
					(end 406.053798 -247.722136)
				)
				(arc
					(start 407.453338 -247.722136)
					(mid 407.489259 -247.707257)
					(end 407.504138 -247.671336)
				)
				(arc
					(start 407.504138 -247.262396)
					(mid 407.489259 -247.226475)
					(end 407.453338 -247.211596)
				)
				(arc
					(start 406.053798 -247.211596)
					(mid 406.017877 -247.226475)
					(end 406.002998 -247.262396)
				)
			)
		)
	)
	(zone
		(layers "In1.Cu" "In2.Cu")
		(hatch none 0.5)
		(connect_pads
			(clearance 0)
		)
		(min_thickness 0.25)
		(keepout
			(tracks not_allowed)
			(vias allowed)
			(pads allowed)
			(copperpour not_allowed)
			(footprints allowed)
		)
		(placement
			(enabled no)
			(sheetname "")
		)
		(fill yes
			(thermal_gap 0.5)
			(thermal_bridge_width 0.5)
			(island_removal_mode 0)
		)
		(polygon
			(pts
				(arc
					(start 443.721998 -266.371324)
					(mid 443.736877 -266.407245)
					(end 443.772798 -266.422124)
				)
				(arc
					(start 445.172338 -266.422124)
					(mid 445.208259 -266.407245)
					(end 445.223138 -266.371324)
				)
				(arc
					(start 445.223138 -265.962384)
					(mid 445.208259 -265.926463)
					(end 445.172338 -265.911584)
				)
				(arc
					(start 443.772798 -265.911584)
					(mid 443.736877 -265.926463)
					(end 443.721998 -265.962384)
				)
			)
		)
	)
	(zone
		(layers "In1.Cu" "In2.Cu")
		(hatch none 0.5)
		(connect_pads
			(clearance 0)
		)
		(min_thickness 0.25)
		(keepout
			(tracks not_allowed)
			(vias allowed)
			(pads allowed)
			(copperpour not_allowed)
			(footprints allowed)
		)
		(placement
			(enabled no)
			(sheetname "")
		)
		(fill yes
			(thermal_gap 0.5)
			(thermal_bridge_width 0.5)
			(island_removal_mode 0)
		)
		(polygon
			(pts
				(arc
					(start 312.236866 -220.471492)
					(mid 312.251745 -220.507413)
					(end 312.287666 -220.522292)
				)
				(arc
					(start 313.687206 -220.522292)
					(mid 313.723127 -220.507413)
					(end 313.738006 -220.471492)
				)
				(arc
					(start 313.738006 -220.062552)
					(mid 313.723127 -220.026631)
					(end 313.687206 -220.011752)
				)
				(arc
					(start 312.287666 -220.011752)
					(mid 312.251745 -220.026631)
					(end 312.236866 -220.062552)
				)
			)
		)
	)
	(zone
		(layers "In1.Cu" "In2.Cu")
		(hatch none 0.5)
		(connect_pads
			(clearance 0)
		)
		(min_thickness 0.25)
		(keepout
			(tracks not_allowed)
			(vias allowed)
			(pads allowed)
			(copperpour not_allowed)
			(footprints allowed)
		)
		(placement
			(enabled no)
			(sheetname "")
		)
		(fill yes
			(thermal_gap 0.5)
			(thermal_bridge_width 0.5)
			(island_removal_mode 0)
		)
		(polygon
			(pts
				(arc
					(start 304.693066 -201.771504)
					(mid 304.707945 -201.807425)
					(end 304.743866 -201.822304)
				)
				(arc
					(start 306.143406 -201.822304)
					(mid 306.179327 -201.807425)
					(end 306.194206 -201.771504)
				)
				(arc
					(start 306.194206 -201.362564)
					(mid 306.179327 -201.326643)
					(end 306.143406 -201.311764)
				)
				(arc
					(start 304.743866 -201.311764)
					(mid 304.707945 -201.326643)
					(end 304.693066 -201.362564)
				)
			)
		)
	)
	(zone
		(layers "In1.Cu" "In2.Cu")
		(hatch none 0.5)
		(connect_pads
			(clearance 0)
		)
		(min_thickness 0.25)
		(keepout
			(tracks not_allowed)
			(vias allowed)
			(pads allowed)
			(copperpour not_allowed)
			(footprints allowed)
		)
		(placement
			(enabled no)
			(sheetname "")
		)
		(fill yes
			(thermal_gap 0.5)
			(thermal_bridge_width 0.5)
			(island_removal_mode 0)
		)
		(polygon
			(pts
				(arc
					(start 458.809598 -264.671302)
					(mid 458.824477 -264.707223)
					(end 458.860398 -264.722102)
				)
				(arc
					(start 460.259938 -264.722102)
					(mid 460.295859 -264.707223)
					(end 460.310738 -264.671302)
				)
				(arc
					(start 460.310738 -264.262362)
					(mid 460.295859 -264.226441)
					(end 460.259938 -264.211562)
				)
				(arc
					(start 458.860398 -264.211562)
					(mid 458.824477 -264.226441)
					(end 458.809598 -264.262362)
				)
			)
		)
	)
	(zone
		(layers "In1.Cu" "In2.Cu")
		(hatch none 0.5)
		(connect_pads
			(clearance 0)
		)
		(min_thickness 0.25)
		(keepout
			(tracks not_allowed)
			(vias allowed)
			(pads allowed)
			(copperpour not_allowed)
			(footprints allowed)
		)
		(placement
			(enabled no)
			(sheetname "")
		)
		(fill yes
			(thermal_gap 0.5)
			(thermal_bridge_width 0.5)
			(island_removal_mode 0)
		)
		(polygon
			(pts
				(arc
					(start 214.969598 -284.221428)
					(mid 214.984477 -284.257349)
					(end 215.020398 -284.272228)
				)
				(arc
					(start 216.419938 -284.272228)
					(mid 216.455859 -284.257349)
					(end 216.470738 -284.221428)
				)
				(arc
					(start 216.470738 -283.812488)
					(mid 216.455859 -283.776567)
					(end 216.419938 -283.761688)
				)
				(arc
					(start 215.020398 -283.761688)
					(mid 214.984477 -283.776567)
					(end 214.969598 -283.812488)
				)
			)
		)
	)
	(zone
		(layers "In1.Cu" "In2.Cu")
		(hatch none 0.5)
		(connect_pads
			(clearance 0)
		)
		(min_thickness 0.25)
		(keepout
			(tracks not_allowed)
			(vias allowed)
			(pads allowed)
			(copperpour not_allowed)
			(footprints allowed)
		)
		(placement
			(enabled no)
			(sheetname "")
		)
		(fill yes
			(thermal_gap 0.5)
			(thermal_bridge_width 0.5)
			(island_removal_mode 0)
		)
		(polygon
			(pts
				(arc
					(start 60.19673 -262.971534)
					(mid 60.211609 -263.007455)
					(end 60.24753 -263.022334)
				)
				(arc
					(start 61.64707 -263.022334)
					(mid 61.682991 -263.007455)
					(end 61.69787 -262.971534)
				)
				(arc
					(start 61.69787 -262.562594)
					(mid 61.682991 -262.526673)
					(end 61.64707 -262.511794)
				)
				(arc
					(start 60.24753 -262.511794)
					(mid 60.211609 -262.526673)
					(end 60.19673 -262.562594)
				)
			)
		)
	)
	(zone
		(layers "In1.Cu" "In2.Cu")
		(hatch none 0.5)
		(connect_pads
			(clearance 0)
		)
		(min_thickness 0.25)
		(keepout
			(tracks not_allowed)
			(vias allowed)
			(pads allowed)
			(copperpour not_allowed)
			(footprints allowed)
		)
		(placement
			(enabled no)
			(sheetname "")
		)
		(fill yes
			(thermal_gap 0.5)
			(thermal_bridge_width 0.5)
			(island_removal_mode 0)
		)
		(polygon
			(pts
				(arc
					(start 49.209198 -279.9715)
					(mid 49.224077 -280.007421)
					(end 49.259998 -280.0223)
				)
				(arc
					(start 50.659538 -280.0223)
					(mid 50.695459 -280.007421)
					(end 50.710338 -279.9715)
				)
				(arc
					(start 50.710338 -279.56256)
					(mid 50.695459 -279.526639)
					(end 50.659538 -279.51176)
				)
				(arc
					(start 49.259998 -279.51176)
					(mid 49.224077 -279.526639)
					(end 49.209198 -279.56256)
				)
			)
		)
	)
	(zone
		(layers "In1.Cu" "In2.Cu")
		(hatch none 0.5)
		(connect_pads
			(clearance 0)
		)
		(min_thickness 0.25)
		(keepout
			(tracks not_allowed)
			(vias allowed)
			(pads allowed)
			(copperpour not_allowed)
			(footprints allowed)
		)
		(placement
			(enabled no)
			(sheetname "")
		)
		(fill yes
			(thermal_gap 0.5)
			(thermal_bridge_width 0.5)
			(island_removal_mode 0)
		)
		(polygon
			(pts
				(arc
					(start 312.236866 -315.671454)
					(mid 312.251745 -315.707375)
					(end 312.287666 -315.722254)
				)
				(arc
					(start 313.687206 -315.722254)
					(mid 313.723127 -315.707375)
					(end 313.738006 -315.671454)
				)
				(arc
					(start 313.738006 -315.262514)
					(mid 313.723127 -315.226593)
					(end 313.687206 -315.211714)
				)
				(arc
					(start 312.287666 -315.211714)
					(mid 312.251745 -315.226593)
					(end 312.236866 -315.262514)
				)
			)
		)
	)
	(zone
		(layers "In1.Cu" "In2.Cu")
		(hatch none 0.5)
		(connect_pads
			(clearance 0)
		)
		(min_thickness 0.25)
		(keepout
			(tracks not_allowed)
			(vias allowed)
			(pads allowed)
			(copperpour not_allowed)
			(footprints allowed)
		)
		(placement
			(enabled no)
			(sheetname "")
		)
		(fill yes
			(thermal_gap 0.5)
			(thermal_bridge_width 0.5)
			(island_removal_mode 0)
		)
		(polygon
			(pts
				(arc
					(start 210.86953 -200.071482)
					(mid 210.884409 -200.107403)
					(end 210.92033 -200.122282)
				)
				(arc
					(start 212.31987 -200.122282)
					(mid 212.355791 -200.107403)
					(end 212.37067 -200.071482)
				)
				(arc
					(start 212.37067 -199.662542)
					(mid 212.355791 -199.626621)
					(end 212.31987 -199.611742)
				)
				(arc
					(start 210.92033 -199.611742)
					(mid 210.884409 -199.626621)
					(end 210.86953 -199.662542)
				)
			)
		)
	)
	(zone
		(layers "In1.Cu" "In2.Cu")
		(hatch none 0.5)
		(connect_pads
			(clearance 0)
		)
		(min_thickness 0.25)
		(keepout
			(tracks not_allowed)
			(vias allowed)
			(pads allowed)
			(copperpour not_allowed)
			(footprints allowed)
		)
		(placement
			(enabled no)
			(sheetname "")
		)
		(fill yes
			(thermal_gap 0.5)
			(thermal_bridge_width 0.5)
			(island_removal_mode 0)
		)
		(polygon
			(pts
				(arc
					(start 60.19673 -308.871366)
					(mid 60.211609 -308.907287)
					(end 60.24753 -308.922166)
				)
				(arc
					(start 61.64707 -308.922166)
					(mid 61.682991 -308.907287)
					(end 61.69787 -308.871366)
				)
				(arc
					(start 61.69787 -308.462426)
					(mid 61.682991 -308.426505)
					(end 61.64707 -308.411626)
				)
				(arc
					(start 60.24753 -308.411626)
					(mid 60.211609 -308.426505)
					(end 60.19673 -308.462426)
				)
			)
		)
	)
	(zone
		(layers "In1.Cu" "In2.Cu")
		(hatch none 0.5)
		(connect_pads
			(clearance 0)
		)
		(min_thickness 0.25)
		(keepout
			(tracks not_allowed)
			(vias allowed)
			(pads allowed)
			(copperpour not_allowed)
			(footprints allowed)
		)
		(placement
			(enabled no)
			(sheetname "")
		)
		(fill yes
			(thermal_gap 0.5)
			(thermal_bridge_width 0.5)
			(island_removal_mode 0)
		)
		(polygon
			(pts
				(arc
					(start 451.265798 -303.7713)
					(mid 451.280677 -303.807221)
					(end 451.316598 -303.8221)
				)
				(arc
					(start 452.716138 -303.8221)
					(mid 452.752059 -303.807221)
					(end 452.766938 -303.7713)
				)
				(arc
					(start 452.766938 -303.36236)
					(mid 452.752059 -303.326439)
					(end 452.716138 -303.31156)
				)
				(arc
					(start 451.316598 -303.31156)
					(mid 451.280677 -303.326439)
					(end 451.265798 -303.36236)
				)
			)
		)
	)
	(zone
		(layers "In1.Cu" "In2.Cu")
		(hatch none 0.5)
		(connect_pads
			(clearance 0)
		)
		(min_thickness 0.25)
		(keepout
			(tracks not_allowed)
			(vias allowed)
			(pads allowed)
			(copperpour not_allowed)
			(footprints allowed)
		)
		(placement
			(enabled no)
			(sheetname "")
		)
		(fill yes
			(thermal_gap 0.5)
			(thermal_bridge_width 0.5)
			(island_removal_mode 0)
		)
		(polygon
			(pts
				(arc
					(start 165.60673 -218.77147)
					(mid 165.621609 -218.807391)
					(end 165.65753 -218.82227)
				)
				(arc
					(start 167.05707 -218.82227)
					(mid 167.092991 -218.807391)
					(end 167.10787 -218.77147)
				)
				(arc
					(start 167.10787 -218.36253)
					(mid 167.092991 -218.326609)
					(end 167.05707 -218.31173)
				)
				(arc
					(start 165.65753 -218.31173)
					(mid 165.621609 -218.326609)
					(end 165.60673 -218.36253)
				)
			)
		)
	)
	(zone
		(layers "In1.Cu" "In2.Cu")
		(hatch none 0.5)
		(connect_pads
			(clearance 0)
		)
		(min_thickness 0.25)
		(keepout
			(tracks not_allowed)
			(vias allowed)
			(pads allowed)
			(copperpour not_allowed)
			(footprints allowed)
		)
		(placement
			(enabled no)
			(sheetname "")
		)
		(fill yes
			(thermal_gap 0.5)
			(thermal_bridge_width 0.5)
			(island_removal_mode 0)
		)
		(polygon
			(pts
				(arc
					(start 410.103066 -304.621438)
					(mid 410.117945 -304.657359)
					(end 410.153866 -304.672238)
				)
				(arc
					(start 411.553406 -304.672238)
					(mid 411.589327 -304.657359)
					(end 411.604206 -304.621438)
				)
				(arc
					(start 411.604206 -304.212498)
					(mid 411.589327 -304.176577)
					(end 411.553406 -304.161698)
				)
				(arc
					(start 410.153866 -304.161698)
					(mid 410.117945 -304.176577)
					(end 410.103066 -304.212498)
				)
			)
		)
	)
	(zone
		(layers "In1.Cu" "In2.Cu")
		(hatch none 0.5)
		(connect_pads
			(clearance 0)
		)
		(min_thickness 0.25)
		(keepout
			(tracks not_allowed)
			(vias allowed)
			(pads allowed)
			(copperpour not_allowed)
			(footprints allowed)
		)
		(placement
			(enabled no)
			(sheetname "")
		)
		(fill yes
			(thermal_gap 0.5)
			(thermal_bridge_width 0.5)
			(island_removal_mode 0)
		)
		(polygon
			(pts
				(arc
					(start 285.505398 -202.621388)
					(mid 285.520277 -202.657309)
					(end 285.556198 -202.672188)
				)
				(arc
					(start 286.955738 -202.672188)
					(mid 286.991659 -202.657309)
					(end 287.006538 -202.621388)
				)
				(arc
					(start 287.006538 -202.212448)
					(mid 286.991659 -202.176527)
					(end 286.955738 -202.161648)
				)
				(arc
					(start 285.556198 -202.161648)
					(mid 285.520277 -202.176527)
					(end 285.505398 -202.212448)
				)
			)
		)
	)
	(zone
		(layers "In1.Cu" "In2.Cu")
		(hatch none 0.5)
		(connect_pads
			(clearance 0)
		)
		(min_thickness 0.25)
		(keepout
			(tracks not_allowed)
			(vias allowed)
			(pads allowed)
			(copperpour not_allowed)
			(footprints allowed)
		)
		(placement
			(enabled no)
			(sheetname "")
		)
		(fill yes
			(thermal_gap 0.5)
			(thermal_bridge_width 0.5)
			(island_removal_mode 0)
		)
		(polygon
			(pts
				(arc
					(start 158.06293 -282.521406)
					(mid 158.077809 -282.557327)
					(end 158.11373 -282.572206)
				)
				(arc
					(start 159.51327 -282.572206)
					(mid 159.549191 -282.557327)
					(end 159.56407 -282.521406)
				)
				(arc
					(start 159.56407 -282.112466)
					(mid 159.549191 -282.076545)
					(end 159.51327 -282.061666)
				)
				(arc
					(start 158.11373 -282.061666)
					(mid 158.077809 -282.076545)
					(end 158.06293 -282.112466)
				)
			)
		)
	)
	(zone
		(layers "In1.Cu" "In2.Cu")
		(hatch none 0.5)
		(connect_pads
			(clearance 0)
		)
		(min_thickness 0.25)
		(keepout
			(tracks not_allowed)
			(vias allowed)
			(pads allowed)
			(copperpour not_allowed)
			(footprints allowed)
		)
		(placement
			(enabled no)
			(sheetname "")
		)
		(fill yes
			(thermal_gap 0.5)
			(thermal_bridge_width 0.5)
			(island_removal_mode 0)
		)
		(polygon
			(pts
				(arc
					(start 199.881998 -313.971432)
					(mid 199.896877 -314.007353)
					(end 199.932798 -314.022232)
				)
				(arc
					(start 201.332338 -314.022232)
					(mid 201.368259 -314.007353)
					(end 201.383138 -313.971432)
				)
				(arc
					(start 201.383138 -313.562492)
					(mid 201.368259 -313.526571)
					(end 201.332338 -313.511692)
				)
				(arc
					(start 199.932798 -313.511692)
					(mid 199.896877 -313.526571)
					(end 199.881998 -313.562492)
				)
			)
		)
	)
	(zone
		(layers "In1.Cu" "In2.Cu")
		(hatch none 0.5)
		(connect_pads
			(clearance 0)
		)
		(min_thickness 0.25)
		(keepout
			(tracks not_allowed)
			(vias allowed)
			(pads allowed)
			(copperpour not_allowed)
			(footprints allowed)
		)
		(placement
			(enabled no)
			(sheetname "")
		)
		(fill yes
			(thermal_gap 0.5)
			(thermal_bridge_width 0.5)
			(island_removal_mode 0)
		)
		(polygon
			(pts
				(arc
					(start 19.033998 -289.321494)
					(mid 19.048877 -289.357415)
					(end 19.084798 -289.372294)
				)
				(arc
					(start 20.484338 -289.372294)
					(mid 20.520259 -289.357415)
					(end 20.535138 -289.321494)
				)
				(arc
					(start 20.535138 -288.912554)
					(mid 20.520259 -288.876633)
					(end 20.484338 -288.861754)
				)
				(arc
					(start 19.084798 -288.861754)
					(mid 19.048877 -288.876633)
					(end 19.033998 -288.912554)
				)
			)
		)
	)
	(zone
		(layers "In1.Cu" "In2.Cu")
		(hatch none 0.5)
		(connect_pads
			(clearance 0)
		)
		(min_thickness 0.25)
		(keepout
			(tracks not_allowed)
			(vias allowed)
			(pads allowed)
			(copperpour not_allowed)
			(footprints allowed)
		)
		(placement
			(enabled no)
			(sheetname "")
		)
		(fill yes
			(thermal_gap 0.5)
			(thermal_bridge_width 0.5)
			(island_removal_mode 0)
		)
		(polygon
			(pts
				(arc
					(start 308.136798 -215.371426)
					(mid 308.151677 -215.407347)
					(end 308.187598 -215.422226)
				)
				(arc
					(start 309.587138 -215.422226)
					(mid 309.623059 -215.407347)
					(end 309.637938 -215.371426)
				)
				(arc
					(start 309.637938 -214.962486)
					(mid 309.623059 -214.926565)
					(end 309.587138 -214.911686)
				)
				(arc
					(start 308.187598 -214.911686)
					(mid 308.151677 -214.926565)
					(end 308.136798 -214.962486)
				)
			)
		)
	)
	(zone
		(layers "In1.Cu" "In2.Cu")
		(hatch none 0.5)
		(connect_pads
			(clearance 0)
		)
		(min_thickness 0.25)
		(keepout
			(tracks not_allowed)
			(vias allowed)
			(pads allowed)
			(copperpour not_allowed)
			(footprints allowed)
		)
		(placement
			(enabled no)
			(sheetname "")
		)
		(fill yes
			(thermal_gap 0.5)
			(thermal_bridge_width 0.5)
			(island_removal_mode 0)
		)
		(polygon
			(pts
				(arc
					(start 413.546798 -219.621354)
					(mid 413.561677 -219.657275)
					(end 413.597598 -219.672154)
				)
				(arc
					(start 414.997138 -219.672154)
					(mid 415.033059 -219.657275)
					(end 415.047938 -219.621354)
				)
				(arc
					(start 415.047938 -219.212414)
					(mid 415.033059 -219.176493)
					(end 414.997138 -219.161614)
				)
				(arc
					(start 413.597598 -219.161614)
					(mid 413.561677 -219.176493)
					(end 413.546798 -219.212414)
				)
			)
		)
	)
	(zone
		(layers "In1.Cu" "In2.Cu")
		(hatch none 0.5)
		(connect_pads
			(clearance 0)
		)
		(min_thickness 0.25)
		(keepout
			(tracks not_allowed)
			(vias allowed)
			(pads allowed)
			(copperpour not_allowed)
			(footprints allowed)
		)
		(placement
			(enabled no)
			(sheetname "")
		)
		(fill yes
			(thermal_gap 0.5)
			(thermal_bridge_width 0.5)
			(island_removal_mode 0)
		)
		(polygon
			(pts
				(arc
					(start 451.265798 -290.171378)
					(mid 451.280677 -290.207299)
					(end 451.316598 -290.222178)
				)
				(arc
					(start 452.716138 -290.222178)
					(mid 452.752059 -290.207299)
					(end 452.766938 -290.171378)
				)
				(arc
					(start 452.766938 -289.762438)
					(mid 452.752059 -289.726517)
					(end 452.716138 -289.711638)
				)
				(arc
					(start 451.316598 -289.711638)
					(mid 451.280677 -289.726517)
					(end 451.265798 -289.762438)
				)
			)
		)
	)
	(zone
		(layers "In1.Cu" "In2.Cu")
		(hatch none 0.5)
		(connect_pads
			(clearance 0)
		)
		(min_thickness 0.25)
		(keepout
			(tracks not_allowed)
			(vias allowed)
			(pads allowed)
			(copperpour not_allowed)
			(footprints allowed)
		)
		(placement
			(enabled no)
			(sheetname "")
		)
		(fill yes
			(thermal_gap 0.5)
			(thermal_bridge_width 0.5)
			(island_removal_mode 0)
		)
		(polygon
			(pts
				(arc
					(start 300.592998 -237.471458)
					(mid 300.607877 -237.507379)
					(end 300.643798 -237.522258)
				)
				(arc
					(start 302.043338 -237.522258)
					(mid 302.079259 -237.507379)
					(end 302.094138 -237.471458)
				)
				(arc
					(start 302.094138 -237.062518)
					(mid 302.079259 -237.026597)
					(end 302.043338 -237.011718)
				)
				(arc
					(start 300.643798 -237.011718)
					(mid 300.607877 -237.026597)
					(end 300.592998 -237.062518)
				)
			)
		)
	)
	(zone
		(layers "In1.Cu" "In2.Cu")
		(hatch none 0.5)
		(connect_pads
			(clearance 0)
		)
		(min_thickness 0.25)
		(keepout
			(tracks not_allowed)
			(vias allowed)
			(pads allowed)
			(copperpour not_allowed)
			(footprints allowed)
		)
		(placement
			(enabled no)
			(sheetname "")
		)
		(fill yes
			(thermal_gap 0.5)
			(thermal_bridge_width 0.5)
			(island_removal_mode 0)
		)
		(polygon
			(pts
				(arc
					(start 214.969598 -260.421374)
					(mid 214.984477 -260.457295)
					(end 215.020398 -260.472174)
				)
				(arc
					(start 216.419938 -260.472174)
					(mid 216.455859 -260.457295)
					(end 216.470738 -260.421374)
				)
				(arc
					(start 216.470738 -260.012434)
					(mid 216.455859 -259.976513)
					(end 216.419938 -259.961634)
				)
				(arc
					(start 215.020398 -259.961634)
					(mid 214.984477 -259.976513)
					(end 214.969598 -260.012434)
				)
			)
		)
	)
	(zone
		(layers "In1.Cu" "In2.Cu")
		(hatch none 0.5)
		(connect_pads
			(clearance 0)
		)
		(min_thickness 0.25)
		(keepout
			(tracks not_allowed)
			(vias allowed)
			(pads allowed)
			(copperpour not_allowed)
			(footprints allowed)
		)
		(placement
			(enabled no)
			(sheetname "")
		)
		(fill yes
			(thermal_gap 0.5)
			(thermal_bridge_width 0.5)
			(island_removal_mode 0)
		)
		(polygon
			(pts
				(arc
					(start 262.873998 -268.071346)
					(mid 262.888877 -268.107267)
					(end 262.924798 -268.122146)
				)
				(arc
					(start 264.324338 -268.122146)
					(mid 264.360259 -268.107267)
					(end 264.375138 -268.071346)
				)
				(arc
					(start 264.375138 -267.662406)
					(mid 264.360259 -267.626485)
					(end 264.324338 -267.611606)
				)
				(arc
					(start 262.924798 -267.611606)
					(mid 262.888877 -267.626485)
					(end 262.873998 -267.662406)
				)
			)
		)
	)
	(zone
		(layers "In1.Cu" "In2.Cu")
		(hatch none 0.5)
		(connect_pads
			(clearance 0)
		)
		(min_thickness 0.25)
		(keepout
			(tracks not_allowed)
			(vias allowed)
			(pads allowed)
			(copperpour not_allowed)
			(footprints allowed)
		)
		(placement
			(enabled no)
			(sheetname "")
		)
		(fill yes
			(thermal_gap 0.5)
			(thermal_bridge_width 0.5)
			(island_removal_mode 0)
		)
		(polygon
			(pts
				(arc
					(start 425.190666 -313.971432)
					(mid 425.205545 -314.007353)
					(end 425.241466 -314.022232)
				)
				(arc
					(start 426.641006 -314.022232)
					(mid 426.676927 -314.007353)
					(end 426.691806 -313.971432)
				)
				(arc
					(start 426.691806 -313.562492)
					(mid 426.676927 -313.526571)
					(end 426.641006 -313.511692)
				)
				(arc
					(start 425.241466 -313.511692)
					(mid 425.205545 -313.526571)
					(end 425.190666 -313.562492)
				)
			)
		)
	)
	(zone
		(layers "In1.Cu" "In2.Cu")
		(hatch none 0.5)
		(connect_pads
			(clearance 0)
		)
		(min_thickness 0.25)
		(keepout
			(tracks not_allowed)
			(vias allowed)
			(pads allowed)
			(copperpour not_allowed)
			(footprints allowed)
		)
		(placement
			(enabled no)
			(sheetname "")
		)
		(fill yes
			(thermal_gap 0.5)
			(thermal_bridge_width 0.5)
			(island_removal_mode 0)
		)
		(polygon
			(pts
				(arc
					(start 64.296798 -236.62132)
					(mid 64.311677 -236.657241)
					(end 64.347598 -236.67212)
				)
				(arc
					(start 65.747138 -236.67212)
					(mid 65.783059 -236.657241)
					(end 65.797938 -236.62132)
				)
				(arc
					(start 65.797938 -236.21238)
					(mid 65.783059 -236.176459)
					(end 65.747138 -236.16158)
				)
				(arc
					(start 64.347598 -236.16158)
					(mid 64.311677 -236.176459)
					(end 64.296798 -236.21238)
				)
			)
		)
	)
	(zone
		(layers "In1.Cu" "In2.Cu")
		(hatch none 0.5)
		(connect_pads
			(clearance 0)
		)
		(min_thickness 0.25)
		(keepout
			(tracks not_allowed)
			(vias allowed)
			(pads allowed)
			(copperpour not_allowed)
			(footprints allowed)
		)
		(placement
			(enabled no)
			(sheetname "")
		)
		(fill yes
			(thermal_gap 0.5)
			(thermal_bridge_width 0.5)
			(island_removal_mode 0)
		)
		(polygon
			(pts
				(arc
					(start 203.32573 -211.971382)
					(mid 203.340609 -212.007303)
					(end 203.37653 -212.022182)
				)
				(arc
					(start 204.77607 -212.022182)
					(mid 204.811991 -212.007303)
					(end 204.82687 -211.971382)
				)
				(arc
					(start 204.82687 -211.562442)
					(mid 204.811991 -211.526521)
					(end 204.77607 -211.511642)
				)
				(arc
					(start 203.37653 -211.511642)
					(mid 203.340609 -211.526521)
					(end 203.32573 -211.562442)
				)
			)
		)
	)
	(zone
		(layers "In1.Cu" "In2.Cu")
		(hatch none 0.5)
		(connect_pads
			(clearance 0)
		)
		(min_thickness 0.25)
		(keepout
			(tracks not_allowed)
			(vias allowed)
			(pads allowed)
			(copperpour not_allowed)
			(footprints allowed)
		)
		(placement
			(enabled no)
			(sheetname "")
		)
		(fill yes
			(thermal_gap 0.5)
			(thermal_bridge_width 0.5)
			(island_removal_mode 0)
		)
		(polygon
			(pts
				(arc
					(start 162.162998 -250.221496)
					(mid 162.177877 -250.257417)
					(end 162.213798 -250.272296)
				)
				(arc
					(start 163.613338 -250.272296)
					(mid 163.649259 -250.257417)
					(end 163.664138 -250.221496)
				)
				(arc
					(start 163.664138 -249.812556)
					(mid 163.649259 -249.776635)
					(end 163.613338 -249.761756)
				)
				(arc
					(start 162.213798 -249.761756)
					(mid 162.177877 -249.776635)
					(end 162.162998 -249.812556)
				)
			)
		)
	)
	(zone
		(layers "In1.Cu" "In2.Cu")
		(hatch none 0.5)
		(connect_pads
			(clearance 0)
		)
		(min_thickness 0.25)
		(keepout
			(tracks not_allowed)
			(vias allowed)
			(pads allowed)
			(copperpour not_allowed)
			(footprints allowed)
		)
		(placement
			(enabled no)
			(sheetname "")
		)
		(fill yes
			(thermal_gap 0.5)
			(thermal_bridge_width 0.5)
			(island_removal_mode 0)
		)
		(polygon
			(pts
				(arc
					(start 165.60673 -200.921366)
					(mid 165.621609 -200.957287)
					(end 165.65753 -200.972166)
				)
				(arc
					(start 167.05707 -200.972166)
					(mid 167.092991 -200.957287)
					(end 167.10787 -200.921366)
				)
				(arc
					(start 167.10787 -200.512426)
					(mid 167.092991 -200.476505)
					(end 167.05707 -200.461626)
				)
				(arc
					(start 165.65753 -200.461626)
					(mid 165.621609 -200.476505)
					(end 165.60673 -200.512426)
				)
			)
		)
	)
	(zone
		(layers "In1.Cu" "In2.Cu")
		(hatch none 0.5)
		(connect_pads
			(clearance 0)
		)
		(min_thickness 0.25)
		(keepout
			(tracks not_allowed)
			(vias allowed)
			(pads allowed)
			(copperpour not_allowed)
			(footprints allowed)
		)
		(placement
			(enabled no)
			(sheetname "")
		)
		(fill yes
			(thermal_gap 0.5)
			(thermal_bridge_width 0.5)
			(island_removal_mode 0)
		)
		(polygon
			(pts
				(arc
					(start 203.32573 -238.321342)
					(mid 203.340609 -238.357263)
					(end 203.37653 -238.372142)
				)
				(arc
					(start 204.77607 -238.372142)
					(mid 204.811991 -238.357263)
					(end 204.82687 -238.321342)
				)
				(arc
					(start 204.82687 -237.912402)
					(mid 204.811991 -237.876481)
					(end 204.77607 -237.861602)
				)
				(arc
					(start 203.37653 -237.861602)
					(mid 203.340609 -237.876481)
					(end 203.32573 -237.912402)
				)
			)
		)
	)
	(zone
		(layers "In1.Cu" "In2.Cu")
		(hatch none 0.5)
		(connect_pads
			(clearance 0)
		)
		(min_thickness 0.25)
		(keepout
			(tracks not_allowed)
			(vias allowed)
			(pads allowed)
			(copperpour not_allowed)
			(footprints allowed)
		)
		(placement
			(enabled no)
			(sheetname "")
		)
		(fill yes
			(thermal_gap 0.5)
			(thermal_bridge_width 0.5)
			(island_removal_mode 0)
		)
		(polygon
			(pts
				(arc
					(start 7.39013 -221.321376)
					(mid 7.405009 -221.357297)
					(end 7.44093 -221.372176)
				)
				(arc
					(start 8.84047 -221.372176)
					(mid 8.876391 -221.357297)
					(end 8.89127 -221.321376)
				)
				(arc
					(start 8.89127 -220.912436)
					(mid 8.876391 -220.876515)
					(end 8.84047 -220.861636)
				)
				(arc
					(start 7.44093 -220.861636)
					(mid 7.405009 -220.876515)
					(end 7.39013 -220.912436)
				)
			)
		)
	)
	(zone
		(layers "In1.Cu" "In2.Cu")
		(hatch none 0.5)
		(connect_pads
			(clearance 0)
		)
		(min_thickness 0.25)
		(keepout
			(tracks not_allowed)
			(vias allowed)
			(pads allowed)
			(copperpour not_allowed)
			(footprints allowed)
		)
		(placement
			(enabled no)
			(sheetname "")
		)
		(fill yes
			(thermal_gap 0.5)
			(thermal_bridge_width 0.5)
			(island_removal_mode 0)
		)
		(polygon
			(pts
				(arc
					(start 165.60673 -303.7713)
					(mid 165.621609 -303.807221)
					(end 165.65753 -303.8221)
				)
				(arc
					(start 167.05707 -303.8221)
					(mid 167.092991 -303.807221)
					(end 167.10787 -303.7713)
				)
				(arc
					(start 167.10787 -303.36236)
					(mid 167.092991 -303.326439)
					(end 167.05707 -303.31156)
				)
				(arc
					(start 165.65753 -303.31156)
					(mid 165.621609 -303.326439)
					(end 165.60673 -303.36236)
				)
			)
		)
	)
	(zone
		(layers "In1.Cu" "In2.Cu")
		(hatch none 0.5)
		(connect_pads
			(clearance 0)
		)
		(min_thickness 0.25)
		(keepout
			(tracks not_allowed)
			(vias allowed)
			(pads allowed)
			(copperpour not_allowed)
			(footprints allowed)
		)
		(placement
			(enabled no)
			(sheetname "")
		)
		(fill yes
			(thermal_gap 0.5)
			(thermal_bridge_width 0.5)
			(island_removal_mode 0)
		)
		(polygon
			(pts
				(arc
					(start 184.794398 -260.421374)
					(mid 184.809277 -260.457295)
					(end 184.845198 -260.472174)
				)
				(arc
					(start 186.244738 -260.472174)
					(mid 186.280659 -260.457295)
					(end 186.295538 -260.421374)
				)
				(arc
					(start 186.295538 -260.012434)
					(mid 186.280659 -259.976513)
					(end 186.244738 -259.961634)
				)
				(arc
					(start 184.845198 -259.961634)
					(mid 184.809277 -259.976513)
					(end 184.794398 -260.012434)
				)
			)
		)
	)
	(zone
		(layers "In1.Cu" "In2.Cu")
		(hatch none 0.5)
		(connect_pads
			(clearance 0)
		)
		(min_thickness 0.25)
		(keepout
			(tracks not_allowed)
			(vias allowed)
			(pads allowed)
			(copperpour not_allowed)
			(footprints allowed)
		)
		(placement
			(enabled no)
			(sheetname "")
		)
		(fill yes
			(thermal_gap 0.5)
			(thermal_bridge_width 0.5)
			(island_removal_mode 0)
		)
		(polygon
			(pts
				(arc
					(start 297.149266 -283.371544)
					(mid 297.164145 -283.407465)
					(end 297.200066 -283.422344)
				)
				(arc
					(start 298.599606 -283.422344)
					(mid 298.635527 -283.407465)
					(end 298.650406 -283.371544)
				)
				(arc
					(start 298.650406 -282.962604)
					(mid 298.635527 -282.926683)
					(end 298.599606 -282.911804)
				)
				(arc
					(start 297.200066 -282.911804)
					(mid 297.164145 -282.926683)
					(end 297.149266 -282.962604)
				)
			)
		)
	)
	(zone
		(layers "In1.Cu" "In2.Cu")
		(hatch none 0.5)
		(connect_pads
			(clearance 0)
		)
		(min_thickness 0.25)
		(keepout
			(tracks not_allowed)
			(vias allowed)
			(pads allowed)
			(copperpour not_allowed)
			(footprints allowed)
		)
		(placement
			(enabled no)
			(sheetname "")
		)
		(fill yes
			(thermal_gap 0.5)
			(thermal_bridge_width 0.5)
			(island_removal_mode 0)
		)
		(polygon
			(pts
				(arc
					(start 277.961598 -234.071414)
					(mid 277.976477 -234.107335)
					(end 278.012398 -234.122214)
				)
				(arc
					(start 279.411938 -234.122214)
					(mid 279.447859 -234.107335)
					(end 279.462738 -234.071414)
				)
				(arc
					(start 279.462738 -233.662474)
					(mid 279.447859 -233.626553)
					(end 279.411938 -233.611674)
				)
				(arc
					(start 278.012398 -233.611674)
					(mid 277.976477 -233.626553)
					(end 277.961598 -233.662474)
				)
			)
		)
	)
	(zone
		(layers "In1.Cu" "In2.Cu")
		(hatch none 0.5)
		(connect_pads
			(clearance 0)
		)
		(min_thickness 0.25)
		(keepout
			(tracks not_allowed)
			(vias allowed)
			(pads allowed)
			(copperpour not_allowed)
			(footprints allowed)
		)
		(placement
			(enabled no)
			(sheetname "")
		)
		(fill yes
			(thermal_gap 0.5)
			(thermal_bridge_width 0.5)
			(island_removal_mode 0)
		)
		(polygon
			(pts
				(arc
					(start 203.32573 -213.671404)
					(mid 203.340609 -213.707325)
					(end 203.37653 -213.722204)
				)
				(arc
					(start 204.77607 -213.722204)
					(mid 204.811991 -213.707325)
					(end 204.82687 -213.671404)
				)
				(arc
					(start 204.82687 -213.262464)
					(mid 204.811991 -213.226543)
					(end 204.77607 -213.211664)
				)
				(arc
					(start 203.37653 -213.211664)
					(mid 203.340609 -213.226543)
					(end 203.32573 -213.262464)
				)
			)
		)
	)
	(zone
		(layers "In1.Cu" "In2.Cu")
		(hatch none 0.5)
		(connect_pads
			(clearance 0)
		)
		(min_thickness 0.25)
		(keepout
			(tracks not_allowed)
			(vias allowed)
			(pads allowed)
			(copperpour not_allowed)
			(footprints allowed)
		)
		(placement
			(enabled no)
			(sheetname "")
		)
		(fill yes
			(thermal_gap 0.5)
			(thermal_bridge_width 0.5)
			(island_removal_mode 0)
		)
		(polygon
			(pts
				(arc
					(start 451.265798 -240.021364)
					(mid 451.280677 -240.057285)
					(end 451.316598 -240.072164)
				)
				(arc
					(start 452.716138 -240.072164)
					(mid 452.752059 -240.057285)
					(end 452.766938 -240.021364)
				)
				(arc
					(start 452.766938 -239.612424)
					(mid 452.752059 -239.576503)
					(end 452.716138 -239.561624)
				)
				(arc
					(start 451.316598 -239.561624)
					(mid 451.280677 -239.576503)
					(end 451.265798 -239.612424)
				)
			)
		)
	)
	(zone
		(layers "In1.Cu" "In2.Cu")
		(hatch none 0.5)
		(connect_pads
			(clearance 0)
		)
		(min_thickness 0.25)
		(keepout
			(tracks not_allowed)
			(vias allowed)
			(pads allowed)
			(copperpour not_allowed)
			(footprints allowed)
		)
		(placement
			(enabled no)
			(sheetname "")
		)
		(fill yes
			(thermal_gap 0.5)
			(thermal_bridge_width 0.5)
			(island_removal_mode 0)
		)
		(polygon
			(pts
				(arc
					(start 447.822066 -262.121396)
					(mid 447.836945 -262.157317)
					(end 447.872866 -262.172196)
				)
				(arc
					(start 449.272406 -262.172196)
					(mid 449.308327 -262.157317)
					(end 449.323206 -262.121396)
				)
				(arc
					(start 449.323206 -261.712456)
					(mid 449.308327 -261.676535)
					(end 449.272406 -261.661656)
				)
				(arc
					(start 447.872866 -261.661656)
					(mid 447.836945 -261.676535)
					(end 447.822066 -261.712456)
				)
			)
		)
	)
	(zone
		(layers "In1.Cu" "In2.Cu")
		(hatch none 0.5)
		(connect_pads
			(clearance 0)
		)
		(min_thickness 0.25)
		(keepout
			(tracks not_allowed)
			(vias allowed)
			(pads allowed)
			(copperpour not_allowed)
			(footprints allowed)
		)
		(placement
			(enabled no)
			(sheetname "")
		)
		(fill yes
			(thermal_gap 0.5)
			(thermal_bridge_width 0.5)
			(island_removal_mode 0)
		)
		(polygon
			(pts
				(arc
					(start 293.049198 -196.671438)
					(mid 293.064077 -196.707359)
					(end 293.099998 -196.722238)
				)
				(arc
					(start 294.499538 -196.722238)
					(mid 294.535459 -196.707359)
					(end 294.550338 -196.671438)
				)
				(arc
					(start 294.550338 -196.262498)
					(mid 294.535459 -196.226577)
					(end 294.499538 -196.211698)
				)
				(arc
					(start 293.099998 -196.211698)
					(mid 293.064077 -196.226577)
					(end 293.049198 -196.262498)
				)
			)
		)
	)
	(zone
		(layers "In1.Cu" "In2.Cu")
		(hatch none 0.5)
		(connect_pads
			(clearance 0)
		)
		(min_thickness 0.25)
		(keepout
			(tracks not_allowed)
			(vias allowed)
			(pads allowed)
			(copperpour not_allowed)
			(footprints allowed)
		)
		(placement
			(enabled no)
			(sheetname "")
		)
		(fill yes
			(thermal_gap 0.5)
			(thermal_bridge_width 0.5)
			(island_removal_mode 0)
		)
		(polygon
			(pts
				(arc
					(start 34.121598 -270.621506)
					(mid 34.136477 -270.657427)
					(end 34.172398 -270.672306)
				)
				(arc
					(start 35.571938 -270.672306)
					(mid 35.607859 -270.657427)
					(end 35.622738 -270.621506)
				)
				(arc
					(start 35.622738 -270.212566)
					(mid 35.607859 -270.176645)
					(end 35.571938 -270.161766)
				)
				(arc
					(start 34.172398 -270.161766)
					(mid 34.136477 -270.176645)
					(end 34.121598 -270.212566)
				)
			)
		)
	)
	(zone
		(layers "In1.Cu" "In2.Cu")
		(hatch none 0.5)
		(connect_pads
			(clearance 0)
		)
		(min_thickness 0.25)
		(keepout
			(tracks not_allowed)
			(vias allowed)
			(pads allowed)
			(copperpour not_allowed)
			(footprints allowed)
		)
		(placement
			(enabled no)
			(sheetname "")
		)
		(fill yes
			(thermal_gap 0.5)
			(thermal_bridge_width 0.5)
			(island_removal_mode 0)
		)
		(polygon
			(pts
				(arc
					(start 458.809598 -251.07138)
					(mid 458.824477 -251.107301)
					(end 458.860398 -251.12218)
				)
				(arc
					(start 460.259938 -251.12218)
					(mid 460.295859 -251.107301)
					(end 460.310738 -251.07138)
				)
				(arc
					(start 460.310738 -250.66244)
					(mid 460.295859 -250.626519)
					(end 460.259938 -250.61164)
				)
				(arc
					(start 458.860398 -250.61164)
					(mid 458.824477 -250.626519)
					(end 458.809598 -250.66244)
				)
			)
		)
	)
	(zone
		(layers "In1.Cu" "In2.Cu")
		(hatch none 0.5)
		(connect_pads
			(clearance 0)
		)
		(min_thickness 0.25)
		(keepout
			(tracks not_allowed)
			(vias allowed)
			(pads allowed)
			(copperpour not_allowed)
			(footprints allowed)
		)
		(placement
			(enabled no)
			(sheetname "")
		)
		(fill yes
			(thermal_gap 0.5)
			(thermal_bridge_width 0.5)
			(island_removal_mode 0)
		)
		(polygon
			(pts
				(arc
					(start 458.809598 -237.471458)
					(mid 458.824477 -237.507379)
					(end 458.860398 -237.522258)
				)
				(arc
					(start 460.259938 -237.522258)
					(mid 460.295859 -237.507379)
					(end 460.310738 -237.471458)
				)
				(arc
					(start 460.310738 -237.062518)
					(mid 460.295859 -237.026597)
					(end 460.259938 -237.011718)
				)
				(arc
					(start 458.860398 -237.011718)
					(mid 458.824477 -237.026597)
					(end 458.809598 -237.062518)
				)
			)
		)
	)
	(zone
		(layers "In1.Cu" "In2.Cu")
		(hatch none 0.5)
		(connect_pads
			(clearance 0)
		)
		(min_thickness 0.25)
		(keepout
			(tracks not_allowed)
			(vias allowed)
			(pads allowed)
			(copperpour not_allowed)
			(footprints allowed)
		)
		(placement
			(enabled no)
			(sheetname "")
		)
		(fill yes
			(thermal_gap 0.5)
			(thermal_bridge_width 0.5)
			(island_removal_mode 0)
		)
		(polygon
			(pts
				(arc
					(start 188.23813 -219.621354)
					(mid 188.253009 -219.657275)
					(end 188.28893 -219.672154)
				)
				(arc
					(start 189.68847 -219.672154)
					(mid 189.724391 -219.657275)
					(end 189.73927 -219.621354)
				)
				(arc
					(start 189.73927 -219.212414)
					(mid 189.724391 -219.176493)
					(end 189.68847 -219.161614)
				)
				(arc
					(start 188.28893 -219.161614)
					(mid 188.253009 -219.176493)
					(end 188.23813 -219.212414)
				)
			)
		)
	)
	(zone
		(layers "In1.Cu" "In2.Cu")
		(hatch none 0.5)
		(connect_pads
			(clearance 0)
		)
		(min_thickness 0.25)
		(keepout
			(tracks not_allowed)
			(vias allowed)
			(pads allowed)
			(copperpour not_allowed)
			(footprints allowed)
		)
		(placement
			(enabled no)
			(sheetname "")
		)
		(fill yes
			(thermal_gap 0.5)
			(thermal_bridge_width 0.5)
			(island_removal_mode 0)
		)
		(polygon
			(pts
				(arc
					(start 289.605466 -236.62132)
					(mid 289.620345 -236.657241)
					(end 289.656266 -236.67212)
				)
				(arc
					(start 291.055806 -236.67212)
					(mid 291.091727 -236.657241)
					(end 291.106606 -236.62132)
				)
				(arc
					(start 291.106606 -236.21238)
					(mid 291.091727 -236.176459)
					(end 291.055806 -236.16158)
				)
				(arc
					(start 289.656266 -236.16158)
					(mid 289.620345 -236.176459)
					(end 289.605466 -236.21238)
				)
			)
		)
	)
	(zone
		(layers "In1.Cu" "In2.Cu")
		(hatch none 0.5)
		(connect_pads
			(clearance 0)
		)
		(min_thickness 0.25)
		(keepout
			(tracks not_allowed)
			(vias allowed)
			(pads allowed)
			(copperpour not_allowed)
			(footprints allowed)
		)
		(placement
			(enabled no)
			(sheetname "")
		)
		(fill yes
			(thermal_gap 0.5)
			(thermal_bridge_width 0.5)
			(island_removal_mode 0)
		)
		(polygon
			(pts
				(arc
					(start 173.15053 -200.921366)
					(mid 173.165409 -200.957287)
					(end 173.20133 -200.972166)
				)
				(arc
					(start 174.60087 -200.972166)
					(mid 174.636791 -200.957287)
					(end 174.65167 -200.921366)
				)
				(arc
					(start 174.65167 -200.512426)
					(mid 174.636791 -200.476505)
					(end 174.60087 -200.461626)
				)
				(arc
					(start 173.20133 -200.461626)
					(mid 173.165409 -200.476505)
					(end 173.15053 -200.512426)
				)
			)
		)
	)
	(zone
		(layers "In1.Cu" "In2.Cu")
		(hatch none 0.5)
		(connect_pads
			(clearance 0)
		)
		(min_thickness 0.25)
		(keepout
			(tracks not_allowed)
			(vias allowed)
			(pads allowed)
			(copperpour not_allowed)
			(footprints allowed)
		)
		(placement
			(enabled no)
			(sheetname "")
		)
		(fill yes
			(thermal_gap 0.5)
			(thermal_bridge_width 0.5)
			(island_removal_mode 0)
		)
		(polygon
			(pts
				(arc
					(start 188.23813 -251.07138)
					(mid 188.253009 -251.107301)
					(end 188.28893 -251.12218)
				)
				(arc
					(start 189.68847 -251.12218)
					(mid 189.724391 -251.107301)
					(end 189.73927 -251.07138)
				)
				(arc
					(start 189.73927 -250.66244)
					(mid 189.724391 -250.626519)
					(end 189.68847 -250.61164)
				)
				(arc
					(start 188.28893 -250.61164)
					(mid 188.253009 -250.626519)
					(end 188.23813 -250.66244)
				)
			)
		)
	)
	(zone
		(layers "In1.Cu" "In2.Cu")
		(hatch none 0.5)
		(connect_pads
			(clearance 0)
		)
		(min_thickness 0.25)
		(keepout
			(tracks not_allowed)
			(vias allowed)
			(pads allowed)
			(copperpour not_allowed)
			(footprints allowed)
		)
		(placement
			(enabled no)
			(sheetname "")
		)
		(fill yes
			(thermal_gap 0.5)
			(thermal_bridge_width 0.5)
			(island_removal_mode 0)
		)
		(polygon
			(pts
				(arc
					(start 158.06293 -207.721454)
					(mid 158.077809 -207.757375)
					(end 158.11373 -207.772254)
				)
				(arc
					(start 159.51327 -207.772254)
					(mid 159.549191 -207.757375)
					(end 159.56407 -207.721454)
				)
				(arc
					(start 159.56407 -207.312514)
					(mid 159.549191 -207.276593)
					(end 159.51327 -207.261714)
				)
				(arc
					(start 158.11373 -207.261714)
					(mid 158.077809 -207.276593)
					(end 158.06293 -207.312514)
				)
			)
		)
	)
	(zone
		(layers "In1.Cu" "In2.Cu")
		(hatch none 0.5)
		(connect_pads
			(clearance 0)
		)
		(min_thickness 0.25)
		(keepout
			(tracks not_allowed)
			(vias allowed)
			(pads allowed)
			(copperpour not_allowed)
			(footprints allowed)
		)
		(placement
			(enabled no)
			(sheetname "")
		)
		(fill yes
			(thermal_gap 0.5)
			(thermal_bridge_width 0.5)
			(island_removal_mode 0)
		)
		(polygon
			(pts
				(arc
					(start 34.121598 -289.321494)
					(mid 34.136477 -289.357415)
					(end 34.172398 -289.372294)
				)
				(arc
					(start 35.571938 -289.372294)
					(mid 35.607859 -289.357415)
					(end 35.622738 -289.321494)
				)
				(arc
					(start 35.622738 -288.912554)
					(mid 35.607859 -288.876633)
					(end 35.571938 -288.861754)
				)
				(arc
					(start 34.172398 -288.861754)
					(mid 34.136477 -288.876633)
					(end 34.121598 -288.912554)
				)
			)
		)
	)
	(zone
		(layers "In1.Cu" "In2.Cu")
		(hatch none 0.5)
		(connect_pads
			(clearance 0)
		)
		(min_thickness 0.25)
		(keepout
			(tracks not_allowed)
			(vias allowed)
			(pads allowed)
			(copperpour not_allowed)
			(footprints allowed)
		)
		(placement
			(enabled no)
			(sheetname "")
		)
		(fill yes
			(thermal_gap 0.5)
			(thermal_bridge_width 0.5)
			(island_removal_mode 0)
		)
		(polygon
			(pts
				(arc
					(start 458.809598 -234.071414)
					(mid 458.824477 -234.107335)
					(end 458.860398 -234.122214)
				)
				(arc
					(start 460.259938 -234.122214)
					(mid 460.295859 -234.107335)
					(end 460.310738 -234.071414)
				)
				(arc
					(start 460.310738 -233.662474)
					(mid 460.295859 -233.626553)
					(end 460.259938 -233.611674)
				)
				(arc
					(start 458.860398 -233.611674)
					(mid 458.824477 -233.626553)
					(end 458.809598 -233.662474)
				)
			)
		)
	)
	(zone
		(layers "In1.Cu" "In2.Cu")
		(hatch none 0.5)
		(connect_pads
			(clearance 0)
		)
		(min_thickness 0.25)
		(keepout
			(tracks not_allowed)
			(vias allowed)
			(pads allowed)
			(copperpour not_allowed)
			(footprints allowed)
		)
		(placement
			(enabled no)
			(sheetname "")
		)
		(fill yes
			(thermal_gap 0.5)
			(thermal_bridge_width 0.5)
			(island_removal_mode 0)
		)
		(polygon
			(pts
				(arc
					(start 274.517866 -236.62132)
					(mid 274.532745 -236.657241)
					(end 274.568666 -236.67212)
				)
				(arc
					(start 275.968206 -236.67212)
					(mid 276.004127 -236.657241)
					(end 276.019006 -236.62132)
				)
				(arc
					(start 276.019006 -236.21238)
					(mid 276.004127 -236.176459)
					(end 275.968206 -236.16158)
				)
				(arc
					(start 274.568666 -236.16158)
					(mid 274.532745 -236.176459)
					(end 274.517866 -236.21238)
				)
			)
		)
	)
	(zone
		(layers "In1.Cu" "In2.Cu")
		(hatch none 0.5)
		(connect_pads
			(clearance 0)
		)
		(min_thickness 0.25)
		(keepout
			(tracks not_allowed)
			(vias allowed)
			(pads allowed)
			(copperpour not_allowed)
			(footprints allowed)
		)
		(placement
			(enabled no)
			(sheetname "")
		)
		(fill yes
			(thermal_gap 0.5)
			(thermal_bridge_width 0.5)
			(island_removal_mode 0)
		)
		(polygon
			(pts
				(arc
					(start 56.752998 -291.021516)
					(mid 56.767877 -291.057437)
					(end 56.803798 -291.072316)
				)
				(arc
					(start 58.203338 -291.072316)
					(mid 58.239259 -291.057437)
					(end 58.254138 -291.021516)
				)
				(arc
					(start 58.254138 -290.612576)
					(mid 58.239259 -290.576655)
					(end 58.203338 -290.561776)
				)
				(arc
					(start 56.803798 -290.561776)
					(mid 56.767877 -290.576655)
					(end 56.752998 -290.612576)
				)
			)
		)
	)
	(zone
		(layers "In1.Cu" "In2.Cu")
		(hatch none 0.5)
		(connect_pads
			(clearance 0)
		)
		(min_thickness 0.25)
		(keepout
			(tracks not_allowed)
			(vias allowed)
			(pads allowed)
			(copperpour not_allowed)
			(footprints allowed)
		)
		(placement
			(enabled no)
			(sheetname "")
		)
		(fill yes
			(thermal_gap 0.5)
			(thermal_bridge_width 0.5)
			(island_removal_mode 0)
		)
		(polygon
			(pts
				(arc
					(start 30.02153 -312.27141)
					(mid 30.036409 -312.307331)
					(end 30.07233 -312.32221)
				)
				(arc
					(start 31.47187 -312.32221)
					(mid 31.507791 -312.307331)
					(end 31.52267 -312.27141)
				)
				(arc
					(start 31.52267 -311.86247)
					(mid 31.507791 -311.826549)
					(end 31.47187 -311.81167)
				)
				(arc
					(start 30.07233 -311.81167)
					(mid 30.036409 -311.826549)
					(end 30.02153 -311.86247)
				)
			)
		)
	)
	(zone
		(layers "In1.Cu" "In2.Cu")
		(hatch none 0.5)
		(connect_pads
			(clearance 0)
		)
		(min_thickness 0.25)
		(keepout
			(tracks not_allowed)
			(vias allowed)
			(pads allowed)
			(copperpour not_allowed)
			(footprints allowed)
		)
		(placement
			(enabled no)
			(sheetname "")
		)
		(fill yes
			(thermal_gap 0.5)
			(thermal_bridge_width 0.5)
			(island_removal_mode 0)
		)
		(polygon
			(pts
				(arc
					(start 421.090598 -303.7713)
					(mid 421.105477 -303.807221)
					(end 421.141398 -303.8221)
				)
				(arc
					(start 422.540938 -303.8221)
					(mid 422.576859 -303.807221)
					(end 422.591738 -303.7713)
				)
				(arc
					(start 422.591738 -303.36236)
					(mid 422.576859 -303.326439)
					(end 422.540938 -303.31156)
				)
				(arc
					(start 421.141398 -303.31156)
					(mid 421.105477 -303.326439)
					(end 421.090598 -303.36236)
				)
			)
		)
	)
	(zone
		(layers "In1.Cu" "In2.Cu")
		(hatch none 0.5)
		(connect_pads
			(clearance 0)
		)
		(min_thickness 0.25)
		(keepout
			(tracks not_allowed)
			(vias allowed)
			(pads allowed)
			(copperpour not_allowed)
			(footprints allowed)
		)
		(placement
			(enabled no)
			(sheetname "")
		)
		(fill yes
			(thermal_gap 0.5)
			(thermal_bridge_width 0.5)
			(island_removal_mode 0)
		)
		(polygon
			(pts
				(arc
					(start 458.809598 -314.821316)
					(mid 458.824477 -314.857237)
					(end 458.860398 -314.872116)
				)
				(arc
					(start 460.259938 -314.872116)
					(mid 460.295859 -314.857237)
					(end 460.310738 -314.821316)
				)
				(arc
					(start 460.310738 -314.412376)
					(mid 460.295859 -314.376455)
					(end 460.259938 -314.361576)
				)
				(arc
					(start 458.860398 -314.361576)
					(mid 458.824477 -314.376455)
					(end 458.809598 -314.412376)
				)
			)
		)
	)
	(zone
		(layers "In1.Cu" "In2.Cu")
		(hatch none 0.5)
		(connect_pads
			(clearance 0)
		)
		(min_thickness 0.25)
		(keepout
			(tracks not_allowed)
			(vias allowed)
			(pads allowed)
			(copperpour not_allowed)
			(footprints allowed)
		)
		(placement
			(enabled no)
			(sheetname "")
		)
		(fill yes
			(thermal_gap 0.5)
			(thermal_bridge_width 0.5)
			(island_removal_mode 0)
		)
		(polygon
			(pts
				(arc
					(start 285.505398 -286.771334)
					(mid 285.520277 -286.807255)
					(end 285.556198 -286.822134)
				)
				(arc
					(start 286.955738 -286.822134)
					(mid 286.991659 -286.807255)
					(end 287.006538 -286.771334)
				)
				(arc
					(start 287.006538 -286.362394)
					(mid 286.991659 -286.326473)
					(end 286.955738 -286.311594)
				)
				(arc
					(start 285.556198 -286.311594)
					(mid 285.520277 -286.326473)
					(end 285.505398 -286.362394)
				)
			)
		)
	)
	(zone
		(layers "In1.Cu" "In2.Cu")
		(hatch none 0.5)
		(connect_pads
			(clearance 0)
		)
		(min_thickness 0.25)
		(keepout
			(tracks not_allowed)
			(vias allowed)
			(pads allowed)
			(copperpour not_allowed)
			(footprints allowed)
		)
		(placement
			(enabled no)
			(sheetname "")
		)
		(fill yes
			(thermal_gap 0.5)
			(thermal_bridge_width 0.5)
			(island_removal_mode 0)
		)
		(polygon
			(pts
				(arc
					(start 308.136798 -200.921366)
					(mid 308.151677 -200.957287)
					(end 308.187598 -200.972166)
				)
				(arc
					(start 309.587138 -200.972166)
					(mid 309.623059 -200.957287)
					(end 309.637938 -200.921366)
				)
				(arc
					(start 309.637938 -200.512426)
					(mid 309.623059 -200.476505)
					(end 309.587138 -200.461626)
				)
				(arc
					(start 308.187598 -200.461626)
					(mid 308.151677 -200.476505)
					(end 308.136798 -200.512426)
				)
			)
		)
	)
	(zone
		(layers "In1.Cu" "In2.Cu")
		(hatch none 0.5)
		(connect_pads
			(clearance 0)
		)
		(min_thickness 0.25)
		(keepout
			(tracks not_allowed)
			(vias allowed)
			(pads allowed)
			(copperpour not_allowed)
			(footprints allowed)
		)
		(placement
			(enabled no)
			(sheetname "")
		)
		(fill yes
			(thermal_gap 0.5)
			(thermal_bridge_width 0.5)
			(island_removal_mode 0)
		)
		(polygon
			(pts
				(arc
					(start 428.634398 -316.521338)
					(mid 428.649277 -316.557259)
					(end 428.685198 -316.572138)
				)
				(arc
					(start 430.084738 -316.572138)
					(mid 430.120659 -316.557259)
					(end 430.135538 -316.521338)
				)
				(arc
					(start 430.135538 -316.112398)
					(mid 430.120659 -316.076477)
					(end 430.084738 -316.061598)
				)
				(arc
					(start 428.685198 -316.061598)
					(mid 428.649277 -316.076477)
					(end 428.634398 -316.112398)
				)
			)
		)
	)
	(zone
		(layers "In1.Cu" "In2.Cu")
		(hatch none 0.5)
		(connect_pads
			(clearance 0)
		)
		(min_thickness 0.25)
		(keepout
			(tracks not_allowed)
			(vias allowed)
			(pads allowed)
			(copperpour not_allowed)
			(footprints allowed)
		)
		(placement
			(enabled no)
			(sheetname "")
		)
		(fill yes
			(thermal_gap 0.5)
			(thermal_bridge_width 0.5)
			(island_removal_mode 0)
		)
		(polygon
			(pts
				(arc
					(start 158.06293 -271.47139)
					(mid 158.077809 -271.507311)
					(end 158.11373 -271.52219)
				)
				(arc
					(start 159.51327 -271.52219)
					(mid 159.549191 -271.507311)
					(end 159.56407 -271.47139)
				)
				(arc
					(start 159.56407 -271.06245)
					(mid 159.549191 -271.026529)
					(end 159.51327 -271.01165)
				)
				(arc
					(start 158.11373 -271.01165)
					(mid 158.077809 -271.026529)
					(end 158.06293 -271.06245)
				)
			)
		)
	)
	(zone
		(layers "In1.Cu" "In2.Cu")
		(hatch none 0.5)
		(connect_pads
			(clearance 0)
		)
		(min_thickness 0.25)
		(keepout
			(tracks not_allowed)
			(vias allowed)
			(pads allowed)
			(copperpour not_allowed)
			(footprints allowed)
		)
		(placement
			(enabled no)
			(sheetname "")
		)
		(fill yes
			(thermal_gap 0.5)
			(thermal_bridge_width 0.5)
			(island_removal_mode 0)
		)
		(polygon
			(pts
				(arc
					(start 41.665398 -231.521508)
					(mid 41.680277 -231.557429)
					(end 41.716198 -231.572308)
				)
				(arc
					(start 43.115738 -231.572308)
					(mid 43.151659 -231.557429)
					(end 43.166538 -231.521508)
				)
				(arc
					(start 43.166538 -231.112568)
					(mid 43.151659 -231.076647)
					(end 43.115738 -231.061768)
				)
				(arc
					(start 41.716198 -231.061768)
					(mid 41.680277 -231.076647)
					(end 41.665398 -231.112568)
				)
			)
		)
	)
	(zone
		(layers "In1.Cu" "In2.Cu")
		(hatch none 0.5)
		(connect_pads
			(clearance 0)
		)
		(min_thickness 0.25)
		(keepout
			(tracks not_allowed)
			(vias allowed)
			(pads allowed)
			(copperpour not_allowed)
			(footprints allowed)
		)
		(placement
			(enabled no)
			(sheetname "")
		)
		(fill yes
			(thermal_gap 0.5)
			(thermal_bridge_width 0.5)
			(island_removal_mode 0)
		)
		(polygon
			(pts
				(arc
					(start 177.250598 -246.821452)
					(mid 177.265477 -246.857373)
					(end 177.301398 -246.872252)
				)
				(arc
					(start 178.700938 -246.872252)
					(mid 178.736859 -246.857373)
					(end 178.751738 -246.821452)
				)
				(arc
					(start 178.751738 -246.412512)
					(mid 178.736859 -246.376591)
					(end 178.700938 -246.361712)
				)
				(arc
					(start 177.301398 -246.361712)
					(mid 177.265477 -246.376591)
					(end 177.250598 -246.412512)
				)
			)
		)
	)
	(zone
		(layers "In1.Cu" "In2.Cu")
		(hatch none 0.5)
		(connect_pads
			(clearance 0)
		)
		(min_thickness 0.25)
		(keepout
			(tracks not_allowed)
			(vias allowed)
			(pads allowed)
			(copperpour not_allowed)
			(footprints allowed)
		)
		(placement
			(enabled no)
			(sheetname "")
		)
		(fill yes
			(thermal_gap 0.5)
			(thermal_bridge_width 0.5)
			(island_removal_mode 0)
		)
		(polygon
			(pts
				(arc
					(start 192.338198 -274.02155)
					(mid 192.353077 -274.057471)
					(end 192.388998 -274.07235)
				)
				(arc
					(start 193.788538 -274.07235)
					(mid 193.824459 -274.057471)
					(end 193.839338 -274.02155)
				)
				(arc
					(start 193.839338 -273.61261)
					(mid 193.824459 -273.576689)
					(end 193.788538 -273.56181)
				)
				(arc
					(start 192.388998 -273.56181)
					(mid 192.353077 -273.576689)
					(end 192.338198 -273.61261)
				)
			)
		)
	)
	(zone
		(layers "In1.Cu" "In2.Cu")
		(hatch none 0.5)
		(connect_pads
			(clearance 0)
		)
		(min_thickness 0.25)
		(keepout
			(tracks not_allowed)
			(vias allowed)
			(pads allowed)
			(copperpour not_allowed)
			(footprints allowed)
		)
		(placement
			(enabled no)
			(sheetname "")
		)
		(fill yes
			(thermal_gap 0.5)
			(thermal_bridge_width 0.5)
			(island_removal_mode 0)
		)
		(polygon
			(pts
				(arc
					(start 304.693066 -274.02155)
					(mid 304.707945 -274.057471)
					(end 304.743866 -274.07235)
				)
				(arc
					(start 306.143406 -274.07235)
					(mid 306.179327 -274.057471)
					(end 306.194206 -274.02155)
				)
				(arc
					(start 306.194206 -273.61261)
					(mid 306.179327 -273.576689)
					(end 306.143406 -273.56181)
				)
				(arc
					(start 304.743866 -273.56181)
					(mid 304.707945 -273.576689)
					(end 304.693066 -273.61261)
				)
			)
		)
	)
	(zone
		(layers "In1.Cu" "In2.Cu")
		(hatch none 0.5)
		(connect_pads
			(clearance 0)
		)
		(min_thickness 0.25)
		(keepout
			(tracks not_allowed)
			(vias allowed)
			(pads allowed)
			(copperpour not_allowed)
			(footprints allowed)
		)
		(placement
			(enabled no)
			(sheetname "")
		)
		(fill yes
			(thermal_gap 0.5)
			(thermal_bridge_width 0.5)
			(island_removal_mode 0)
		)
		(polygon
			(pts
				(arc
					(start 308.136798 -219.621354)
					(mid 308.151677 -219.657275)
					(end 308.187598 -219.672154)
				)
				(arc
					(start 309.587138 -219.672154)
					(mid 309.623059 -219.657275)
					(end 309.637938 -219.621354)
				)
				(arc
					(start 309.637938 -219.212414)
					(mid 309.623059 -219.176493)
					(end 309.587138 -219.161614)
				)
				(arc
					(start 308.187598 -219.161614)
					(mid 308.151677 -219.176493)
					(end 308.136798 -219.212414)
				)
			)
		)
	)
	(zone
		(layers "In1.Cu" "In2.Cu")
		(hatch none 0.5)
		(connect_pads
			(clearance 0)
		)
		(min_thickness 0.25)
		(keepout
			(tracks not_allowed)
			(vias allowed)
			(pads allowed)
			(copperpour not_allowed)
			(footprints allowed)
		)
		(placement
			(enabled no)
			(sheetname "")
		)
		(fill yes
			(thermal_gap 0.5)
			(thermal_bridge_width 0.5)
			(island_removal_mode 0)
		)
		(polygon
			(pts
				(arc
					(start 188.23813 -221.321376)
					(mid 188.253009 -221.357297)
					(end 188.28893 -221.372176)
				)
				(arc
					(start 189.68847 -221.372176)
					(mid 189.724391 -221.357297)
					(end 189.73927 -221.321376)
				)
				(arc
					(start 189.73927 -220.912436)
					(mid 189.724391 -220.876515)
					(end 189.68847 -220.861636)
				)
				(arc
					(start 188.28893 -220.861636)
					(mid 188.253009 -220.876515)
					(end 188.23813 -220.912436)
				)
			)
		)
	)
	(zone
		(layers "In1.Cu" "In2.Cu")
		(hatch none 0.5)
		(connect_pads
			(clearance 0)
		)
		(min_thickness 0.25)
		(keepout
			(tracks not_allowed)
			(vias allowed)
			(pads allowed)
			(copperpour not_allowed)
			(footprints allowed)
		)
		(placement
			(enabled no)
			(sheetname "")
		)
		(fill yes
			(thermal_gap 0.5)
			(thermal_bridge_width 0.5)
			(island_removal_mode 0)
		)
		(polygon
			(pts
				(arc
					(start 199.881998 -292.721538)
					(mid 199.896877 -292.757459)
					(end 199.932798 -292.772338)
				)
				(arc
					(start 201.332338 -292.772338)
					(mid 201.368259 -292.757459)
					(end 201.383138 -292.721538)
				)
				(arc
					(start 201.383138 -292.312598)
					(mid 201.368259 -292.276677)
					(end 201.332338 -292.261798)
				)
				(arc
					(start 199.932798 -292.261798)
					(mid 199.896877 -292.276677)
					(end 199.881998 -292.312598)
				)
			)
		)
	)
	(zone
		(layers "In1.Cu" "In2.Cu")
		(hatch none 0.5)
		(connect_pads
			(clearance 0)
		)
		(min_thickness 0.25)
		(keepout
			(tracks not_allowed)
			(vias allowed)
			(pads allowed)
			(copperpour not_allowed)
			(footprints allowed)
		)
		(placement
			(enabled no)
			(sheetname "")
		)
		(fill yes
			(thermal_gap 0.5)
			(thermal_bridge_width 0.5)
			(island_removal_mode 0)
		)
		(polygon
			(pts
				(arc
					(start 455.365866 -272.321528)
					(mid 455.380745 -272.357449)
					(end 455.416666 -272.372328)
				)
				(arc
					(start 456.816206 -272.372328)
					(mid 456.852127 -272.357449)
					(end 456.867006 -272.321528)
				)
				(arc
					(start 456.867006 -271.912588)
					(mid 456.852127 -271.876667)
					(end 456.816206 -271.861788)
				)
				(arc
					(start 455.416666 -271.861788)
					(mid 455.380745 -271.876667)
					(end 455.365866 -271.912588)
				)
			)
		)
	)
	(zone
		(layers "In1.Cu" "In2.Cu")
		(hatch none 0.5)
		(connect_pads
			(clearance 0)
		)
		(min_thickness 0.25)
		(keepout
			(tracks not_allowed)
			(vias allowed)
			(pads allowed)
			(copperpour not_allowed)
			(footprints allowed)
		)
		(placement
			(enabled no)
			(sheetname "")
		)
		(fill yes
			(thermal_gap 0.5)
			(thermal_bridge_width 0.5)
			(island_removal_mode 0)
		)
		(polygon
			(pts
				(arc
					(start 203.32573 -305.471322)
					(mid 203.340609 -305.507243)
					(end 203.37653 -305.522122)
				)
				(arc
					(start 204.77607 -305.522122)
					(mid 204.811991 -305.507243)
					(end 204.82687 -305.471322)
				)
				(arc
					(start 204.82687 -305.062382)
					(mid 204.811991 -305.026461)
					(end 204.77607 -305.011582)
				)
				(arc
					(start 203.37653 -305.011582)
					(mid 203.340609 -305.026461)
					(end 203.32573 -305.062382)
				)
			)
		)
	)
	(zone
		(layers "In1.Cu" "In2.Cu")
		(hatch none 0.5)
		(connect_pads
			(clearance 0)
		)
		(min_thickness 0.25)
		(keepout
			(tracks not_allowed)
			(vias allowed)
			(pads allowed)
			(copperpour not_allowed)
			(footprints allowed)
		)
		(placement
			(enabled no)
			(sheetname "")
		)
		(fill yes
			(thermal_gap 0.5)
			(thermal_bridge_width 0.5)
			(island_removal_mode 0)
		)
		(polygon
			(pts
				(arc
					(start 199.881998 -289.321494)
					(mid 199.896877 -289.357415)
					(end 199.932798 -289.372294)
				)
				(arc
					(start 201.332338 -289.372294)
					(mid 201.368259 -289.357415)
					(end 201.383138 -289.321494)
				)
				(arc
					(start 201.383138 -288.912554)
					(mid 201.368259 -288.876633)
					(end 201.332338 -288.861754)
				)
				(arc
					(start 199.932798 -288.861754)
					(mid 199.896877 -288.876633)
					(end 199.881998 -288.912554)
				)
			)
		)
	)
	(zone
		(layers "In1.Cu" "In2.Cu")
		(hatch none 0.5)
		(connect_pads
			(clearance 0)
		)
		(min_thickness 0.25)
		(keepout
			(tracks not_allowed)
			(vias allowed)
			(pads allowed)
			(copperpour not_allowed)
			(footprints allowed)
		)
		(placement
			(enabled no)
			(sheetname "")
		)
		(fill yes
			(thermal_gap 0.5)
			(thermal_bridge_width 0.5)
			(island_removal_mode 0)
		)
		(polygon
			(pts
				(arc
					(start 7.39013 -262.971534)
					(mid 7.405009 -263.007455)
					(end 7.44093 -263.022334)
				)
				(arc
					(start 8.84047 -263.022334)
					(mid 8.876391 -263.007455)
					(end 8.89127 -262.971534)
				)
				(arc
					(start 8.89127 -262.562594)
					(mid 8.876391 -262.526673)
					(end 8.84047 -262.511794)
				)
				(arc
					(start 7.44093 -262.511794)
					(mid 7.405009 -262.526673)
					(end 7.39013 -262.562594)
				)
			)
		)
	)
	(zone
		(layers "In1.Cu" "In2.Cu")
		(hatch none 0.5)
		(connect_pads
			(clearance 0)
		)
		(min_thickness 0.25)
		(keepout
			(tracks not_allowed)
			(vias allowed)
			(pads allowed)
			(copperpour not_allowed)
			(footprints allowed)
		)
		(placement
			(enabled no)
			(sheetname "")
		)
		(fill yes
			(thermal_gap 0.5)
			(thermal_bridge_width 0.5)
			(island_removal_mode 0)
		)
		(polygon
			(pts
				(arc
					(start 173.15053 -286.771334)
					(mid 173.165409 -286.807255)
					(end 173.20133 -286.822134)
				)
				(arc
					(start 174.60087 -286.822134)
					(mid 174.636791 -286.807255)
					(end 174.65167 -286.771334)
				)
				(arc
					(start 174.65167 -286.362394)
					(mid 174.636791 -286.326473)
					(end 174.60087 -286.311594)
				)
				(arc
					(start 173.20133 -286.311594)
					(mid 173.165409 -286.326473)
					(end 173.15053 -286.362394)
				)
			)
		)
	)
	(zone
		(layers "In1.Cu" "In2.Cu")
		(hatch none 0.5)
		(connect_pads
			(clearance 0)
		)
		(min_thickness 0.25)
		(keepout
			(tracks not_allowed)
			(vias allowed)
			(pads allowed)
			(copperpour not_allowed)
			(footprints allowed)
		)
		(placement
			(enabled no)
			(sheetname "")
		)
		(fill yes
			(thermal_gap 0.5)
			(thermal_bridge_width 0.5)
			(island_removal_mode 0)
		)
		(polygon
			(pts
				(arc
					(start 421.090598 -244.271292)
					(mid 421.105477 -244.307213)
					(end 421.141398 -244.322092)
				)
				(arc
					(start 422.540938 -244.322092)
					(mid 422.576859 -244.307213)
					(end 422.591738 -244.271292)
				)
				(arc
					(start 422.591738 -243.862352)
					(mid 422.576859 -243.826431)
					(end 422.540938 -243.811552)
				)
				(arc
					(start 421.141398 -243.811552)
					(mid 421.105477 -243.826431)
					(end 421.090598 -243.862352)
				)
			)
		)
	)
	(zone
		(layers "In1.Cu" "In2.Cu")
		(hatch none 0.5)
		(connect_pads
			(clearance 0)
		)
		(min_thickness 0.25)
		(keepout
			(tracks not_allowed)
			(vias allowed)
			(pads allowed)
			(copperpour not_allowed)
			(footprints allowed)
		)
		(placement
			(enabled no)
			(sheetname "")
		)
		(fill yes
			(thermal_gap 0.5)
			(thermal_bridge_width 0.5)
			(island_removal_mode 0)
		)
		(polygon
			(pts
				(arc
					(start 158.06293 -213.671404)
					(mid 158.077809 -213.707325)
					(end 158.11373 -213.722204)
				)
				(arc
					(start 159.51327 -213.722204)
					(mid 159.549191 -213.707325)
					(end 159.56407 -213.671404)
				)
				(arc
					(start 159.56407 -213.262464)
					(mid 159.549191 -213.226543)
					(end 159.51327 -213.211664)
				)
				(arc
					(start 158.11373 -213.211664)
					(mid 158.077809 -213.226543)
					(end 158.06293 -213.262464)
				)
			)
		)
	)
	(zone
		(layers "In1.Cu" "In2.Cu")
		(hatch none 0.5)
		(connect_pads
			(clearance 0)
		)
		(min_thickness 0.25)
		(keepout
			(tracks not_allowed)
			(vias allowed)
			(pads allowed)
			(copperpour not_allowed)
			(footprints allowed)
		)
		(placement
			(enabled no)
			(sheetname "")
		)
		(fill yes
			(thermal_gap 0.5)
			(thermal_bridge_width 0.5)
			(island_removal_mode 0)
		)
		(polygon
			(pts
				(arc
					(start 277.961598 -252.771402)
					(mid 277.976477 -252.807323)
					(end 278.012398 -252.822202)
				)
				(arc
					(start 279.411938 -252.822202)
					(mid 279.447859 -252.807323)
					(end 279.462738 -252.771402)
				)
				(arc
					(start 279.462738 -252.362462)
					(mid 279.447859 -252.326541)
					(end 279.411938 -252.311662)
				)
				(arc
					(start 278.012398 -252.311662)
					(mid 277.976477 -252.326541)
					(end 277.961598 -252.362462)
				)
			)
		)
	)
	(zone
		(layers "In1.Cu" "In2.Cu")
		(hatch none 0.5)
		(connect_pads
			(clearance 0)
		)
		(min_thickness 0.25)
		(keepout
			(tracks not_allowed)
			(vias allowed)
			(pads allowed)
			(copperpour not_allowed)
			(footprints allowed)
		)
		(placement
			(enabled no)
			(sheetname "")
		)
		(fill yes
			(thermal_gap 0.5)
			(thermal_bridge_width 0.5)
			(island_removal_mode 0)
		)
		(polygon
			(pts
				(arc
					(start 165.60673 -217.071448)
					(mid 165.621609 -217.107369)
					(end 165.65753 -217.122248)
				)
				(arc
					(start 167.05707 -217.122248)
					(mid 167.092991 -217.107369)
					(end 167.10787 -217.071448)
				)
				(arc
					(start 167.10787 -216.662508)
					(mid 167.092991 -216.626587)
					(end 167.05707 -216.611708)
				)
				(arc
					(start 165.65753 -216.611708)
					(mid 165.621609 -216.626587)
					(end 165.60673 -216.662508)
				)
			)
		)
	)
	(zone
		(layers "In1.Cu" "In2.Cu")
		(hatch none 0.5)
		(connect_pads
			(clearance 0)
		)
		(min_thickness 0.25)
		(keepout
			(tracks not_allowed)
			(vias allowed)
			(pads allowed)
			(copperpour not_allowed)
			(footprints allowed)
		)
		(placement
			(enabled no)
			(sheetname "")
		)
		(fill yes
			(thermal_gap 0.5)
			(thermal_bridge_width 0.5)
			(island_removal_mode 0)
		)
		(polygon
			(pts
				(arc
					(start 462.909666 -200.071482)
					(mid 462.924545 -200.107403)
					(end 462.960466 -200.122282)
				)
				(arc
					(start 464.360006 -200.122282)
					(mid 464.395927 -200.107403)
					(end 464.410806 -200.071482)
				)
				(arc
					(start 464.410806 -199.662542)
					(mid 464.395927 -199.626621)
					(end 464.360006 -199.611742)
				)
				(arc
					(start 462.960466 -199.611742)
					(mid 462.924545 -199.626621)
					(end 462.909666 -199.662542)
				)
			)
		)
	)
	(zone
		(layers "In1.Cu" "In2.Cu")
		(hatch none 0.5)
		(connect_pads
			(clearance 0)
		)
		(min_thickness 0.25)
		(keepout
			(tracks not_allowed)
			(vias allowed)
			(pads allowed)
			(copperpour not_allowed)
			(footprints allowed)
		)
		(placement
			(enabled no)
			(sheetname "")
		)
		(fill yes
			(thermal_gap 0.5)
			(thermal_bridge_width 0.5)
			(island_removal_mode 0)
		)
		(polygon
			(pts
				(arc
					(start 56.752998 -292.721538)
					(mid 56.767877 -292.757459)
					(end 56.803798 -292.772338)
				)
				(arc
					(start 58.203338 -292.772338)
					(mid 58.239259 -292.757459)
					(end 58.254138 -292.721538)
				)
				(arc
					(start 58.254138 -292.312598)
					(mid 58.239259 -292.276677)
					(end 58.203338 -292.261798)
				)
				(arc
					(start 56.803798 -292.261798)
					(mid 56.767877 -292.276677)
					(end 56.752998 -292.312598)
				)
			)
		)
	)
	(zone
		(layers "In1.Cu" "In2.Cu")
		(hatch none 0.5)
		(connect_pads
			(clearance 0)
		)
		(min_thickness 0.25)
		(keepout
			(tracks not_allowed)
			(vias allowed)
			(pads allowed)
			(copperpour not_allowed)
			(footprints allowed)
		)
		(placement
			(enabled no)
			(sheetname "")
		)
		(fill yes
			(thermal_gap 0.5)
			(thermal_bridge_width 0.5)
			(island_removal_mode 0)
		)
		(polygon
			(pts
				(arc
					(start 203.32573 -302.921416)
					(mid 203.340609 -302.957337)
					(end 203.37653 -302.972216)
				)
				(arc
					(start 204.77607 -302.972216)
					(mid 204.811991 -302.957337)
					(end 204.82687 -302.921416)
				)
				(arc
					(start 204.82687 -302.512476)
					(mid 204.811991 -302.476555)
					(end 204.77607 -302.461676)
				)
				(arc
					(start 203.37653 -302.461676)
					(mid 203.340609 -302.476555)
					(end 203.32573 -302.512476)
				)
			)
		)
	)
	(zone
		(layers "In1.Cu" "In2.Cu")
		(hatch none 0.5)
		(connect_pads
			(clearance 0)
		)
		(min_thickness 0.25)
		(keepout
			(tracks not_allowed)
			(vias allowed)
			(pads allowed)
			(copperpour not_allowed)
			(footprints allowed)
		)
		(placement
			(enabled no)
			(sheetname "")
		)
		(fill yes
			(thermal_gap 0.5)
			(thermal_bridge_width 0.5)
			(island_removal_mode 0)
		)
		(polygon
			(pts
				(arc
					(start 455.365866 -228.121464)
					(mid 455.380745 -228.157385)
					(end 455.416666 -228.172264)
				)
				(arc
					(start 456.816206 -228.172264)
					(mid 456.852127 -228.157385)
					(end 456.867006 -228.121464)
				)
				(arc
					(start 456.867006 -227.712524)
					(mid 456.852127 -227.676603)
					(end 456.816206 -227.661724)
				)
				(arc
					(start 455.416666 -227.661724)
					(mid 455.380745 -227.676603)
					(end 455.365866 -227.712524)
				)
			)
		)
	)
	(zone
		(layers "In1.Cu" "In2.Cu")
		(hatch none 0.5)
		(connect_pads
			(clearance 0)
		)
		(min_thickness 0.25)
		(keepout
			(tracks not_allowed)
			(vias allowed)
			(pads allowed)
			(copperpour not_allowed)
			(footprints allowed)
		)
		(placement
			(enabled no)
			(sheetname "")
		)
		(fill yes
			(thermal_gap 0.5)
			(thermal_bridge_width 0.5)
			(island_removal_mode 0)
		)
		(polygon
			(pts
				(arc
					(start 293.049198 -291.8714)
					(mid 293.064077 -291.907321)
					(end 293.099998 -291.9222)
				)
				(arc
					(start 294.499538 -291.9222)
					(mid 294.535459 -291.907321)
					(end 294.550338 -291.8714)
				)
				(arc
					(start 294.550338 -291.46246)
					(mid 294.535459 -291.426539)
					(end 294.499538 -291.41166)
				)
				(arc
					(start 293.099998 -291.41166)
					(mid 293.064077 -291.426539)
					(end 293.049198 -291.46246)
				)
			)
		)
	)
	(zone
		(layers "In1.Cu" "In2.Cu")
		(hatch none 0.5)
		(connect_pads
			(clearance 0)
		)
		(min_thickness 0.25)
		(keepout
			(tracks not_allowed)
			(vias allowed)
			(pads allowed)
			(copperpour not_allowed)
			(footprints allowed)
		)
		(placement
			(enabled no)
			(sheetname "")
		)
		(fill yes
			(thermal_gap 0.5)
			(thermal_bridge_width 0.5)
			(island_removal_mode 0)
		)
		(polygon
			(pts
				(arc
					(start 7.39013 -266.371324)
					(mid 7.405009 -266.407245)
					(end 7.44093 -266.422124)
				)
				(arc
					(start 8.84047 -266.422124)
					(mid 8.876391 -266.407245)
					(end 8.89127 -266.371324)
				)
				(arc
					(start 8.89127 -265.962384)
					(mid 8.876391 -265.926463)
					(end 8.84047 -265.911584)
				)
				(arc
					(start 7.44093 -265.911584)
					(mid 7.405009 -265.926463)
					(end 7.39013 -265.962384)
				)
			)
		)
	)
	(zone
		(layers "In1.Cu" "In2.Cu")
		(hatch none 0.5)
		(connect_pads
			(clearance 0)
		)
		(min_thickness 0.25)
		(keepout
			(tracks not_allowed)
			(vias allowed)
			(pads allowed)
			(copperpour not_allowed)
			(footprints allowed)
		)
		(placement
			(enabled no)
			(sheetname "")
		)
		(fill yes
			(thermal_gap 0.5)
			(thermal_bridge_width 0.5)
			(island_removal_mode 0)
		)
		(polygon
			(pts
				(arc
					(start 410.103066 -205.171548)
					(mid 410.117945 -205.207469)
					(end 410.153866 -205.222348)
				)
				(arc
					(start 411.553406 -205.222348)
					(mid 411.589327 -205.207469)
					(end 411.604206 -205.171548)
				)
				(arc
					(start 411.604206 -204.762608)
					(mid 411.589327 -204.726687)
					(end 411.553406 -204.711808)
				)
				(arc
					(start 410.153866 -204.711808)
					(mid 410.117945 -204.726687)
					(end 410.103066 -204.762608)
				)
			)
		)
	)
	(zone
		(layers "In1.Cu" "In2.Cu")
		(hatch none 0.5)
		(connect_pads
			(clearance 0)
		)
		(min_thickness 0.25)
		(keepout
			(tracks not_allowed)
			(vias allowed)
			(pads allowed)
			(copperpour not_allowed)
			(footprints allowed)
		)
		(placement
			(enabled no)
			(sheetname "")
		)
		(fill yes
			(thermal_gap 0.5)
			(thermal_bridge_width 0.5)
			(island_removal_mode 0)
		)
		(polygon
			(pts
				(arc
					(start 37.56533 -303.7713)
					(mid 37.580209 -303.807221)
					(end 37.61613 -303.8221)
				)
				(arc
					(start 39.01567 -303.8221)
					(mid 39.051591 -303.807221)
					(end 39.06647 -303.7713)
				)
				(arc
					(start 39.06647 -303.36236)
					(mid 39.051591 -303.326439)
					(end 39.01567 -303.31156)
				)
				(arc
					(start 37.61613 -303.31156)
					(mid 37.580209 -303.326439)
					(end 37.56533 -303.36236)
				)
			)
		)
	)
	(zone
		(layers "In1.Cu" "In2.Cu")
		(hatch none 0.5)
		(connect_pads
			(clearance 0)
		)
		(min_thickness 0.25)
		(keepout
			(tracks not_allowed)
			(vias allowed)
			(pads allowed)
			(copperpour not_allowed)
			(footprints allowed)
		)
		(placement
			(enabled no)
			(sheetname "")
		)
		(fill yes
			(thermal_gap 0.5)
			(thermal_bridge_width 0.5)
			(island_removal_mode 0)
		)
		(polygon
			(pts
				(arc
					(start 188.23813 -230.67137)
					(mid 188.253009 -230.707291)
					(end 188.28893 -230.72217)
				)
				(arc
					(start 189.68847 -230.72217)
					(mid 189.724391 -230.707291)
					(end 189.73927 -230.67137)
				)
				(arc
					(start 189.73927 -230.26243)
					(mid 189.724391 -230.226509)
					(end 189.68847 -230.21163)
				)
				(arc
					(start 188.28893 -230.21163)
					(mid 188.253009 -230.226509)
					(end 188.23813 -230.26243)
				)
			)
		)
	)
	(zone
		(layers "In1.Cu" "In2.Cu")
		(hatch none 0.5)
		(connect_pads
			(clearance 0)
		)
		(min_thickness 0.25)
		(keepout
			(tracks not_allowed)
			(vias allowed)
			(pads allowed)
			(copperpour not_allowed)
			(footprints allowed)
		)
		(placement
			(enabled no)
			(sheetname "")
		)
		(fill yes
			(thermal_gap 0.5)
			(thermal_bridge_width 0.5)
			(island_removal_mode 0)
		)
		(polygon
			(pts
				(arc
					(start 455.365866 -259.57149)
					(mid 455.380745 -259.607411)
					(end 455.416666 -259.62229)
				)
				(arc
					(start 456.816206 -259.62229)
					(mid 456.852127 -259.607411)
					(end 456.867006 -259.57149)
				)
				(arc
					(start 456.867006 -259.16255)
					(mid 456.852127 -259.126629)
					(end 456.816206 -259.11175)
				)
				(arc
					(start 455.416666 -259.11175)
					(mid 455.380745 -259.126629)
					(end 455.365866 -259.16255)
				)
			)
		)
	)
	(zone
		(layers "In1.Cu" "In2.Cu")
		(hatch none 0.5)
		(connect_pads
			(clearance 0)
		)
		(min_thickness 0.25)
		(keepout
			(tracks not_allowed)
			(vias allowed)
			(pads allowed)
			(copperpour not_allowed)
			(footprints allowed)
		)
		(placement
			(enabled no)
			(sheetname "")
		)
		(fill yes
			(thermal_gap 0.5)
			(thermal_bridge_width 0.5)
			(island_removal_mode 0)
		)
		(polygon
			(pts
				(arc
					(start 19.033998 -259.57149)
					(mid 19.048877 -259.607411)
					(end 19.084798 -259.62229)
				)
				(arc
					(start 20.484338 -259.62229)
					(mid 20.520259 -259.607411)
					(end 20.535138 -259.57149)
				)
				(arc
					(start 20.535138 -259.16255)
					(mid 20.520259 -259.126629)
					(end 20.484338 -259.11175)
				)
				(arc
					(start 19.084798 -259.11175)
					(mid 19.048877 -259.126629)
					(end 19.033998 -259.16255)
				)
			)
		)
	)
	(zone
		(layers "In1.Cu" "In2.Cu")
		(hatch none 0.5)
		(connect_pads
			(clearance 0)
		)
		(min_thickness 0.25)
		(keepout
			(tracks not_allowed)
			(vias allowed)
			(pads allowed)
			(copperpour not_allowed)
			(footprints allowed)
		)
		(placement
			(enabled no)
			(sheetname "")
		)
		(fill yes
			(thermal_gap 0.5)
			(thermal_bridge_width 0.5)
			(island_removal_mode 0)
		)
		(polygon
			(pts
				(arc
					(start 173.15053 -305.471322)
					(mid 173.165409 -305.507243)
					(end 173.20133 -305.522122)
				)
				(arc
					(start 174.60087 -305.522122)
					(mid 174.636791 -305.507243)
					(end 174.65167 -305.471322)
				)
				(arc
					(start 174.65167 -305.062382)
					(mid 174.636791 -305.026461)
					(end 174.60087 -305.011582)
				)
				(arc
					(start 173.20133 -305.011582)
					(mid 173.165409 -305.026461)
					(end 173.15053 -305.062382)
				)
			)
		)
	)
	(zone
		(layers "In1.Cu" "In2.Cu")
		(hatch none 0.5)
		(connect_pads
			(clearance 0)
		)
		(min_thickness 0.25)
		(keepout
			(tracks not_allowed)
			(vias allowed)
			(pads allowed)
			(copperpour not_allowed)
			(footprints allowed)
		)
		(placement
			(enabled no)
			(sheetname "")
		)
		(fill yes
			(thermal_gap 0.5)
			(thermal_bridge_width 0.5)
			(island_removal_mode 0)
		)
		(polygon
			(pts
				(arc
					(start 52.65293 -226.421442)
					(mid 52.667809 -226.457363)
					(end 52.70373 -226.472242)
				)
				(arc
					(start 54.10327 -226.472242)
					(mid 54.139191 -226.457363)
					(end 54.15407 -226.421442)
				)
				(arc
					(start 54.15407 -226.012502)
					(mid 54.139191 -225.976581)
					(end 54.10327 -225.961702)
				)
				(arc
					(start 52.70373 -225.961702)
					(mid 52.667809 -225.976581)
					(end 52.65293 -226.012502)
				)
			)
		)
	)
	(zone
		(layers "In1.Cu" "In2.Cu")
		(hatch none 0.5)
		(connect_pads
			(clearance 0)
		)
		(min_thickness 0.25)
		(keepout
			(tracks not_allowed)
			(vias allowed)
			(pads allowed)
			(copperpour not_allowed)
			(footprints allowed)
		)
		(placement
			(enabled no)
			(sheetname "")
		)
		(fill yes
			(thermal_gap 0.5)
			(thermal_bridge_width 0.5)
			(island_removal_mode 0)
		)
		(polygon
			(pts
				(arc
					(start 162.162998 -315.671454)
					(mid 162.177877 -315.707375)
					(end 162.213798 -315.722254)
				)
				(arc
					(start 163.613338 -315.722254)
					(mid 163.649259 -315.707375)
					(end 163.664138 -315.671454)
				)
				(arc
					(start 163.664138 -315.262514)
					(mid 163.649259 -315.226593)
					(end 163.613338 -315.211714)
				)
				(arc
					(start 162.213798 -315.211714)
					(mid 162.177877 -315.226593)
					(end 162.162998 -315.262514)
				)
			)
		)
	)
	(zone
		(layers "In1.Cu" "In2.Cu")
		(hatch none 0.5)
		(connect_pads
			(clearance 0)
		)
		(min_thickness 0.25)
		(keepout
			(tracks not_allowed)
			(vias allowed)
			(pads allowed)
			(copperpour not_allowed)
			(footprints allowed)
		)
		(placement
			(enabled no)
			(sheetname "")
		)
		(fill yes
			(thermal_gap 0.5)
			(thermal_bridge_width 0.5)
			(island_removal_mode 0)
		)
		(polygon
			(pts
				(arc
					(start 162.162998 -311.421526)
					(mid 162.177877 -311.457447)
					(end 162.213798 -311.472326)
				)
				(arc
					(start 163.613338 -311.472326)
					(mid 163.649259 -311.457447)
					(end 163.664138 -311.421526)
				)
				(arc
					(start 163.664138 -311.012586)
					(mid 163.649259 -310.976665)
					(end 163.613338 -310.961786)
				)
				(arc
					(start 162.213798 -310.961786)
					(mid 162.177877 -310.976665)
					(end 162.162998 -311.012586)
				)
			)
		)
	)
	(zone
		(layers "In1.Cu" "In2.Cu")
		(hatch none 0.5)
		(connect_pads
			(clearance 0)
		)
		(min_thickness 0.25)
		(keepout
			(tracks not_allowed)
			(vias allowed)
			(pads allowed)
			(copperpour not_allowed)
			(footprints allowed)
		)
		(placement
			(enabled no)
			(sheetname "")
		)
		(fill yes
			(thermal_gap 0.5)
			(thermal_bridge_width 0.5)
			(island_removal_mode 0)
		)
		(polygon
			(pts
				(arc
					(start 49.209198 -236.62132)
					(mid 49.224077 -236.657241)
					(end 49.259998 -236.67212)
				)
				(arc
					(start 50.659538 -236.67212)
					(mid 50.695459 -236.657241)
					(end 50.710338 -236.62132)
				)
				(arc
					(start 50.710338 -236.21238)
					(mid 50.695459 -236.176459)
					(end 50.659538 -236.16158)
				)
				(arc
					(start 49.259998 -236.16158)
					(mid 49.224077 -236.176459)
					(end 49.209198 -236.21238)
				)
			)
		)
	)
	(zone
		(layers "In1.Cu" "In2.Cu")
		(hatch none 0.5)
		(connect_pads
			(clearance 0)
		)
		(min_thickness 0.25)
		(keepout
			(tracks not_allowed)
			(vias allowed)
			(pads allowed)
			(copperpour not_allowed)
			(footprints allowed)
		)
		(placement
			(enabled no)
			(sheetname "")
		)
		(fill yes
			(thermal_gap 0.5)
			(thermal_bridge_width 0.5)
			(island_removal_mode 0)
		)
		(polygon
			(pts
				(arc
					(start 64.296798 -227.271326)
					(mid 64.311677 -227.307247)
					(end 64.347598 -227.322126)
				)
				(arc
					(start 65.747138 -227.322126)
					(mid 65.783059 -227.307247)
					(end 65.797938 -227.271326)
				)
				(arc
					(start 65.797938 -226.862386)
					(mid 65.783059 -226.826465)
					(end 65.747138 -226.811586)
				)
				(arc
					(start 64.347598 -226.811586)
					(mid 64.311677 -226.826465)
					(end 64.296798 -226.862386)
				)
			)
		)
	)
	(zone
		(layers "In1.Cu" "In2.Cu")
		(hatch none 0.5)
		(connect_pads
			(clearance 0)
		)
		(min_thickness 0.25)
		(keepout
			(tracks not_allowed)
			(vias allowed)
			(pads allowed)
			(copperpour not_allowed)
			(footprints allowed)
		)
		(placement
			(enabled no)
			(sheetname "")
		)
		(fill yes
			(thermal_gap 0.5)
			(thermal_bridge_width 0.5)
			(island_removal_mode 0)
		)
		(polygon
			(pts
				(arc
					(start 30.02153 -202.621388)
					(mid 30.036409 -202.657309)
					(end 30.07233 -202.672188)
				)
				(arc
					(start 31.47187 -202.672188)
					(mid 31.507791 -202.657309)
					(end 31.52267 -202.621388)
				)
				(arc
					(start 31.52267 -202.212448)
					(mid 31.507791 -202.176527)
					(end 31.47187 -202.161648)
				)
				(arc
					(start 30.07233 -202.161648)
					(mid 30.036409 -202.176527)
					(end 30.02153 -202.212448)
				)
			)
		)
	)
	(zone
		(layers "In1.Cu" "In2.Cu")
		(hatch none 0.5)
		(connect_pads
			(clearance 0)
		)
		(min_thickness 0.25)
		(keepout
			(tracks not_allowed)
			(vias allowed)
			(pads allowed)
			(copperpour not_allowed)
			(footprints allowed)
		)
		(placement
			(enabled no)
			(sheetname "")
		)
		(fill yes
			(thermal_gap 0.5)
			(thermal_bridge_width 0.5)
			(island_removal_mode 0)
		)
		(polygon
			(pts
				(arc
					(start 192.338198 -308.021482)
					(mid 192.353077 -308.057403)
					(end 192.388998 -308.072282)
				)
				(arc
					(start 193.788538 -308.072282)
					(mid 193.824459 -308.057403)
					(end 193.839338 -308.021482)
				)
				(arc
					(start 193.839338 -307.612542)
					(mid 193.824459 -307.576621)
					(end 193.788538 -307.561742)
				)
				(arc
					(start 192.388998 -307.561742)
					(mid 192.353077 -307.576621)
					(end 192.338198 -307.612542)
				)
			)
		)
	)
	(zone
		(layers "In1.Cu" "In2.Cu")
		(hatch none 0.5)
		(connect_pads
			(clearance 0)
		)
		(min_thickness 0.25)
		(keepout
			(tracks not_allowed)
			(vias allowed)
			(pads allowed)
			(copperpour not_allowed)
			(footprints allowed)
		)
		(placement
			(enabled no)
			(sheetname "")
		)
		(fill yes
			(thermal_gap 0.5)
			(thermal_bridge_width 0.5)
			(island_removal_mode 0)
		)
		(polygon
			(pts
				(arc
					(start 255.330198 -262.971534)
					(mid 255.345077 -263.007455)
					(end 255.380998 -263.022334)
				)
				(arc
					(start 256.780538 -263.022334)
					(mid 256.816459 -263.007455)
					(end 256.831338 -262.971534)
				)
				(arc
					(start 256.831338 -262.562594)
					(mid 256.816459 -262.526673)
					(end 256.780538 -262.511794)
				)
				(arc
					(start 255.380998 -262.511794)
					(mid 255.345077 -262.526673)
					(end 255.330198 -262.562594)
				)
			)
		)
	)
	(zone
		(layers "In1.Cu" "In2.Cu")
		(hatch none 0.5)
		(connect_pads
			(clearance 0)
		)
		(min_thickness 0.25)
		(keepout
			(tracks not_allowed)
			(vias allowed)
			(pads allowed)
			(copperpour not_allowed)
			(footprints allowed)
		)
		(placement
			(enabled no)
			(sheetname "")
		)
		(fill yes
			(thermal_gap 0.5)
			(thermal_bridge_width 0.5)
			(island_removal_mode 0)
		)
		(polygon
			(pts
				(arc
					(start 443.721998 -290.171378)
					(mid 443.736877 -290.207299)
					(end 443.772798 -290.222178)
				)
				(arc
					(start 445.172338 -290.222178)
					(mid 445.208259 -290.207299)
					(end 445.223138 -290.171378)
				)
				(arc
					(start 445.223138 -289.762438)
					(mid 445.208259 -289.726517)
					(end 445.172338 -289.711638)
				)
				(arc
					(start 443.772798 -289.711638)
					(mid 443.736877 -289.726517)
					(end 443.721998 -289.762438)
				)
			)
		)
	)
	(zone
		(layers "In1.Cu" "In2.Cu")
		(hatch none 0.5)
		(connect_pads
			(clearance 0)
		)
		(min_thickness 0.25)
		(keepout
			(tracks not_allowed)
			(vias allowed)
			(pads allowed)
			(copperpour not_allowed)
			(footprints allowed)
		)
		(placement
			(enabled no)
			(sheetname "")
		)
		(fill yes
			(thermal_gap 0.5)
			(thermal_bridge_width 0.5)
			(island_removal_mode 0)
		)
		(polygon
			(pts
				(arc
					(start 14.93393 -240.021364)
					(mid 14.948809 -240.057285)
					(end 14.98473 -240.072164)
				)
				(arc
					(start 16.38427 -240.072164)
					(mid 16.420191 -240.057285)
					(end 16.43507 -240.021364)
				)
				(arc
					(start 16.43507 -239.612424)
					(mid 16.420191 -239.576503)
					(end 16.38427 -239.561624)
				)
				(arc
					(start 14.98473 -239.561624)
					(mid 14.948809 -239.576503)
					(end 14.93393 -239.612424)
				)
			)
		)
	)
	(zone
		(layers "In1.Cu" "In2.Cu")
		(hatch none 0.5)
		(connect_pads
			(clearance 0)
		)
		(min_thickness 0.25)
		(keepout
			(tracks not_allowed)
			(vias allowed)
			(pads allowed)
			(copperpour not_allowed)
			(footprints allowed)
		)
		(placement
			(enabled no)
			(sheetname "")
		)
		(fill yes
			(thermal_gap 0.5)
			(thermal_bridge_width 0.5)
			(island_removal_mode 0)
		)
		(polygon
			(pts
				(arc
					(start 270.417798 -310.571388)
					(mid 270.432677 -310.607309)
					(end 270.468598 -310.622188)
				)
				(arc
					(start 271.868138 -310.622188)
					(mid 271.904059 -310.607309)
					(end 271.918938 -310.571388)
				)
				(arc
					(start 271.918938 -310.162448)
					(mid 271.904059 -310.126527)
					(end 271.868138 -310.111648)
				)
				(arc
					(start 270.468598 -310.111648)
					(mid 270.432677 -310.126527)
					(end 270.417798 -310.162448)
				)
			)
		)
	)
	(zone
		(layers "In1.Cu" "In2.Cu")
		(hatch none 0.5)
		(connect_pads
			(clearance 0)
		)
		(min_thickness 0.25)
		(keepout
			(tracks not_allowed)
			(vias allowed)
			(pads allowed)
			(copperpour not_allowed)
			(footprints allowed)
		)
		(placement
			(enabled no)
			(sheetname "")
		)
		(fill yes
			(thermal_gap 0.5)
			(thermal_bridge_width 0.5)
			(island_removal_mode 0)
		)
		(polygon
			(pts
				(arc
					(start 255.330198 -238.321342)
					(mid 255.345077 -238.357263)
					(end 255.380998 -238.372142)
				)
				(arc
					(start 256.780538 -238.372142)
					(mid 256.816459 -238.357263)
					(end 256.831338 -238.321342)
				)
				(arc
					(start 256.831338 -237.912402)
					(mid 256.816459 -237.876481)
					(end 256.780538 -237.861602)
				)
				(arc
					(start 255.380998 -237.861602)
					(mid 255.345077 -237.876481)
					(end 255.330198 -237.912402)
				)
			)
		)
	)
	(zone
		(layers "In1.Cu" "In2.Cu")
		(hatch none 0.5)
		(connect_pads
			(clearance 0)
		)
		(min_thickness 0.25)
		(keepout
			(tracks not_allowed)
			(vias allowed)
			(pads allowed)
			(copperpour not_allowed)
			(footprints allowed)
		)
		(placement
			(enabled no)
			(sheetname "")
		)
		(fill yes
			(thermal_gap 0.5)
			(thermal_bridge_width 0.5)
			(island_removal_mode 0)
		)
		(polygon
			(pts
				(arc
					(start 214.969598 -217.921332)
					(mid 214.984477 -217.957253)
					(end 215.020398 -217.972132)
				)
				(arc
					(start 216.419938 -217.972132)
					(mid 216.455859 -217.957253)
					(end 216.470738 -217.921332)
				)
				(arc
					(start 216.470738 -217.512392)
					(mid 216.455859 -217.476471)
					(end 216.419938 -217.461592)
				)
				(arc
					(start 215.020398 -217.461592)
					(mid 214.984477 -217.476471)
					(end 214.969598 -217.512392)
				)
			)
		)
	)
	(zone
		(layers "In1.Cu" "In2.Cu")
		(hatch none 0.5)
		(connect_pads
			(clearance 0)
		)
		(min_thickness 0.25)
		(keepout
			(tracks not_allowed)
			(vias allowed)
			(pads allowed)
			(copperpour not_allowed)
			(footprints allowed)
		)
		(placement
			(enabled no)
			(sheetname "")
		)
		(fill yes
			(thermal_gap 0.5)
			(thermal_bridge_width 0.5)
			(island_removal_mode 0)
		)
		(polygon
			(pts
				(arc
					(start 458.809598 -240.021364)
					(mid 458.824477 -240.057285)
					(end 458.860398 -240.072164)
				)
				(arc
					(start 460.259938 -240.072164)
					(mid 460.295859 -240.057285)
					(end 460.310738 -240.021364)
				)
				(arc
					(start 460.310738 -239.612424)
					(mid 460.295859 -239.576503)
					(end 460.259938 -239.561624)
				)
				(arc
					(start 458.860398 -239.561624)
					(mid 458.824477 -239.576503)
					(end 458.809598 -239.612424)
				)
			)
		)
	)
	(zone
		(layers "In1.Cu" "In2.Cu")
		(hatch none 0.5)
		(connect_pads
			(clearance 0)
		)
		(min_thickness 0.25)
		(keepout
			(tracks not_allowed)
			(vias allowed)
			(pads allowed)
			(copperpour not_allowed)
			(footprints allowed)
		)
		(placement
			(enabled no)
			(sheetname "")
		)
		(fill yes
			(thermal_gap 0.5)
			(thermal_bridge_width 0.5)
			(island_removal_mode 0)
		)
		(polygon
			(pts
				(arc
					(start 60.19673 -223.021398)
					(mid 60.211609 -223.057319)
					(end 60.24753 -223.072198)
				)
				(arc
					(start 61.64707 -223.072198)
					(mid 61.682991 -223.057319)
					(end 61.69787 -223.021398)
				)
				(arc
					(start 61.69787 -222.612458)
					(mid 61.682991 -222.576537)
					(end 61.64707 -222.561658)
				)
				(arc
					(start 60.24753 -222.561658)
					(mid 60.211609 -222.576537)
					(end 60.19673 -222.612458)
				)
			)
		)
	)
	(zone
		(layers "In1.Cu" "In2.Cu")
		(hatch none 0.5)
		(connect_pads
			(clearance 0)
		)
		(min_thickness 0.25)
		(keepout
			(tracks not_allowed)
			(vias allowed)
			(pads allowed)
			(copperpour not_allowed)
			(footprints allowed)
		)
		(placement
			(enabled no)
			(sheetname "")
		)
		(fill yes
			(thermal_gap 0.5)
			(thermal_bridge_width 0.5)
			(island_removal_mode 0)
		)
		(polygon
			(pts
				(arc
					(start 49.209198 -199.221344)
					(mid 49.224077 -199.257265)
					(end 49.259998 -199.272144)
				)
				(arc
					(start 50.659538 -199.272144)
					(mid 50.695459 -199.257265)
					(end 50.710338 -199.221344)
				)
				(arc
					(start 50.710338 -198.812404)
					(mid 50.695459 -198.776483)
					(end 50.659538 -198.761604)
				)
				(arc
					(start 49.259998 -198.761604)
					(mid 49.224077 -198.776483)
					(end 49.209198 -198.812404)
				)
			)
		)
	)
	(zone
		(layers "In1.Cu" "In2.Cu")
		(hatch none 0.5)
		(connect_pads
			(clearance 0)
		)
		(min_thickness 0.25)
		(keepout
			(tracks not_allowed)
			(vias allowed)
			(pads allowed)
			(copperpour not_allowed)
			(footprints allowed)
		)
		(placement
			(enabled no)
			(sheetname "")
		)
		(fill yes
			(thermal_gap 0.5)
			(thermal_bridge_width 0.5)
			(island_removal_mode 0)
		)
		(polygon
			(pts
				(arc
					(start 262.873998 -200.921366)
					(mid 262.888877 -200.957287)
					(end 262.924798 -200.972166)
				)
				(arc
					(start 264.324338 -200.972166)
					(mid 264.360259 -200.957287)
					(end 264.375138 -200.921366)
				)
				(arc
					(start 264.375138 -200.512426)
					(mid 264.360259 -200.476505)
					(end 264.324338 -200.461626)
				)
				(arc
					(start 262.924798 -200.461626)
					(mid 262.888877 -200.476505)
					(end 262.873998 -200.512426)
				)
			)
		)
	)
	(zone
		(layers "In1.Cu" "In2.Cu")
		(hatch none 0.5)
		(connect_pads
			(clearance 0)
		)
		(min_thickness 0.25)
		(keepout
			(tracks not_allowed)
			(vias allowed)
			(pads allowed)
			(copperpour not_allowed)
			(footprints allowed)
		)
		(placement
			(enabled no)
			(sheetname "")
		)
		(fill yes
			(thermal_gap 0.5)
			(thermal_bridge_width 0.5)
			(island_removal_mode 0)
		)
		(polygon
			(pts
				(arc
					(start 41.665398 -251.921518)
					(mid 41.680277 -251.957439)
					(end 41.716198 -251.972318)
				)
				(arc
					(start 43.115738 -251.972318)
					(mid 43.151659 -251.957439)
					(end 43.166538 -251.921518)
				)
				(arc
					(start 43.166538 -251.512578)
					(mid 43.151659 -251.476657)
					(end 43.115738 -251.461778)
				)
				(arc
					(start 41.716198 -251.461778)
					(mid 41.680277 -251.476657)
					(end 41.665398 -251.512578)
				)
			)
		)
	)
	(zone
		(layers "In1.Cu" "In2.Cu")
		(hatch none 0.5)
		(connect_pads
			(clearance 0)
		)
		(min_thickness 0.25)
		(keepout
			(tracks not_allowed)
			(vias allowed)
			(pads allowed)
			(copperpour not_allowed)
			(footprints allowed)
		)
		(placement
			(enabled no)
			(sheetname "")
		)
		(fill yes
			(thermal_gap 0.5)
			(thermal_bridge_width 0.5)
			(island_removal_mode 0)
		)
		(polygon
			(pts
				(arc
					(start 180.69433 -274.871434)
					(mid 180.709209 -274.907355)
					(end 180.74513 -274.922234)
				)
				(arc
					(start 182.14467 -274.922234)
					(mid 182.180591 -274.907355)
					(end 182.19547 -274.871434)
				)
				(arc
					(start 182.19547 -274.462494)
					(mid 182.180591 -274.426573)
					(end 182.14467 -274.411694)
				)
				(arc
					(start 180.74513 -274.411694)
					(mid 180.709209 -274.426573)
					(end 180.69433 -274.462494)
				)
			)
		)
	)
	(zone
		(layers "In1.Cu" "In2.Cu")
		(hatch none 0.5)
		(connect_pads
			(clearance 0)
		)
		(min_thickness 0.25)
		(keepout
			(tracks not_allowed)
			(vias allowed)
			(pads allowed)
			(copperpour not_allowed)
			(footprints allowed)
		)
		(placement
			(enabled no)
			(sheetname "")
		)
		(fill yes
			(thermal_gap 0.5)
			(thermal_bridge_width 0.5)
			(island_removal_mode 0)
		)
		(polygon
			(pts
				(arc
					(start 64.296798 -228.121464)
					(mid 64.311677 -228.157385)
					(end 64.347598 -228.172264)
				)
				(arc
					(start 65.747138 -228.172264)
					(mid 65.783059 -228.157385)
					(end 65.797938 -228.121464)
				)
				(arc
					(start 65.797938 -227.712524)
					(mid 65.783059 -227.676603)
					(end 65.747138 -227.661724)
				)
				(arc
					(start 64.347598 -227.661724)
					(mid 64.311677 -227.676603)
					(end 64.296798 -227.712524)
				)
			)
		)
	)
	(zone
		(layers "In1.Cu" "In2.Cu")
		(hatch none 0.5)
		(connect_pads
			(clearance 0)
		)
		(min_thickness 0.25)
		(keepout
			(tracks not_allowed)
			(vias allowed)
			(pads allowed)
			(copperpour not_allowed)
			(footprints allowed)
		)
		(placement
			(enabled no)
			(sheetname "")
		)
		(fill yes
			(thermal_gap 0.5)
			(thermal_bridge_width 0.5)
			(island_removal_mode 0)
		)
		(polygon
			(pts
				(arc
					(start 180.69433 -228.971348)
					(mid 180.709209 -229.007269)
					(end 180.74513 -229.022148)
				)
				(arc
					(start 182.14467 -229.022148)
					(mid 182.180591 -229.007269)
					(end 182.19547 -228.971348)
				)
				(arc
					(start 182.19547 -228.562408)
					(mid 182.180591 -228.526487)
					(end 182.14467 -228.511608)
				)
				(arc
					(start 180.74513 -228.511608)
					(mid 180.709209 -228.526487)
					(end 180.69433 -228.562408)
				)
			)
		)
	)
	(zone
		(layers "In1.Cu" "In2.Cu")
		(hatch none 0.5)
		(connect_pads
			(clearance 0)
		)
		(min_thickness 0.25)
		(keepout
			(tracks not_allowed)
			(vias allowed)
			(pads allowed)
			(copperpour not_allowed)
			(footprints allowed)
		)
		(placement
			(enabled no)
			(sheetname "")
		)
		(fill yes
			(thermal_gap 0.5)
			(thermal_bridge_width 0.5)
			(island_removal_mode 0)
		)
		(polygon
			(pts
				(arc
					(start 56.752998 -251.921518)
					(mid 56.767877 -251.957439)
					(end 56.803798 -251.972318)
				)
				(arc
					(start 58.203338 -251.972318)
					(mid 58.239259 -251.957439)
					(end 58.254138 -251.921518)
				)
				(arc
					(start 58.254138 -251.512578)
					(mid 58.239259 -251.476657)
					(end 58.203338 -251.461778)
				)
				(arc
					(start 56.803798 -251.461778)
					(mid 56.767877 -251.476657)
					(end 56.752998 -251.512578)
				)
			)
		)
	)
	(zone
		(layers "In1.Cu" "In2.Cu")
		(hatch none 0.5)
		(connect_pads
			(clearance 0)
		)
		(min_thickness 0.25)
		(keepout
			(tracks not_allowed)
			(vias allowed)
			(pads allowed)
			(copperpour not_allowed)
			(footprints allowed)
		)
		(placement
			(enabled no)
			(sheetname "")
		)
		(fill yes
			(thermal_gap 0.5)
			(thermal_bridge_width 0.5)
			(island_removal_mode 0)
		)
		(polygon
			(pts
				(arc
					(start 413.546798 -301.221394)
					(mid 413.561677 -301.257315)
					(end 413.597598 -301.272194)
				)
				(arc
					(start 414.997138 -301.272194)
					(mid 415.033059 -301.257315)
					(end 415.047938 -301.221394)
				)
				(arc
					(start 415.047938 -300.812454)
					(mid 415.033059 -300.776533)
					(end 414.997138 -300.761654)
				)
				(arc
					(start 413.597598 -300.761654)
					(mid 413.561677 -300.776533)
					(end 413.546798 -300.812454)
				)
			)
		)
	)
	(zone
		(layers "In1.Cu" "In2.Cu")
		(hatch none 0.5)
		(connect_pads
			(clearance 0)
		)
		(min_thickness 0.25)
		(keepout
			(tracks not_allowed)
			(vias allowed)
			(pads allowed)
			(copperpour not_allowed)
			(footprints allowed)
		)
		(placement
			(enabled no)
			(sheetname "")
		)
		(fill yes
			(thermal_gap 0.5)
			(thermal_bridge_width 0.5)
			(island_removal_mode 0)
		)
		(polygon
			(pts
				(arc
					(start 428.634398 -286.771334)
					(mid 428.649277 -286.807255)
					(end 428.685198 -286.822134)
				)
				(arc
					(start 430.084738 -286.822134)
					(mid 430.120659 -286.807255)
					(end 430.135538 -286.771334)
				)
				(arc
					(start 430.135538 -286.362394)
					(mid 430.120659 -286.326473)
					(end 430.084738 -286.311594)
				)
				(arc
					(start 428.685198 -286.311594)
					(mid 428.649277 -286.326473)
					(end 428.634398 -286.362394)
				)
			)
		)
	)
	(zone
		(layers "In1.Cu" "In2.Cu")
		(hatch none 0.5)
		(connect_pads
			(clearance 0)
		)
		(min_thickness 0.25)
		(keepout
			(tracks not_allowed)
			(vias allowed)
			(pads allowed)
			(copperpour not_allowed)
			(footprints allowed)
		)
		(placement
			(enabled no)
			(sheetname "")
		)
		(fill yes
			(thermal_gap 0.5)
			(thermal_bridge_width 0.5)
			(island_removal_mode 0)
		)
		(polygon
			(pts
				(arc
					(start 255.330198 -301.221394)
					(mid 255.345077 -301.257315)
					(end 255.380998 -301.272194)
				)
				(arc
					(start 256.780538 -301.272194)
					(mid 256.816459 -301.257315)
					(end 256.831338 -301.221394)
				)
				(arc
					(start 256.831338 -300.812454)
					(mid 256.816459 -300.776533)
					(end 256.780538 -300.761654)
				)
				(arc
					(start 255.380998 -300.761654)
					(mid 255.345077 -300.776533)
					(end 255.330198 -300.812454)
				)
			)
		)
	)
	(zone
		(layers "In1.Cu" "In2.Cu")
		(hatch none 0.5)
		(connect_pads
			(clearance 0)
		)
		(min_thickness 0.25)
		(keepout
			(tracks not_allowed)
			(vias allowed)
			(pads allowed)
			(copperpour not_allowed)
			(footprints allowed)
		)
		(placement
			(enabled no)
			(sheetname "")
		)
		(fill yes
			(thermal_gap 0.5)
			(thermal_bridge_width 0.5)
			(island_removal_mode 0)
		)
		(polygon
			(pts
				(arc
					(start 195.78193 -251.07138)
					(mid 195.796809 -251.107301)
					(end 195.83273 -251.12218)
				)
				(arc
					(start 197.23227 -251.12218)
					(mid 197.268191 -251.107301)
					(end 197.28307 -251.07138)
				)
				(arc
					(start 197.28307 -250.66244)
					(mid 197.268191 -250.626519)
					(end 197.23227 -250.61164)
				)
				(arc
					(start 195.83273 -250.61164)
					(mid 195.796809 -250.626519)
					(end 195.78193 -250.66244)
				)
			)
		)
	)
	(zone
		(layers "In1.Cu" "In2.Cu")
		(hatch none 0.5)
		(connect_pads
			(clearance 0)
		)
		(min_thickness 0.25)
		(keepout
			(tracks not_allowed)
			(vias allowed)
			(pads allowed)
			(copperpour not_allowed)
			(footprints allowed)
		)
		(placement
			(enabled no)
			(sheetname "")
		)
		(fill yes
			(thermal_gap 0.5)
			(thermal_bridge_width 0.5)
			(island_removal_mode 0)
		)
		(polygon
			(pts
				(arc
					(start 259.430266 -227.271326)
					(mid 259.445145 -227.307247)
					(end 259.481066 -227.322126)
				)
				(arc
					(start 260.880606 -227.322126)
					(mid 260.916527 -227.307247)
					(end 260.931406 -227.271326)
				)
				(arc
					(start 260.931406 -226.862386)
					(mid 260.916527 -226.826465)
					(end 260.880606 -226.811586)
				)
				(arc
					(start 259.481066 -226.811586)
					(mid 259.445145 -226.826465)
					(end 259.430266 -226.862386)
				)
			)
		)
	)
	(zone
		(layers "In1.Cu" "In2.Cu")
		(hatch none 0.5)
		(connect_pads
			(clearance 0)
		)
		(min_thickness 0.25)
		(keepout
			(tracks not_allowed)
			(vias allowed)
			(pads allowed)
			(copperpour not_allowed)
			(footprints allowed)
		)
		(placement
			(enabled no)
			(sheetname "")
		)
		(fill yes
			(thermal_gap 0.5)
			(thermal_bridge_width 0.5)
			(island_removal_mode 0)
		)
		(polygon
			(pts
				(arc
					(start 180.69433 -259.57149)
					(mid 180.709209 -259.607411)
					(end 180.74513 -259.62229)
				)
				(arc
					(start 182.14467 -259.62229)
					(mid 182.180591 -259.607411)
					(end 182.19547 -259.57149)
				)
				(arc
					(start 182.19547 -259.16255)
					(mid 182.180591 -259.126629)
					(end 182.14467 -259.11175)
				)
				(arc
					(start 180.74513 -259.11175)
					(mid 180.709209 -259.126629)
					(end 180.69433 -259.16255)
				)
			)
		)
	)
	(zone
		(layers "In1.Cu" "In2.Cu")
		(hatch none 0.5)
		(connect_pads
			(clearance 0)
		)
		(min_thickness 0.25)
		(keepout
			(tracks not_allowed)
			(vias allowed)
			(pads allowed)
			(copperpour not_allowed)
			(footprints allowed)
		)
		(placement
			(enabled no)
			(sheetname "")
		)
		(fill yes
			(thermal_gap 0.5)
			(thermal_bridge_width 0.5)
			(island_removal_mode 0)
		)
		(polygon
			(pts
				(arc
					(start 180.69433 -217.071448)
					(mid 180.709209 -217.107369)
					(end 180.74513 -217.122248)
				)
				(arc
					(start 182.14467 -217.122248)
					(mid 182.180591 -217.107369)
					(end 182.19547 -217.071448)
				)
				(arc
					(start 182.19547 -216.662508)
					(mid 182.180591 -216.626587)
					(end 182.14467 -216.611708)
				)
				(arc
					(start 180.74513 -216.611708)
					(mid 180.709209 -216.626587)
					(end 180.69433 -216.662508)
				)
			)
		)
	)
	(zone
		(layers "In1.Cu" "In2.Cu")
		(hatch none 0.5)
		(connect_pads
			(clearance 0)
		)
		(min_thickness 0.25)
		(keepout
			(tracks not_allowed)
			(vias allowed)
			(pads allowed)
			(copperpour not_allowed)
			(footprints allowed)
		)
		(placement
			(enabled no)
			(sheetname "")
		)
		(fill yes
			(thermal_gap 0.5)
			(thermal_bridge_width 0.5)
			(island_removal_mode 0)
		)
		(polygon
			(pts
				(arc
					(start 64.296798 -309.721504)
					(mid 64.311677 -309.757425)
					(end 64.347598 -309.772304)
				)
				(arc
					(start 65.747138 -309.772304)
					(mid 65.783059 -309.757425)
					(end 65.797938 -309.721504)
				)
				(arc
					(start 65.797938 -309.312564)
					(mid 65.783059 -309.276643)
					(end 65.747138 -309.261764)
				)
				(arc
					(start 64.347598 -309.261764)
					(mid 64.311677 -309.276643)
					(end 64.296798 -309.312564)
				)
			)
		)
	)
	(zone
		(layers "In1.Cu" "In2.Cu")
		(hatch none 0.5)
		(connect_pads
			(clearance 0)
		)
		(min_thickness 0.25)
		(keepout
			(tracks not_allowed)
			(vias allowed)
			(pads allowed)
			(copperpour not_allowed)
			(footprints allowed)
		)
		(placement
			(enabled no)
			(sheetname "")
		)
		(fill yes
			(thermal_gap 0.5)
			(thermal_bridge_width 0.5)
			(island_removal_mode 0)
		)
		(polygon
			(pts
				(arc
					(start 304.693066 -291.021516)
					(mid 304.707945 -291.057437)
					(end 304.743866 -291.072316)
				)
				(arc
					(start 306.143406 -291.072316)
					(mid 306.179327 -291.057437)
					(end 306.194206 -291.021516)
				)
				(arc
					(start 306.194206 -290.612576)
					(mid 306.179327 -290.576655)
					(end 306.143406 -290.561776)
				)
				(arc
					(start 304.743866 -290.561776)
					(mid 304.707945 -290.576655)
					(end 304.693066 -290.612576)
				)
			)
		)
	)
	(zone
		(layers "In1.Cu" "In2.Cu")
		(hatch none 0.5)
		(connect_pads
			(clearance 0)
		)
		(min_thickness 0.25)
		(keepout
			(tracks not_allowed)
			(vias allowed)
			(pads allowed)
			(copperpour not_allowed)
			(footprints allowed)
		)
		(placement
			(enabled no)
			(sheetname "")
		)
		(fill yes
			(thermal_gap 0.5)
			(thermal_bridge_width 0.5)
			(island_removal_mode 0)
		)
		(polygon
			(pts
				(arc
					(start 37.56533 -284.221428)
					(mid 37.580209 -284.257349)
					(end 37.61613 -284.272228)
				)
				(arc
					(start 39.01567 -284.272228)
					(mid 39.051591 -284.257349)
					(end 39.06647 -284.221428)
				)
				(arc
					(start 39.06647 -283.812488)
					(mid 39.051591 -283.776567)
					(end 39.01567 -283.761688)
				)
				(arc
					(start 37.61613 -283.761688)
					(mid 37.580209 -283.776567)
					(end 37.56533 -283.812488)
				)
			)
		)
	)
	(zone
		(layers "In1.Cu" "In2.Cu")
		(hatch none 0.5)
		(connect_pads
			(clearance 0)
		)
		(min_thickness 0.25)
		(keepout
			(tracks not_allowed)
			(vias allowed)
			(pads allowed)
			(copperpour not_allowed)
			(footprints allowed)
		)
		(placement
			(enabled no)
			(sheetname "")
		)
		(fill yes
			(thermal_gap 0.5)
			(thermal_bridge_width 0.5)
			(island_removal_mode 0)
		)
		(polygon
			(pts
				(arc
					(start 22.47773 -210.27136)
					(mid 22.492609 -210.307281)
					(end 22.52853 -210.32216)
				)
				(arc
					(start 23.92807 -210.32216)
					(mid 23.963991 -210.307281)
					(end 23.97887 -210.27136)
				)
				(arc
					(start 23.97887 -209.86242)
					(mid 23.963991 -209.826499)
					(end 23.92807 -209.81162)
				)
				(arc
					(start 22.52853 -209.81162)
					(mid 22.492609 -209.826499)
					(end 22.47773 -209.86242)
				)
			)
		)
	)
	(zone
		(layers "In1.Cu" "In2.Cu")
		(hatch none 0.5)
		(connect_pads
			(clearance 0)
		)
		(min_thickness 0.25)
		(keepout
			(tracks not_allowed)
			(vias allowed)
			(pads allowed)
			(copperpour not_allowed)
			(footprints allowed)
		)
		(placement
			(enabled no)
			(sheetname "")
		)
		(fill yes
			(thermal_gap 0.5)
			(thermal_bridge_width 0.5)
			(island_removal_mode 0)
		)
		(polygon
			(pts
				(arc
					(start 162.162998 -270.621506)
					(mid 162.177877 -270.657427)
					(end 162.213798 -270.672306)
				)
				(arc
					(start 163.613338 -270.672306)
					(mid 163.649259 -270.657427)
					(end 163.664138 -270.621506)
				)
				(arc
					(start 163.664138 -270.212566)
					(mid 163.649259 -270.176645)
					(end 163.613338 -270.161766)
				)
				(arc
					(start 162.213798 -270.161766)
					(mid 162.177877 -270.176645)
					(end 162.162998 -270.212566)
				)
			)
		)
	)
	(zone
		(layers "In1.Cu" "In2.Cu")
		(hatch none 0.5)
		(connect_pads
			(clearance 0)
		)
		(min_thickness 0.25)
		(keepout
			(tracks not_allowed)
			(vias allowed)
			(pads allowed)
			(copperpour not_allowed)
			(footprints allowed)
		)
		(placement
			(enabled no)
			(sheetname "")
		)
		(fill yes
			(thermal_gap 0.5)
			(thermal_bridge_width 0.5)
			(island_removal_mode 0)
		)
		(polygon
			(pts
				(arc
					(start 203.32573 -288.471356)
					(mid 203.340609 -288.507277)
					(end 203.37653 -288.522156)
				)
				(arc
					(start 204.77607 -288.522156)
					(mid 204.811991 -288.507277)
					(end 204.82687 -288.471356)
				)
				(arc
					(start 204.82687 -288.062416)
					(mid 204.811991 -288.026495)
					(end 204.77607 -288.011616)
				)
				(arc
					(start 203.37653 -288.011616)
					(mid 203.340609 -288.026495)
					(end 203.32573 -288.062416)
				)
			)
		)
	)
	(zone
		(layers "In1.Cu" "In2.Cu")
		(hatch none 0.5)
		(connect_pads
			(clearance 0)
		)
		(min_thickness 0.25)
		(keepout
			(tracks not_allowed)
			(vias allowed)
			(pads allowed)
			(copperpour not_allowed)
			(footprints allowed)
		)
		(placement
			(enabled no)
			(sheetname "")
		)
		(fill yes
			(thermal_gap 0.5)
			(thermal_bridge_width 0.5)
			(island_removal_mode 0)
		)
		(polygon
			(pts
				(arc
					(start 37.56533 -210.27136)
					(mid 37.580209 -210.307281)
					(end 37.61613 -210.32216)
				)
				(arc
					(start 39.01567 -210.32216)
					(mid 39.051591 -210.307281)
					(end 39.06647 -210.27136)
				)
				(arc
					(start 39.06647 -209.86242)
					(mid 39.051591 -209.826499)
					(end 39.01567 -209.81162)
				)
				(arc
					(start 37.61613 -209.81162)
					(mid 37.580209 -209.826499)
					(end 37.56533 -209.86242)
				)
			)
		)
	)
	(zone
		(layers "In1.Cu" "In2.Cu")
		(hatch none 0.5)
		(connect_pads
			(clearance 0)
		)
		(min_thickness 0.25)
		(keepout
			(tracks not_allowed)
			(vias allowed)
			(pads allowed)
			(copperpour not_allowed)
			(footprints allowed)
		)
		(placement
			(enabled no)
			(sheetname "")
		)
		(fill yes
			(thermal_gap 0.5)
			(thermal_bridge_width 0.5)
			(island_removal_mode 0)
		)
		(polygon
			(pts
				(arc
					(start 270.417798 -279.121362)
					(mid 270.432677 -279.157283)
					(end 270.468598 -279.172162)
				)
				(arc
					(start 271.868138 -279.172162)
					(mid 271.904059 -279.157283)
					(end 271.918938 -279.121362)
				)
				(arc
					(start 271.918938 -278.712422)
					(mid 271.904059 -278.676501)
					(end 271.868138 -278.661622)
				)
				(arc
					(start 270.468598 -278.661622)
					(mid 270.432677 -278.676501)
					(end 270.417798 -278.712422)
				)
			)
		)
	)
	(zone
		(layers "In1.Cu" "In2.Cu")
		(hatch none 0.5)
		(connect_pads
			(clearance 0)
		)
		(min_thickness 0.25)
		(keepout
			(tracks not_allowed)
			(vias allowed)
			(pads allowed)
			(copperpour not_allowed)
			(footprints allowed)
		)
		(placement
			(enabled no)
			(sheetname "")
		)
		(fill yes
			(thermal_gap 0.5)
			(thermal_bridge_width 0.5)
			(island_removal_mode 0)
		)
		(polygon
			(pts
				(arc
					(start 184.794398 -203.471526)
					(mid 184.809277 -203.507447)
					(end 184.845198 -203.522326)
				)
				(arc
					(start 186.244738 -203.522326)
					(mid 186.280659 -203.507447)
					(end 186.295538 -203.471526)
				)
				(arc
					(start 186.295538 -203.062586)
					(mid 186.280659 -203.026665)
					(end 186.244738 -203.011786)
				)
				(arc
					(start 184.845198 -203.011786)
					(mid 184.809277 -203.026665)
					(end 184.794398 -203.062586)
				)
			)
		)
	)
	(zone
		(layers "In1.Cu" "In2.Cu")
		(hatch none 0.5)
		(connect_pads
			(clearance 0)
		)
		(min_thickness 0.25)
		(keepout
			(tracks not_allowed)
			(vias allowed)
			(pads allowed)
			(copperpour not_allowed)
			(footprints allowed)
		)
		(placement
			(enabled no)
			(sheetname "")
		)
		(fill yes
			(thermal_gap 0.5)
			(thermal_bridge_width 0.5)
			(island_removal_mode 0)
		)
		(polygon
			(pts
				(arc
					(start 192.338198 -234.921298)
					(mid 192.353077 -234.957219)
					(end 192.388998 -234.972098)
				)
				(arc
					(start 193.788538 -234.972098)
					(mid 193.824459 -234.957219)
					(end 193.839338 -234.921298)
				)
				(arc
					(start 193.839338 -234.512358)
					(mid 193.824459 -234.476437)
					(end 193.788538 -234.461558)
				)
				(arc
					(start 192.388998 -234.461558)
					(mid 192.353077 -234.476437)
					(end 192.338198 -234.512358)
				)
			)
		)
	)
	(zone
		(layers "In1.Cu" "In2.Cu")
		(hatch none 0.5)
		(connect_pads
			(clearance 0)
		)
		(min_thickness 0.25)
		(keepout
			(tracks not_allowed)
			(vias allowed)
			(pads allowed)
			(copperpour not_allowed)
			(footprints allowed)
		)
		(placement
			(enabled no)
			(sheetname "")
		)
		(fill yes
			(thermal_gap 0.5)
			(thermal_bridge_width 0.5)
			(island_removal_mode 0)
		)
		(polygon
			(pts
				(arc
					(start 406.002998 -264.671302)
					(mid 406.017877 -264.707223)
					(end 406.053798 -264.722102)
				)
				(arc
					(start 407.453338 -264.722102)
					(mid 407.489259 -264.707223)
					(end 407.504138 -264.671302)
				)
				(arc
					(start 407.504138 -264.262362)
					(mid 407.489259 -264.226441)
					(end 407.453338 -264.211562)
				)
				(arc
					(start 406.053798 -264.211562)
					(mid 406.017877 -264.226441)
					(end 406.002998 -264.262362)
				)
			)
		)
	)
	(zone
		(layers "In1.Cu" "In2.Cu")
		(hatch none 0.5)
		(connect_pads
			(clearance 0)
		)
		(min_thickness 0.25)
		(keepout
			(tracks not_allowed)
			(vias allowed)
			(pads allowed)
			(copperpour not_allowed)
			(footprints allowed)
		)
		(placement
			(enabled no)
			(sheetname "")
		)
		(fill yes
			(thermal_gap 0.5)
			(thermal_bridge_width 0.5)
			(island_removal_mode 0)
		)
		(polygon
			(pts
				(arc
					(start 52.65293 -230.67137)
					(mid 52.667809 -230.707291)
					(end 52.70373 -230.72217)
				)
				(arc
					(start 54.10327 -230.72217)
					(mid 54.139191 -230.707291)
					(end 54.15407 -230.67137)
				)
				(arc
					(start 54.15407 -230.26243)
					(mid 54.139191 -230.226509)
					(end 54.10327 -230.21163)
				)
				(arc
					(start 52.70373 -230.21163)
					(mid 52.667809 -230.226509)
					(end 52.65293 -230.26243)
				)
			)
		)
	)
	(zone
		(layers "In1.Cu" "In2.Cu")
		(hatch none 0.5)
		(connect_pads
			(clearance 0)
		)
		(min_thickness 0.25)
		(keepout
			(tracks not_allowed)
			(vias allowed)
			(pads allowed)
			(copperpour not_allowed)
			(footprints allowed)
		)
		(placement
			(enabled no)
			(sheetname "")
		)
		(fill yes
			(thermal_gap 0.5)
			(thermal_bridge_width 0.5)
			(island_removal_mode 0)
		)
		(polygon
			(pts
				(arc
					(start 289.605466 -283.371544)
					(mid 289.620345 -283.407465)
					(end 289.656266 -283.422344)
				)
				(arc
					(start 291.055806 -283.422344)
					(mid 291.091727 -283.407465)
					(end 291.106606 -283.371544)
				)
				(arc
					(start 291.106606 -282.962604)
					(mid 291.091727 -282.926683)
					(end 291.055806 -282.911804)
				)
				(arc
					(start 289.656266 -282.911804)
					(mid 289.620345 -282.926683)
					(end 289.605466 -282.962604)
				)
			)
		)
	)
	(zone
		(layers "In1.Cu" "In2.Cu")
		(hatch none 0.5)
		(connect_pads
			(clearance 0)
		)
		(min_thickness 0.25)
		(keepout
			(tracks not_allowed)
			(vias allowed)
			(pads allowed)
			(copperpour not_allowed)
			(footprints allowed)
		)
		(placement
			(enabled no)
			(sheetname "")
		)
		(fill yes
			(thermal_gap 0.5)
			(thermal_bridge_width 0.5)
			(island_removal_mode 0)
		)
		(polygon
			(pts
				(arc
					(start 266.974066 -217.921332)
					(mid 266.988945 -217.957253)
					(end 267.024866 -217.972132)
				)
				(arc
					(start 268.424406 -217.972132)
					(mid 268.460327 -217.957253)
					(end 268.475206 -217.921332)
				)
				(arc
					(start 268.475206 -217.512392)
					(mid 268.460327 -217.476471)
					(end 268.424406 -217.461592)
				)
				(arc
					(start 267.024866 -217.461592)
					(mid 266.988945 -217.476471)
					(end 266.974066 -217.512392)
				)
			)
		)
	)
	(zone
		(layers "In1.Cu" "In2.Cu")
		(hatch none 0.5)
		(connect_pads
			(clearance 0)
		)
		(min_thickness 0.25)
		(keepout
			(tracks not_allowed)
			(vias allowed)
			(pads allowed)
			(copperpour not_allowed)
			(footprints allowed)
		)
		(placement
			(enabled no)
			(sheetname "")
		)
		(fill yes
			(thermal_gap 0.5)
			(thermal_bridge_width 0.5)
			(island_removal_mode 0)
		)
		(polygon
			(pts
				(arc
					(start 34.121598 -206.871316)
					(mid 34.136477 -206.907237)
					(end 34.172398 -206.922116)
				)
				(arc
					(start 35.571938 -206.922116)
					(mid 35.607859 -206.907237)
					(end 35.622738 -206.871316)
				)
				(arc
					(start 35.622738 -206.462376)
					(mid 35.607859 -206.426455)
					(end 35.571938 -206.411576)
				)
				(arc
					(start 34.172398 -206.411576)
					(mid 34.136477 -206.426455)
					(end 34.121598 -206.462376)
				)
			)
		)
	)
	(zone
		(layers "In1.Cu" "In2.Cu")
		(hatch none 0.5)
		(connect_pads
			(clearance 0)
		)
		(min_thickness 0.25)
		(keepout
			(tracks not_allowed)
			(vias allowed)
			(pads allowed)
			(copperpour not_allowed)
			(footprints allowed)
		)
		(placement
			(enabled no)
			(sheetname "")
		)
		(fill yes
			(thermal_gap 0.5)
			(thermal_bridge_width 0.5)
			(island_removal_mode 0)
		)
		(polygon
			(pts
				(arc
					(start 192.338198 -217.921332)
					(mid 192.353077 -217.957253)
					(end 192.388998 -217.972132)
				)
				(arc
					(start 193.788538 -217.972132)
					(mid 193.824459 -217.957253)
					(end 193.839338 -217.921332)
				)
				(arc
					(start 193.839338 -217.512392)
					(mid 193.824459 -217.476471)
					(end 193.788538 -217.461592)
				)
				(arc
					(start 192.388998 -217.461592)
					(mid 192.353077 -217.476471)
					(end 192.338198 -217.512392)
				)
			)
		)
	)
	(zone
		(layers "In1.Cu" "In2.Cu")
		(hatch none 0.5)
		(connect_pads
			(clearance 0)
		)
		(min_thickness 0.25)
		(keepout
			(tracks not_allowed)
			(vias allowed)
			(pads allowed)
			(copperpour not_allowed)
			(footprints allowed)
		)
		(placement
			(enabled no)
			(sheetname "")
		)
		(fill yes
			(thermal_gap 0.5)
			(thermal_bridge_width 0.5)
			(island_removal_mode 0)
		)
		(polygon
			(pts
				(arc
					(start 304.693066 -245.12143)
					(mid 304.707945 -245.157351)
					(end 304.743866 -245.17223)
				)
				(arc
					(start 306.143406 -245.17223)
					(mid 306.179327 -245.157351)
					(end 306.194206 -245.12143)
				)
				(arc
					(start 306.194206 -244.71249)
					(mid 306.179327 -244.676569)
					(end 306.143406 -244.66169)
				)
				(arc
					(start 304.743866 -244.66169)
					(mid 304.707945 -244.676569)
					(end 304.693066 -244.71249)
				)
			)
		)
	)
	(zone
		(layers "In1.Cu" "In2.Cu")
		(hatch none 0.5)
		(connect_pads
			(clearance 0)
		)
		(min_thickness 0.25)
		(keepout
			(tracks not_allowed)
			(vias allowed)
			(pads allowed)
			(copperpour not_allowed)
			(footprints allowed)
		)
		(placement
			(enabled no)
			(sheetname "")
		)
		(fill yes
			(thermal_gap 0.5)
			(thermal_bridge_width 0.5)
			(island_removal_mode 0)
		)
		(polygon
			(pts
				(arc
					(start 255.330198 -302.921416)
					(mid 255.345077 -302.957337)
					(end 255.380998 -302.972216)
				)
				(arc
					(start 256.780538 -302.972216)
					(mid 256.816459 -302.957337)
					(end 256.831338 -302.921416)
				)
				(arc
					(start 256.831338 -302.512476)
					(mid 256.816459 -302.476555)
					(end 256.780538 -302.461676)
				)
				(arc
					(start 255.380998 -302.461676)
					(mid 255.345077 -302.476555)
					(end 255.330198 -302.512476)
				)
			)
		)
	)
	(zone
		(layers "In1.Cu" "In2.Cu")
		(hatch none 0.5)
		(connect_pads
			(clearance 0)
		)
		(min_thickness 0.25)
		(keepout
			(tracks not_allowed)
			(vias allowed)
			(pads allowed)
			(copperpour not_allowed)
			(footprints allowed)
		)
		(placement
			(enabled no)
			(sheetname "")
		)
		(fill yes
			(thermal_gap 0.5)
			(thermal_bridge_width 0.5)
			(island_removal_mode 0)
		)
		(polygon
			(pts
				(arc
					(start 406.002998 -244.271292)
					(mid 406.017877 -244.307213)
					(end 406.053798 -244.322092)
				)
				(arc
					(start 407.453338 -244.322092)
					(mid 407.489259 -244.307213)
					(end 407.504138 -244.271292)
				)
				(arc
					(start 407.504138 -243.862352)
					(mid 407.489259 -243.826431)
					(end 407.453338 -243.811552)
				)
				(arc
					(start 406.053798 -243.811552)
					(mid 406.017877 -243.826431)
					(end 406.002998 -243.862352)
				)
			)
		)
	)
	(zone
		(layers "In1.Cu" "In2.Cu")
		(hatch none 0.5)
		(connect_pads
			(clearance 0)
		)
		(min_thickness 0.25)
		(keepout
			(tracks not_allowed)
			(vias allowed)
			(pads allowed)
			(copperpour not_allowed)
			(footprints allowed)
		)
		(placement
			(enabled no)
			(sheetname "")
		)
		(fill yes
			(thermal_gap 0.5)
			(thermal_bridge_width 0.5)
			(island_removal_mode 0)
		)
		(polygon
			(pts
				(arc
					(start 447.822066 -302.921416)
					(mid 447.836945 -302.957337)
					(end 447.872866 -302.972216)
				)
				(arc
					(start 449.272406 -302.972216)
					(mid 449.308327 -302.957337)
					(end 449.323206 -302.921416)
				)
				(arc
					(start 449.323206 -302.512476)
					(mid 449.308327 -302.476555)
					(end 449.272406 -302.461676)
				)
				(arc
					(start 447.872866 -302.461676)
					(mid 447.836945 -302.476555)
					(end 447.822066 -302.512476)
				)
			)
		)
	)
	(zone
		(layers "In1.Cu" "In2.Cu")
		(hatch none 0.5)
		(connect_pads
			(clearance 0)
		)
		(min_thickness 0.25)
		(keepout
			(tracks not_allowed)
			(vias allowed)
			(pads allowed)
			(copperpour not_allowed)
			(footprints allowed)
		)
		(placement
			(enabled no)
			(sheetname "")
		)
		(fill yes
			(thermal_gap 0.5)
			(thermal_bridge_width 0.5)
			(island_removal_mode 0)
		)
		(polygon
			(pts
				(arc
					(start 165.60673 -264.671302)
					(mid 165.621609 -264.707223)
					(end 165.65753 -264.722102)
				)
				(arc
					(start 167.05707 -264.722102)
					(mid 167.092991 -264.707223)
					(end 167.10787 -264.671302)
				)
				(arc
					(start 167.10787 -264.262362)
					(mid 167.092991 -264.226441)
					(end 167.05707 -264.211562)
				)
				(arc
					(start 165.65753 -264.211562)
					(mid 165.621609 -264.226441)
					(end 165.60673 -264.262362)
				)
			)
		)
	)
	(zone
		(layers "In1.Cu" "In2.Cu")
		(hatch none 0.5)
		(connect_pads
			(clearance 0)
		)
		(min_thickness 0.25)
		(keepout
			(tracks not_allowed)
			(vias allowed)
			(pads allowed)
			(copperpour not_allowed)
			(footprints allowed)
		)
		(placement
			(enabled no)
			(sheetname "")
		)
		(fill yes
			(thermal_gap 0.5)
			(thermal_bridge_width 0.5)
			(island_removal_mode 0)
		)
		(polygon
			(pts
				(arc
					(start 274.517866 -203.471526)
					(mid 274.532745 -203.507447)
					(end 274.568666 -203.522326)
				)
				(arc
					(start 275.968206 -203.522326)
					(mid 276.004127 -203.507447)
					(end 276.019006 -203.471526)
				)
				(arc
					(start 276.019006 -203.062586)
					(mid 276.004127 -203.026665)
					(end 275.968206 -203.011786)
				)
				(arc
					(start 274.568666 -203.011786)
					(mid 274.532745 -203.026665)
					(end 274.517866 -203.062586)
				)
			)
		)
	)
	(zone
		(layers "In1.Cu" "In2.Cu")
		(hatch none 0.5)
		(connect_pads
			(clearance 0)
		)
		(min_thickness 0.25)
		(keepout
			(tracks not_allowed)
			(vias allowed)
			(pads allowed)
			(copperpour not_allowed)
			(footprints allowed)
		)
		(placement
			(enabled no)
			(sheetname "")
		)
		(fill yes
			(thermal_gap 0.5)
			(thermal_bridge_width 0.5)
			(island_removal_mode 0)
		)
		(polygon
			(pts
				(arc
					(start 14.93393 -301.221394)
					(mid 14.948809 -301.257315)
					(end 14.98473 -301.272194)
				)
				(arc
					(start 16.38427 -301.272194)
					(mid 16.420191 -301.257315)
					(end 16.43507 -301.221394)
				)
				(arc
					(start 16.43507 -300.812454)
					(mid 16.420191 -300.776533)
					(end 16.38427 -300.761654)
				)
				(arc
					(start 14.98473 -300.761654)
					(mid 14.948809 -300.776533)
					(end 14.93393 -300.812454)
				)
			)
		)
	)
	(zone
		(layers "In1.Cu" "In2.Cu")
		(hatch none 0.5)
		(connect_pads
			(clearance 0)
		)
		(min_thickness 0.25)
		(keepout
			(tracks not_allowed)
			(vias allowed)
			(pads allowed)
			(copperpour not_allowed)
			(footprints allowed)
		)
		(placement
			(enabled no)
			(sheetname "")
		)
		(fill yes
			(thermal_gap 0.5)
			(thermal_bridge_width 0.5)
			(island_removal_mode 0)
		)
		(polygon
			(pts
				(arc
					(start 199.881998 -237.471458)
					(mid 199.896877 -237.507379)
					(end 199.932798 -237.522258)
				)
				(arc
					(start 201.332338 -237.522258)
					(mid 201.368259 -237.507379)
					(end 201.383138 -237.471458)
				)
				(arc
					(start 201.383138 -237.062518)
					(mid 201.368259 -237.026597)
					(end 201.332338 -237.011718)
				)
				(arc
					(start 199.932798 -237.011718)
					(mid 199.896877 -237.026597)
					(end 199.881998 -237.062518)
				)
			)
		)
	)
	(zone
		(layers "In1.Cu" "In2.Cu")
		(hatch none 0.5)
		(connect_pads
			(clearance 0)
		)
		(min_thickness 0.25)
		(keepout
			(tracks not_allowed)
			(vias allowed)
			(pads allowed)
			(copperpour not_allowed)
			(footprints allowed)
		)
		(placement
			(enabled no)
			(sheetname "")
		)
		(fill yes
			(thermal_gap 0.5)
			(thermal_bridge_width 0.5)
			(island_removal_mode 0)
		)
		(polygon
			(pts
				(arc
					(start 259.430266 -214.521542)
					(mid 259.445145 -214.557463)
					(end 259.481066 -214.572342)
				)
				(arc
					(start 260.880606 -214.572342)
					(mid 260.916527 -214.557463)
					(end 260.931406 -214.521542)
				)
				(arc
					(start 260.931406 -214.112602)
					(mid 260.916527 -214.076681)
					(end 260.880606 -214.061802)
				)
				(arc
					(start 259.481066 -214.061802)
					(mid 259.445145 -214.076681)
					(end 259.430266 -214.112602)
				)
			)
		)
	)
	(zone
		(layers "In1.Cu" "In2.Cu")
		(hatch none 0.5)
		(connect_pads
			(clearance 0)
		)
		(min_thickness 0.25)
		(keepout
			(tracks not_allowed)
			(vias allowed)
			(pads allowed)
			(copperpour not_allowed)
			(footprints allowed)
		)
		(placement
			(enabled no)
			(sheetname "")
		)
		(fill yes
			(thermal_gap 0.5)
			(thermal_bridge_width 0.5)
			(island_removal_mode 0)
		)
		(polygon
			(pts
				(arc
					(start 34.121598 -208.571338)
					(mid 34.136477 -208.607259)
					(end 34.172398 -208.622138)
				)
				(arc
					(start 35.571938 -208.622138)
					(mid 35.607859 -208.607259)
					(end 35.622738 -208.571338)
				)
				(arc
					(start 35.622738 -208.162398)
					(mid 35.607859 -208.126477)
					(end 35.571938 -208.111598)
				)
				(arc
					(start 34.172398 -208.111598)
					(mid 34.136477 -208.126477)
					(end 34.121598 -208.162398)
				)
			)
		)
	)
	(zone
		(layers "In1.Cu" "In2.Cu")
		(hatch none 0.5)
		(connect_pads
			(clearance 0)
		)
		(min_thickness 0.25)
		(keepout
			(tracks not_allowed)
			(vias allowed)
			(pads allowed)
			(copperpour not_allowed)
			(footprints allowed)
		)
		(placement
			(enabled no)
			(sheetname "")
		)
		(fill yes
			(thermal_gap 0.5)
			(thermal_bridge_width 0.5)
			(island_removal_mode 0)
		)
		(polygon
			(pts
				(arc
					(start 192.338198 -209.421476)
					(mid 192.353077 -209.457397)
					(end 192.388998 -209.472276)
				)
				(arc
					(start 193.788538 -209.472276)
					(mid 193.824459 -209.457397)
					(end 193.839338 -209.421476)
				)
				(arc
					(start 193.839338 -209.012536)
					(mid 193.824459 -208.976615)
					(end 193.788538 -208.961736)
				)
				(arc
					(start 192.388998 -208.961736)
					(mid 192.353077 -208.976615)
					(end 192.338198 -209.012536)
				)
			)
		)
	)
	(zone
		(layers "In1.Cu" "In2.Cu")
		(hatch none 0.5)
		(connect_pads
			(clearance 0)
		)
		(min_thickness 0.25)
		(keepout
			(tracks not_allowed)
			(vias allowed)
			(pads allowed)
			(copperpour not_allowed)
			(footprints allowed)
		)
		(placement
			(enabled no)
			(sheetname "")
		)
		(fill yes
			(thermal_gap 0.5)
			(thermal_bridge_width 0.5)
			(island_removal_mode 0)
		)
		(polygon
			(pts
				(arc
					(start 270.417798 -282.521406)
					(mid 270.432677 -282.557327)
					(end 270.468598 -282.572206)
				)
				(arc
					(start 271.868138 -282.572206)
					(mid 271.904059 -282.557327)
					(end 271.918938 -282.521406)
				)
				(arc
					(start 271.918938 -282.112466)
					(mid 271.904059 -282.076545)
					(end 271.868138 -282.061666)
				)
				(arc
					(start 270.468598 -282.061666)
					(mid 270.432677 -282.076545)
					(end 270.417798 -282.112466)
				)
			)
		)
	)
	(zone
		(layers "In1.Cu" "In2.Cu")
		(hatch none 0.5)
		(connect_pads
			(clearance 0)
		)
		(min_thickness 0.25)
		(keepout
			(tracks not_allowed)
			(vias allowed)
			(pads allowed)
			(copperpour not_allowed)
			(footprints allowed)
		)
		(placement
			(enabled no)
			(sheetname "")
		)
		(fill yes
			(thermal_gap 0.5)
			(thermal_bridge_width 0.5)
			(island_removal_mode 0)
		)
		(polygon
			(pts
				(arc
					(start 203.32573 -312.27141)
					(mid 203.340609 -312.307331)
					(end 203.37653 -312.32221)
				)
				(arc
					(start 204.77607 -312.32221)
					(mid 204.811991 -312.307331)
					(end 204.82687 -312.27141)
				)
				(arc
					(start 204.82687 -311.86247)
					(mid 204.811991 -311.826549)
					(end 204.77607 -311.81167)
				)
				(arc
					(start 203.37653 -311.81167)
					(mid 203.340609 -311.826549)
					(end 203.32573 -311.86247)
				)
			)
		)
	)
	(zone
		(layers "In1.Cu" "In2.Cu")
		(hatch none 0.5)
		(connect_pads
			(clearance 0)
		)
		(min_thickness 0.25)
		(keepout
			(tracks not_allowed)
			(vias allowed)
			(pads allowed)
			(copperpour not_allowed)
			(footprints allowed)
		)
		(placement
			(enabled no)
			(sheetname "")
		)
		(fill yes
			(thermal_gap 0.5)
			(thermal_bridge_width 0.5)
			(island_removal_mode 0)
		)
		(polygon
			(pts
				(arc
					(start 413.546798 -204.32141)
					(mid 413.561677 -204.357331)
					(end 413.597598 -204.37221)
				)
				(arc
					(start 414.997138 -204.37221)
					(mid 415.033059 -204.357331)
					(end 415.047938 -204.32141)
				)
				(arc
					(start 415.047938 -203.91247)
					(mid 415.033059 -203.876549)
					(end 414.997138 -203.86167)
				)
				(arc
					(start 413.597598 -203.86167)
					(mid 413.561677 -203.876549)
					(end 413.546798 -203.91247)
				)
			)
		)
	)
	(zone
		(layers "In1.Cu" "In2.Cu")
		(hatch none 0.5)
		(connect_pads
			(clearance 0)
		)
		(min_thickness 0.25)
		(keepout
			(tracks not_allowed)
			(vias allowed)
			(pads allowed)
			(copperpour not_allowed)
			(footprints allowed)
		)
		(placement
			(enabled no)
			(sheetname "")
		)
		(fill yes
			(thermal_gap 0.5)
			(thermal_bridge_width 0.5)
			(island_removal_mode 0)
		)
		(polygon
			(pts
				(arc
					(start 447.822066 -296.971466)
					(mid 447.836945 -297.007387)
					(end 447.872866 -297.022266)
				)
				(arc
					(start 449.272406 -297.022266)
					(mid 449.308327 -297.007387)
					(end 449.323206 -296.971466)
				)
				(arc
					(start 449.323206 -296.562526)
					(mid 449.308327 -296.526605)
					(end 449.272406 -296.511726)
				)
				(arc
					(start 447.872866 -296.511726)
					(mid 447.836945 -296.526605)
					(end 447.822066 -296.562526)
				)
			)
		)
	)
	(zone
		(layers "In1.Cu" "In2.Cu")
		(hatch none 0.5)
		(connect_pads
			(clearance 0)
		)
		(min_thickness 0.25)
		(keepout
			(tracks not_allowed)
			(vias allowed)
			(pads allowed)
			(copperpour not_allowed)
			(footprints allowed)
		)
		(placement
			(enabled no)
			(sheetname "")
		)
		(fill yes
			(thermal_gap 0.5)
			(thermal_bridge_width 0.5)
			(island_removal_mode 0)
		)
		(polygon
			(pts
				(arc
					(start 255.330198 -268.071346)
					(mid 255.345077 -268.107267)
					(end 255.380998 -268.122146)
				)
				(arc
					(start 256.780538 -268.122146)
					(mid 256.816459 -268.107267)
					(end 256.831338 -268.071346)
				)
				(arc
					(start 256.831338 -267.662406)
					(mid 256.816459 -267.626485)
					(end 256.780538 -267.611606)
				)
				(arc
					(start 255.380998 -267.611606)
					(mid 255.345077 -267.626485)
					(end 255.330198 -267.662406)
				)
			)
		)
	)
	(zone
		(layers "In1.Cu" "In2.Cu")
		(hatch none 0.5)
		(connect_pads
			(clearance 0)
		)
		(min_thickness 0.25)
		(keepout
			(tracks not_allowed)
			(vias allowed)
			(pads allowed)
			(copperpour not_allowed)
			(footprints allowed)
		)
		(placement
			(enabled no)
			(sheetname "")
		)
		(fill yes
			(thermal_gap 0.5)
			(thermal_bridge_width 0.5)
			(island_removal_mode 0)
		)
		(polygon
			(pts
				(arc
					(start 173.15053 -207.721454)
					(mid 173.165409 -207.757375)
					(end 173.20133 -207.772254)
				)
				(arc
					(start 174.60087 -207.772254)
					(mid 174.636791 -207.757375)
					(end 174.65167 -207.721454)
				)
				(arc
					(start 174.65167 -207.312514)
					(mid 174.636791 -207.276593)
					(end 174.60087 -207.261714)
				)
				(arc
					(start 173.20133 -207.261714)
					(mid 173.165409 -207.276593)
					(end 173.15053 -207.312514)
				)
			)
		)
	)
	(zone
		(layers "In1.Cu" "In2.Cu")
		(hatch none 0.5)
		(connect_pads
			(clearance 0)
		)
		(min_thickness 0.25)
		(keepout
			(tracks not_allowed)
			(vias allowed)
			(pads allowed)
			(copperpour not_allowed)
			(footprints allowed)
		)
		(placement
			(enabled no)
			(sheetname "")
		)
		(fill yes
			(thermal_gap 0.5)
			(thermal_bridge_width 0.5)
			(island_removal_mode 0)
		)
		(polygon
			(pts
				(arc
					(start 214.969598 -262.121396)
					(mid 214.984477 -262.157317)
					(end 215.020398 -262.172196)
				)
				(arc
					(start 216.419938 -262.172196)
					(mid 216.455859 -262.157317)
					(end 216.470738 -262.121396)
				)
				(arc
					(start 216.470738 -261.712456)
					(mid 216.455859 -261.676535)
					(end 216.419938 -261.661656)
				)
				(arc
					(start 215.020398 -261.661656)
					(mid 214.984477 -261.676535)
					(end 214.969598 -261.712456)
				)
			)
		)
	)
	(zone
		(layers "In1.Cu" "In2.Cu")
		(hatch none 0.5)
		(connect_pads
			(clearance 0)
		)
		(min_thickness 0.25)
		(keepout
			(tracks not_allowed)
			(vias allowed)
			(pads allowed)
			(copperpour not_allowed)
			(footprints allowed)
		)
		(placement
			(enabled no)
			(sheetname "")
		)
		(fill yes
			(thermal_gap 0.5)
			(thermal_bridge_width 0.5)
			(island_removal_mode 0)
		)
		(polygon
			(pts
				(arc
					(start 432.734466 -300.37151)
					(mid 432.749345 -300.407431)
					(end 432.785266 -300.42231)
				)
				(arc
					(start 434.184806 -300.42231)
					(mid 434.220727 -300.407431)
					(end 434.235606 -300.37151)
				)
				(arc
					(start 434.235606 -299.96257)
					(mid 434.220727 -299.926649)
					(end 434.184806 -299.91177)
				)
				(arc
					(start 432.785266 -299.91177)
					(mid 432.749345 -299.926649)
					(end 432.734466 -299.96257)
				)
			)
		)
	)
	(zone
		(layers "In1.Cu" "In2.Cu")
		(hatch none 0.5)
		(connect_pads
			(clearance 0)
		)
		(min_thickness 0.25)
		(keepout
			(tracks not_allowed)
			(vias allowed)
			(pads allowed)
			(copperpour not_allowed)
			(footprints allowed)
		)
		(placement
			(enabled no)
			(sheetname "")
		)
		(fill yes
			(thermal_gap 0.5)
			(thermal_bridge_width 0.5)
			(island_removal_mode 0)
		)
		(polygon
			(pts
				(arc
					(start 162.162998 -308.021482)
					(mid 162.177877 -308.057403)
					(end 162.213798 -308.072282)
				)
				(arc
					(start 163.613338 -308.072282)
					(mid 163.649259 -308.057403)
					(end 163.664138 -308.021482)
				)
				(arc
					(start 163.664138 -307.612542)
					(mid 163.649259 -307.576621)
					(end 163.613338 -307.561742)
				)
				(arc
					(start 162.213798 -307.561742)
					(mid 162.177877 -307.576621)
					(end 162.162998 -307.612542)
				)
			)
		)
	)
	(zone
		(layers "In1.Cu" "In2.Cu")
		(hatch none 0.5)
		(connect_pads
			(clearance 0)
		)
		(min_thickness 0.25)
		(keepout
			(tracks not_allowed)
			(vias allowed)
			(pads allowed)
			(copperpour not_allowed)
			(footprints allowed)
		)
		(placement
			(enabled no)
			(sheetname "")
		)
		(fill yes
			(thermal_gap 0.5)
			(thermal_bridge_width 0.5)
			(island_removal_mode 0)
		)
		(polygon
			(pts
				(arc
					(start 259.430266 -203.471526)
					(mid 259.445145 -203.507447)
					(end 259.481066 -203.522326)
				)
				(arc
					(start 260.880606 -203.522326)
					(mid 260.916527 -203.507447)
					(end 260.931406 -203.471526)
				)
				(arc
					(start 260.931406 -203.062586)
					(mid 260.916527 -203.026665)
					(end 260.880606 -203.011786)
				)
				(arc
					(start 259.481066 -203.011786)
					(mid 259.445145 -203.026665)
					(end 259.430266 -203.062586)
				)
			)
		)
	)
	(zone
		(layers "In1.Cu" "In2.Cu")
		(hatch none 0.5)
		(connect_pads
			(clearance 0)
		)
		(min_thickness 0.25)
		(keepout
			(tracks not_allowed)
			(vias allowed)
			(pads allowed)
			(copperpour not_allowed)
			(footprints allowed)
		)
		(placement
			(enabled no)
			(sheetname "")
		)
		(fill yes
			(thermal_gap 0.5)
			(thermal_bridge_width 0.5)
			(island_removal_mode 0)
		)
		(polygon
			(pts
				(arc
					(start 443.721998 -285.071312)
					(mid 443.736877 -285.107233)
					(end 443.772798 -285.122112)
				)
				(arc
					(start 445.172338 -285.122112)
					(mid 445.208259 -285.107233)
					(end 445.223138 -285.071312)
				)
				(arc
					(start 445.223138 -284.662372)
					(mid 445.208259 -284.626451)
					(end 445.172338 -284.611572)
				)
				(arc
					(start 443.772798 -284.611572)
					(mid 443.736877 -284.626451)
					(end 443.721998 -284.662372)
				)
			)
		)
	)
	(zone
		(layers "In1.Cu" "In2.Cu")
		(hatch none 0.5)
		(connect_pads
			(clearance 0)
		)
		(min_thickness 0.25)
		(keepout
			(tracks not_allowed)
			(vias allowed)
			(pads allowed)
			(copperpour not_allowed)
			(footprints allowed)
		)
		(placement
			(enabled no)
			(sheetname "")
		)
		(fill yes
			(thermal_gap 0.5)
			(thermal_bridge_width 0.5)
			(island_removal_mode 0)
		)
		(polygon
			(pts
				(arc
					(start 406.002998 -288.471356)
					(mid 406.017877 -288.507277)
					(end 406.053798 -288.522156)
				)
				(arc
					(start 407.453338 -288.522156)
					(mid 407.489259 -288.507277)
					(end 407.504138 -288.471356)
				)
				(arc
					(start 407.504138 -288.062416)
					(mid 407.489259 -288.026495)
					(end 407.453338 -288.011616)
				)
				(arc
					(start 406.053798 -288.011616)
					(mid 406.017877 -288.026495)
					(end 406.002998 -288.062416)
				)
			)
		)
	)
	(zone
		(layers "In1.Cu" "In2.Cu")
		(hatch none 0.5)
		(connect_pads
			(clearance 0)
		)
		(min_thickness 0.25)
		(keepout
			(tracks not_allowed)
			(vias allowed)
			(pads allowed)
			(copperpour not_allowed)
			(footprints allowed)
		)
		(placement
			(enabled no)
			(sheetname "")
		)
		(fill yes
			(thermal_gap 0.5)
			(thermal_bridge_width 0.5)
			(island_removal_mode 0)
		)
		(polygon
			(pts
				(arc
					(start 26.577798 -279.9715)
					(mid 26.592677 -280.007421)
					(end 26.628598 -280.0223)
				)
				(arc
					(start 28.028138 -280.0223)
					(mid 28.064059 -280.007421)
					(end 28.078938 -279.9715)
				)
				(arc
					(start 28.078938 -279.56256)
					(mid 28.064059 -279.526639)
					(end 28.028138 -279.51176)
				)
				(arc
					(start 26.628598 -279.51176)
					(mid 26.592677 -279.526639)
					(end 26.577798 -279.56256)
				)
			)
		)
	)
	(zone
		(layers "In1.Cu" "In2.Cu")
		(hatch none 0.5)
		(connect_pads
			(clearance 0)
		)
		(min_thickness 0.25)
		(keepout
			(tracks not_allowed)
			(vias allowed)
			(pads allowed)
			(copperpour not_allowed)
			(footprints allowed)
		)
		(placement
			(enabled no)
			(sheetname "")
		)
		(fill yes
			(thermal_gap 0.5)
			(thermal_bridge_width 0.5)
			(island_removal_mode 0)
		)
		(polygon
			(pts
				(arc
					(start 180.69433 -219.621354)
					(mid 180.709209 -219.657275)
					(end 180.74513 -219.672154)
				)
				(arc
					(start 182.14467 -219.672154)
					(mid 182.180591 -219.657275)
					(end 182.19547 -219.621354)
				)
				(arc
					(start 182.19547 -219.212414)
					(mid 182.180591 -219.176493)
					(end 182.14467 -219.161614)
				)
				(arc
					(start 180.74513 -219.161614)
					(mid 180.709209 -219.176493)
					(end 180.69433 -219.212414)
				)
			)
		)
	)
	(zone
		(layers "In1.Cu" "In2.Cu")
		(hatch none 0.5)
		(connect_pads
			(clearance 0)
		)
		(min_thickness 0.25)
		(keepout
			(tracks not_allowed)
			(vias allowed)
			(pads allowed)
			(copperpour not_allowed)
			(footprints allowed)
		)
		(placement
			(enabled no)
			(sheetname "")
		)
		(fill yes
			(thermal_gap 0.5)
			(thermal_bridge_width 0.5)
			(island_removal_mode 0)
		)
		(polygon
			(pts
				(arc
					(start 60.19673 -237.471458)
					(mid 60.211609 -237.507379)
					(end 60.24753 -237.522258)
				)
				(arc
					(start 61.64707 -237.522258)
					(mid 61.682991 -237.507379)
					(end 61.69787 -237.471458)
				)
				(arc
					(start 61.69787 -237.062518)
					(mid 61.682991 -237.026597)
					(end 61.64707 -237.011718)
				)
				(arc
					(start 60.24753 -237.011718)
					(mid 60.211609 -237.026597)
					(end 60.19673 -237.062518)
				)
			)
		)
	)
	(zone
		(layers "In1.Cu" "In2.Cu")
		(hatch none 0.5)
		(connect_pads
			(clearance 0)
		)
		(min_thickness 0.25)
		(keepout
			(tracks not_allowed)
			(vias allowed)
			(pads allowed)
			(copperpour not_allowed)
			(footprints allowed)
		)
		(placement
			(enabled no)
			(sheetname "")
		)
		(fill yes
			(thermal_gap 0.5)
			(thermal_bridge_width 0.5)
			(island_removal_mode 0)
		)
		(polygon
			(pts
				(arc
					(start 274.517866 -276.571456)
					(mid 274.532745 -276.607377)
					(end 274.568666 -276.622256)
				)
				(arc
					(start 275.968206 -276.622256)
					(mid 276.004127 -276.607377)
					(end 276.019006 -276.571456)
				)
				(arc
					(start 276.019006 -276.162516)
					(mid 276.004127 -276.126595)
					(end 275.968206 -276.111716)
				)
				(arc
					(start 274.568666 -276.111716)
					(mid 274.532745 -276.126595)
					(end 274.517866 -276.162516)
				)
			)
		)
	)
	(zone
		(layers "In1.Cu" "In2.Cu")
		(hatch none 0.5)
		(connect_pads
			(clearance 0)
		)
		(min_thickness 0.25)
		(keepout
			(tracks not_allowed)
			(vias allowed)
			(pads allowed)
			(copperpour not_allowed)
			(footprints allowed)
		)
		(placement
			(enabled no)
			(sheetname "")
		)
		(fill yes
			(thermal_gap 0.5)
			(thermal_bridge_width 0.5)
			(island_removal_mode 0)
		)
		(polygon
			(pts
				(arc
					(start 458.809598 -261.271512)
					(mid 458.824477 -261.307433)
					(end 458.860398 -261.322312)
				)
				(arc
					(start 460.259938 -261.322312)
					(mid 460.295859 -261.307433)
					(end 460.310738 -261.271512)
				)
				(arc
					(start 460.310738 -260.862572)
					(mid 460.295859 -260.826651)
					(end 460.259938 -260.811772)
				)
				(arc
					(start 458.860398 -260.811772)
					(mid 458.824477 -260.826651)
					(end 458.809598 -260.862572)
				)
			)
		)
	)
	(zone
		(layers "In1.Cu" "In2.Cu")
		(hatch none 0.5)
		(connect_pads
			(clearance 0)
		)
		(min_thickness 0.25)
		(keepout
			(tracks not_allowed)
			(vias allowed)
			(pads allowed)
			(copperpour not_allowed)
			(footprints allowed)
		)
		(placement
			(enabled no)
			(sheetname "")
		)
		(fill yes
			(thermal_gap 0.5)
			(thermal_bridge_width 0.5)
			(island_removal_mode 0)
		)
		(polygon
			(pts
				(arc
					(start 158.06293 -274.871434)
					(mid 158.077809 -274.907355)
					(end 158.11373 -274.922234)
				)
				(arc
					(start 159.51327 -274.922234)
					(mid 159.549191 -274.907355)
					(end 159.56407 -274.871434)
				)
				(arc
					(start 159.56407 -274.462494)
					(mid 159.549191 -274.426573)
					(end 159.51327 -274.411694)
				)
				(arc
					(start 158.11373 -274.411694)
					(mid 158.077809 -274.426573)
					(end 158.06293 -274.462494)
				)
			)
		)
	)
	(zone
		(layers "In1.Cu" "In2.Cu")
		(hatch none 0.5)
		(connect_pads
			(clearance 0)
		)
		(min_thickness 0.25)
		(keepout
			(tracks not_allowed)
			(vias allowed)
			(pads allowed)
			(copperpour not_allowed)
			(footprints allowed)
		)
		(placement
			(enabled no)
			(sheetname "")
		)
		(fill yes
			(thermal_gap 0.5)
			(thermal_bridge_width 0.5)
			(island_removal_mode 0)
		)
		(polygon
			(pts
				(arc
					(start 413.546798 -269.771368)
					(mid 413.561677 -269.807289)
					(end 413.597598 -269.822168)
				)
				(arc
					(start 414.997138 -269.822168)
					(mid 415.033059 -269.807289)
					(end 415.047938 -269.771368)
				)
				(arc
					(start 415.047938 -269.362428)
					(mid 415.033059 -269.326507)
					(end 414.997138 -269.311628)
				)
				(arc
					(start 413.597598 -269.311628)
					(mid 413.561677 -269.326507)
					(end 413.546798 -269.362428)
				)
			)
		)
	)
	(zone
		(layers "In1.Cu" "In2.Cu")
		(hatch none 0.5)
		(connect_pads
			(clearance 0)
		)
		(min_thickness 0.25)
		(keepout
			(tracks not_allowed)
			(vias allowed)
			(pads allowed)
			(copperpour not_allowed)
			(footprints allowed)
		)
		(placement
			(enabled no)
			(sheetname "")
		)
		(fill yes
			(thermal_gap 0.5)
			(thermal_bridge_width 0.5)
			(island_removal_mode 0)
		)
		(polygon
			(pts
				(arc
					(start 173.15053 -307.171344)
					(mid 173.165409 -307.207265)
					(end 173.20133 -307.222144)
				)
				(arc
					(start 174.60087 -307.222144)
					(mid 174.636791 -307.207265)
					(end 174.65167 -307.171344)
				)
				(arc
					(start 174.65167 -306.762404)
					(mid 174.636791 -306.726483)
					(end 174.60087 -306.711604)
				)
				(arc
					(start 173.20133 -306.711604)
					(mid 173.165409 -306.726483)
					(end 173.15053 -306.762404)
				)
			)
		)
	)
	(zone
		(layers "In1.Cu" "In2.Cu")
		(hatch none 0.5)
		(connect_pads
			(clearance 0)
		)
		(min_thickness 0.25)
		(keepout
			(tracks not_allowed)
			(vias allowed)
			(pads allowed)
			(copperpour not_allowed)
			(footprints allowed)
		)
		(placement
			(enabled no)
			(sheetname "")
		)
		(fill yes
			(thermal_gap 0.5)
			(thermal_bridge_width 0.5)
			(island_removal_mode 0)
		)
		(polygon
			(pts
				(arc
					(start 274.517866 -298.671488)
					(mid 274.532745 -298.707409)
					(end 274.568666 -298.722288)
				)
				(arc
					(start 275.968206 -298.722288)
					(mid 276.004127 -298.707409)
					(end 276.019006 -298.671488)
				)
				(arc
					(start 276.019006 -298.262548)
					(mid 276.004127 -298.226627)
					(end 275.968206 -298.211748)
				)
				(arc
					(start 274.568666 -298.211748)
					(mid 274.532745 -298.226627)
					(end 274.517866 -298.262548)
				)
			)
		)
	)
	(zone
		(layers "In1.Cu" "In2.Cu")
		(hatch none 0.5)
		(connect_pads
			(clearance 0)
		)
		(min_thickness 0.25)
		(keepout
			(tracks not_allowed)
			(vias allowed)
			(pads allowed)
			(copperpour not_allowed)
			(footprints allowed)
		)
		(placement
			(enabled no)
			(sheetname "")
		)
		(fill yes
			(thermal_gap 0.5)
			(thermal_bridge_width 0.5)
			(island_removal_mode 0)
		)
		(polygon
			(pts
				(arc
					(start 184.794398 -208.571338)
					(mid 184.809277 -208.607259)
					(end 184.845198 -208.622138)
				)
				(arc
					(start 186.244738 -208.622138)
					(mid 186.280659 -208.607259)
					(end 186.295538 -208.571338)
				)
				(arc
					(start 186.295538 -208.162398)
					(mid 186.280659 -208.126477)
					(end 186.244738 -208.111598)
				)
				(arc
					(start 184.845198 -208.111598)
					(mid 184.809277 -208.126477)
					(end 184.794398 -208.162398)
				)
			)
		)
	)
	(zone
		(layers "In1.Cu" "In2.Cu")
		(hatch none 0.5)
		(connect_pads
			(clearance 0)
		)
		(min_thickness 0.25)
		(keepout
			(tracks not_allowed)
			(vias allowed)
			(pads allowed)
			(copperpour not_allowed)
			(footprints allowed)
		)
		(placement
			(enabled no)
			(sheetname "")
		)
		(fill yes
			(thermal_gap 0.5)
			(thermal_bridge_width 0.5)
			(island_removal_mode 0)
		)
		(polygon
			(pts
				(arc
					(start 455.365866 -227.271326)
					(mid 455.380745 -227.307247)
					(end 455.416666 -227.322126)
				)
				(arc
					(start 456.816206 -227.322126)
					(mid 456.852127 -227.307247)
					(end 456.867006 -227.271326)
				)
				(arc
					(start 456.867006 -226.862386)
					(mid 456.852127 -226.826465)
					(end 456.816206 -226.811586)
				)
				(arc
					(start 455.416666 -226.811586)
					(mid 455.380745 -226.826465)
					(end 455.365866 -226.862386)
				)
			)
		)
	)
	(zone
		(layers "In1.Cu" "In2.Cu")
		(hatch none 0.5)
		(connect_pads
			(clearance 0)
		)
		(min_thickness 0.25)
		(keepout
			(tracks not_allowed)
			(vias allowed)
			(pads allowed)
			(copperpour not_allowed)
			(footprints allowed)
		)
		(placement
			(enabled no)
			(sheetname "")
		)
		(fill yes
			(thermal_gap 0.5)
			(thermal_bridge_width 0.5)
			(island_removal_mode 0)
		)
		(polygon
			(pts
				(arc
					(start 180.69433 -314.821316)
					(mid 180.709209 -314.857237)
					(end 180.74513 -314.872116)
				)
				(arc
					(start 182.14467 -314.872116)
					(mid 182.180591 -314.857237)
					(end 182.19547 -314.821316)
				)
				(arc
					(start 182.19547 -314.412376)
					(mid 182.180591 -314.376455)
					(end 182.14467 -314.361576)
				)
				(arc
					(start 180.74513 -314.361576)
					(mid 180.709209 -314.376455)
					(end 180.69433 -314.412376)
				)
			)
		)
	)
	(zone
		(layers "In1.Cu" "In2.Cu")
		(hatch none 0.5)
		(connect_pads
			(clearance 0)
		)
		(min_thickness 0.25)
		(keepout
			(tracks not_allowed)
			(vias allowed)
			(pads allowed)
			(copperpour not_allowed)
			(footprints allowed)
		)
		(placement
			(enabled no)
			(sheetname "")
		)
		(fill yes
			(thermal_gap 0.5)
			(thermal_bridge_width 0.5)
			(island_removal_mode 0)
		)
		(polygon
			(pts
				(arc
					(start 7.39013 -226.421442)
					(mid 7.405009 -226.457363)
					(end 7.44093 -226.472242)
				)
				(arc
					(start 8.84047 -226.472242)
					(mid 8.876391 -226.457363)
					(end 8.89127 -226.421442)
				)
				(arc
					(start 8.89127 -226.012502)
					(mid 8.876391 -225.976581)
					(end 8.84047 -225.961702)
				)
				(arc
					(start 7.44093 -225.961702)
					(mid 7.405009 -225.976581)
					(end 7.39013 -226.012502)
				)
			)
		)
	)
	(zone
		(layers "In1.Cu" "In2.Cu")
		(hatch none 0.5)
		(connect_pads
			(clearance 0)
		)
		(min_thickness 0.25)
		(keepout
			(tracks not_allowed)
			(vias allowed)
			(pads allowed)
			(copperpour not_allowed)
			(footprints allowed)
		)
		(placement
			(enabled no)
			(sheetname "")
		)
		(fill yes
			(thermal_gap 0.5)
			(thermal_bridge_width 0.5)
			(island_removal_mode 0)
		)
		(polygon
			(pts
				(arc
					(start 56.752998 -274.02155)
					(mid 56.767877 -274.057471)
					(end 56.803798 -274.07235)
				)
				(arc
					(start 58.203338 -274.07235)
					(mid 58.239259 -274.057471)
					(end 58.254138 -274.02155)
				)
				(arc
					(start 58.254138 -273.61261)
					(mid 58.239259 -273.576689)
					(end 58.203338 -273.56181)
				)
				(arc
					(start 56.803798 -273.56181)
					(mid 56.767877 -273.576689)
					(end 56.752998 -273.61261)
				)
			)
		)
	)
	(zone
		(layers "In1.Cu" "In2.Cu")
		(hatch none 0.5)
		(connect_pads
			(clearance 0)
		)
		(min_thickness 0.25)
		(keepout
			(tracks not_allowed)
			(vias allowed)
			(pads allowed)
			(copperpour not_allowed)
			(footprints allowed)
		)
		(placement
			(enabled no)
			(sheetname "")
		)
		(fill yes
			(thermal_gap 0.5)
			(thermal_bridge_width 0.5)
			(island_removal_mode 0)
		)
		(polygon
			(pts
				(arc
					(start 214.969598 -315.671454)
					(mid 214.984477 -315.707375)
					(end 215.020398 -315.722254)
				)
				(arc
					(start 216.419938 -315.722254)
					(mid 216.455859 -315.707375)
					(end 216.470738 -315.671454)
				)
				(arc
					(start 216.470738 -315.262514)
					(mid 216.455859 -315.226593)
					(end 216.419938 -315.211714)
				)
				(arc
					(start 215.020398 -315.211714)
					(mid 214.984477 -315.226593)
					(end 214.969598 -315.262514)
				)
			)
		)
	)
	(zone
		(layers "In1.Cu" "In2.Cu")
		(hatch none 0.5)
		(connect_pads
			(clearance 0)
		)
		(min_thickness 0.25)
		(keepout
			(tracks not_allowed)
			(vias allowed)
			(pads allowed)
			(copperpour not_allowed)
			(footprints allowed)
		)
		(placement
			(enabled no)
			(sheetname "")
		)
		(fill yes
			(thermal_gap 0.5)
			(thermal_bridge_width 0.5)
			(island_removal_mode 0)
		)
		(polygon
			(pts
				(arc
					(start 37.56533 -200.921366)
					(mid 37.580209 -200.957287)
					(end 37.61613 -200.972166)
				)
				(arc
					(start 39.01567 -200.972166)
					(mid 39.051591 -200.957287)
					(end 39.06647 -200.921366)
				)
				(arc
					(start 39.06647 -200.512426)
					(mid 39.051591 -200.476505)
					(end 39.01567 -200.461626)
				)
				(arc
					(start 37.61613 -200.461626)
					(mid 37.580209 -200.476505)
					(end 37.56533 -200.512426)
				)
			)
		)
	)
	(zone
		(layers "In1.Cu" "In2.Cu")
		(hatch none 0.5)
		(connect_pads
			(clearance 0)
		)
		(min_thickness 0.25)
		(keepout
			(tracks not_allowed)
			(vias allowed)
			(pads allowed)
			(copperpour not_allowed)
			(footprints allowed)
		)
		(placement
			(enabled no)
			(sheetname "")
		)
		(fill yes
			(thermal_gap 0.5)
			(thermal_bridge_width 0.5)
			(island_removal_mode 0)
		)
		(polygon
			(pts
				(arc
					(start 436.178198 -269.771368)
					(mid 436.193077 -269.807289)
					(end 436.228998 -269.822168)
				)
				(arc
					(start 437.628538 -269.822168)
					(mid 437.664459 -269.807289)
					(end 437.679338 -269.771368)
				)
				(arc
					(start 437.679338 -269.362428)
					(mid 437.664459 -269.326507)
					(end 437.628538 -269.311628)
				)
				(arc
					(start 436.228998 -269.311628)
					(mid 436.193077 -269.326507)
					(end 436.178198 -269.362428)
				)
			)
		)
	)
	(zone
		(layers "In1.Cu" "In2.Cu")
		(hatch none 0.5)
		(connect_pads
			(clearance 0)
		)
		(min_thickness 0.25)
		(keepout
			(tracks not_allowed)
			(vias allowed)
			(pads allowed)
			(copperpour not_allowed)
			(footprints allowed)
		)
		(placement
			(enabled no)
			(sheetname "")
		)
		(fill yes
			(thermal_gap 0.5)
			(thermal_bridge_width 0.5)
			(island_removal_mode 0)
		)
		(polygon
			(pts
				(arc
					(start 417.646866 -287.621472)
					(mid 417.661745 -287.657393)
					(end 417.697666 -287.672272)
				)
				(arc
					(start 419.097206 -287.672272)
					(mid 419.133127 -287.657393)
					(end 419.148006 -287.621472)
				)
				(arc
					(start 419.148006 -287.212532)
					(mid 419.133127 -287.176611)
					(end 419.097206 -287.161732)
				)
				(arc
					(start 417.697666 -287.161732)
					(mid 417.661745 -287.176611)
					(end 417.646866 -287.212532)
				)
			)
		)
	)
	(zone
		(layers "In1.Cu" "In2.Cu")
		(hatch none 0.5)
		(connect_pads
			(clearance 0)
		)
		(min_thickness 0.25)
		(keepout
			(tracks not_allowed)
			(vias allowed)
			(pads allowed)
			(copperpour not_allowed)
			(footprints allowed)
		)
		(placement
			(enabled no)
			(sheetname "")
		)
		(fill yes
			(thermal_gap 0.5)
			(thermal_bridge_width 0.5)
			(island_removal_mode 0)
		)
		(polygon
			(pts
				(arc
					(start 308.136798 -262.971534)
					(mid 308.151677 -263.007455)
					(end 308.187598 -263.022334)
				)
				(arc
					(start 309.587138 -263.022334)
					(mid 309.623059 -263.007455)
					(end 309.637938 -262.971534)
				)
				(arc
					(start 309.637938 -262.562594)
					(mid 309.623059 -262.526673)
					(end 309.587138 -262.511794)
				)
				(arc
					(start 308.187598 -262.511794)
					(mid 308.151677 -262.526673)
					(end 308.136798 -262.562594)
				)
			)
		)
	)
	(zone
		(layers "In1.Cu" "In2.Cu")
		(hatch none 0.5)
		(connect_pads
			(clearance 0)
		)
		(min_thickness 0.25)
		(keepout
			(tracks not_allowed)
			(vias allowed)
			(pads allowed)
			(copperpour not_allowed)
			(footprints allowed)
		)
		(placement
			(enabled no)
			(sheetname "")
		)
		(fill yes
			(thermal_gap 0.5)
			(thermal_bridge_width 0.5)
			(island_removal_mode 0)
		)
		(polygon
			(pts
				(arc
					(start 277.961598 -264.671302)
					(mid 277.976477 -264.707223)
					(end 278.012398 -264.722102)
				)
				(arc
					(start 279.411938 -264.722102)
					(mid 279.447859 -264.707223)
					(end 279.462738 -264.671302)
				)
				(arc
					(start 279.462738 -264.262362)
					(mid 279.447859 -264.226441)
					(end 279.411938 -264.211562)
				)
				(arc
					(start 278.012398 -264.211562)
					(mid 277.976477 -264.226441)
					(end 277.961598 -264.262362)
				)
			)
		)
	)
	(zone
		(layers "In1.Cu" "In2.Cu")
		(hatch none 0.5)
		(connect_pads
			(clearance 0)
		)
		(min_thickness 0.25)
		(keepout
			(tracks not_allowed)
			(vias allowed)
			(pads allowed)
			(copperpour not_allowed)
			(footprints allowed)
		)
		(placement
			(enabled no)
			(sheetname "")
		)
		(fill yes
			(thermal_gap 0.5)
			(thermal_bridge_width 0.5)
			(island_removal_mode 0)
		)
		(polygon
			(pts
				(arc
					(start 259.430266 -197.521322)
					(mid 259.445145 -197.557243)
					(end 259.481066 -197.572122)
				)
				(arc
					(start 260.880606 -197.572122)
					(mid 260.916527 -197.557243)
					(end 260.931406 -197.521322)
				)
				(arc
					(start 260.931406 -197.112382)
					(mid 260.916527 -197.076461)
					(end 260.880606 -197.061582)
				)
				(arc
					(start 259.481066 -197.061582)
					(mid 259.445145 -197.076461)
					(end 259.430266 -197.112382)
				)
			)
		)
	)
	(zone
		(layers "In1.Cu" "In2.Cu")
		(hatch none 0.5)
		(connect_pads
			(clearance 0)
		)
		(min_thickness 0.25)
		(keepout
			(tracks not_allowed)
			(vias allowed)
			(pads allowed)
			(copperpour not_allowed)
			(footprints allowed)
		)
		(placement
			(enabled no)
			(sheetname "")
		)
		(fill yes
			(thermal_gap 0.5)
			(thermal_bridge_width 0.5)
			(island_removal_mode 0)
		)
		(polygon
			(pts
				(arc
					(start 455.365866 -216.22131)
					(mid 455.380745 -216.257231)
					(end 455.416666 -216.27211)
				)
				(arc
					(start 456.816206 -216.27211)
					(mid 456.852127 -216.257231)
					(end 456.867006 -216.22131)
				)
				(arc
					(start 456.867006 -215.81237)
					(mid 456.852127 -215.776449)
					(end 456.816206 -215.76157)
				)
				(arc
					(start 455.416666 -215.76157)
					(mid 455.380745 -215.776449)
					(end 455.365866 -215.81237)
				)
			)
		)
	)
	(zone
		(layers "In1.Cu" "In2.Cu")
		(hatch none 0.5)
		(connect_pads
			(clearance 0)
		)
		(min_thickness 0.25)
		(keepout
			(tracks not_allowed)
			(vias allowed)
			(pads allowed)
			(copperpour not_allowed)
			(footprints allowed)
		)
		(placement
			(enabled no)
			(sheetname "")
		)
		(fill yes
			(thermal_gap 0.5)
			(thermal_bridge_width 0.5)
			(island_removal_mode 0)
		)
		(polygon
			(pts
				(arc
					(start 14.93393 -266.371324)
					(mid 14.948809 -266.407245)
					(end 14.98473 -266.422124)
				)
				(arc
					(start 16.38427 -266.422124)
					(mid 16.420191 -266.407245)
					(end 16.43507 -266.371324)
				)
				(arc
					(start 16.43507 -265.962384)
					(mid 16.420191 -265.926463)
					(end 16.38427 -265.911584)
				)
				(arc
					(start 14.98473 -265.911584)
					(mid 14.948809 -265.926463)
					(end 14.93393 -265.962384)
				)
			)
		)
	)
	(zone
		(layers "In1.Cu" "In2.Cu")
		(hatch none 0.5)
		(connect_pads
			(clearance 0)
		)
		(min_thickness 0.25)
		(keepout
			(tracks not_allowed)
			(vias allowed)
			(pads allowed)
			(copperpour not_allowed)
			(footprints allowed)
		)
		(placement
			(enabled no)
			(sheetname "")
		)
		(fill yes
			(thermal_gap 0.5)
			(thermal_bridge_width 0.5)
			(island_removal_mode 0)
		)
		(polygon
			(pts
				(arc
					(start 11.490198 -298.671488)
					(mid 11.505077 -298.707409)
					(end 11.540998 -298.722288)
				)
				(arc
					(start 12.940538 -298.722288)
					(mid 12.976459 -298.707409)
					(end 12.991338 -298.671488)
				)
				(arc
					(start 12.991338 -298.262548)
					(mid 12.976459 -298.226627)
					(end 12.940538 -298.211748)
				)
				(arc
					(start 11.540998 -298.211748)
					(mid 11.505077 -298.226627)
					(end 11.490198 -298.262548)
				)
			)
		)
	)
	(zone
		(layers "In1.Cu" "In2.Cu")
		(hatch none 0.5)
		(connect_pads
			(clearance 0)
		)
		(min_thickness 0.25)
		(keepout
			(tracks not_allowed)
			(vias allowed)
			(pads allowed)
			(copperpour not_allowed)
			(footprints allowed)
		)
		(placement
			(enabled no)
			(sheetname "")
		)
		(fill yes
			(thermal_gap 0.5)
			(thermal_bridge_width 0.5)
			(island_removal_mode 0)
		)
		(polygon
			(pts
				(arc
					(start 255.330198 -280.821384)
					(mid 255.345077 -280.857305)
					(end 255.380998 -280.872184)
				)
				(arc
					(start 256.780538 -280.872184)
					(mid 256.816459 -280.857305)
					(end 256.831338 -280.821384)
				)
				(arc
					(start 256.831338 -280.412444)
					(mid 256.816459 -280.376523)
					(end 256.780538 -280.361644)
				)
				(arc
					(start 255.380998 -280.361644)
					(mid 255.345077 -280.376523)
					(end 255.330198 -280.412444)
				)
			)
		)
	)
	(zone
		(layers "In1.Cu" "In2.Cu")
		(hatch none 0.5)
		(connect_pads
			(clearance 0)
		)
		(min_thickness 0.25)
		(keepout
			(tracks not_allowed)
			(vias allowed)
			(pads allowed)
			(copperpour not_allowed)
			(footprints allowed)
		)
		(placement
			(enabled no)
			(sheetname "")
		)
		(fill yes
			(thermal_gap 0.5)
			(thermal_bridge_width 0.5)
			(island_removal_mode 0)
		)
		(polygon
			(pts
				(arc
					(start 436.178198 -277.42134)
					(mid 436.193077 -277.457261)
					(end 436.228998 -277.47214)
				)
				(arc
					(start 437.628538 -277.47214)
					(mid 437.664459 -277.457261)
					(end 437.679338 -277.42134)
				)
				(arc
					(start 437.679338 -277.0124)
					(mid 437.664459 -276.976479)
					(end 437.628538 -276.9616)
				)
				(arc
					(start 436.228998 -276.9616)
					(mid 436.193077 -276.976479)
					(end 436.178198 -277.0124)
				)
			)
		)
	)
	(zone
		(layers "In1.Cu" "In2.Cu")
		(hatch none 0.5)
		(connect_pads
			(clearance 0)
		)
		(min_thickness 0.25)
		(keepout
			(tracks not_allowed)
			(vias allowed)
			(pads allowed)
			(copperpour not_allowed)
			(footprints allowed)
		)
		(placement
			(enabled no)
			(sheetname "")
		)
		(fill yes
			(thermal_gap 0.5)
			(thermal_bridge_width 0.5)
			(island_removal_mode 0)
		)
		(polygon
			(pts
				(arc
					(start 19.033998 -195.821554)
					(mid 19.048877 -195.857475)
					(end 19.084798 -195.872354)
				)
				(arc
					(start 20.484338 -195.872354)
					(mid 20.520259 -195.857475)
					(end 20.535138 -195.821554)
				)
				(arc
					(start 20.535138 -195.412614)
					(mid 20.520259 -195.376693)
					(end 20.484338 -195.361814)
				)
				(arc
					(start 19.084798 -195.361814)
					(mid 19.048877 -195.376693)
					(end 19.033998 -195.412614)
				)
			)
		)
	)
	(zone
		(layers "In1.Cu" "In2.Cu")
		(hatch none 0.5)
		(connect_pads
			(clearance 0)
		)
		(min_thickness 0.25)
		(keepout
			(tracks not_allowed)
			(vias allowed)
			(pads allowed)
			(copperpour not_allowed)
			(footprints allowed)
		)
		(placement
			(enabled no)
			(sheetname "")
		)
		(fill yes
			(thermal_gap 0.5)
			(thermal_bridge_width 0.5)
			(island_removal_mode 0)
		)
		(polygon
			(pts
				(arc
					(start 41.665398 -265.52144)
					(mid 41.680277 -265.557361)
					(end 41.716198 -265.57224)
				)
				(arc
					(start 43.115738 -265.57224)
					(mid 43.151659 -265.557361)
					(end 43.166538 -265.52144)
				)
				(arc
					(start 43.166538 -265.1125)
					(mid 43.151659 -265.076579)
					(end 43.115738 -265.0617)
				)
				(arc
					(start 41.716198 -265.0617)
					(mid 41.680277 -265.076579)
					(end 41.665398 -265.1125)
				)
			)
		)
	)
	(zone
		(layers "In1.Cu" "In2.Cu")
		(hatch none 0.5)
		(connect_pads
			(clearance 0)
		)
		(min_thickness 0.25)
		(keepout
			(tracks not_allowed)
			(vias allowed)
			(pads allowed)
			(copperpour not_allowed)
			(footprints allowed)
		)
		(placement
			(enabled no)
			(sheetname "")
		)
		(fill yes
			(thermal_gap 0.5)
			(thermal_bridge_width 0.5)
			(island_removal_mode 0)
		)
		(polygon
			(pts
				(arc
					(start 188.23813 -313.121294)
					(mid 188.253009 -313.157215)
					(end 188.28893 -313.172094)
				)
				(arc
					(start 189.68847 -313.172094)
					(mid 189.724391 -313.157215)
					(end 189.73927 -313.121294)
				)
				(arc
					(start 189.73927 -312.712354)
					(mid 189.724391 -312.676433)
					(end 189.68847 -312.661554)
				)
				(arc
					(start 188.28893 -312.661554)
					(mid 188.253009 -312.676433)
					(end 188.23813 -312.712354)
				)
			)
		)
	)
	(zone
		(layers "In1.Cu" "In2.Cu")
		(hatch none 0.5)
		(connect_pads
			(clearance 0)
		)
		(min_thickness 0.25)
		(keepout
			(tracks not_allowed)
			(vias allowed)
			(pads allowed)
			(copperpour not_allowed)
			(footprints allowed)
		)
		(placement
			(enabled no)
			(sheetname "")
		)
		(fill yes
			(thermal_gap 0.5)
			(thermal_bridge_width 0.5)
			(island_removal_mode 0)
		)
		(polygon
			(pts
				(arc
					(start 45.10913 -240.021364)
					(mid 45.124009 -240.057285)
					(end 45.15993 -240.072164)
				)
				(arc
					(start 46.55947 -240.072164)
					(mid 46.595391 -240.057285)
					(end 46.61027 -240.021364)
				)
				(arc
					(start 46.61027 -239.612424)
					(mid 46.595391 -239.576503)
					(end 46.55947 -239.561624)
				)
				(arc
					(start 45.15993 -239.561624)
					(mid 45.124009 -239.576503)
					(end 45.10913 -239.612424)
				)
			)
		)
	)
	(zone
		(layers "In1.Cu" "In2.Cu")
		(hatch none 0.5)
		(connect_pads
			(clearance 0)
		)
		(min_thickness 0.25)
		(keepout
			(tracks not_allowed)
			(vias allowed)
			(pads allowed)
			(copperpour not_allowed)
			(footprints allowed)
		)
		(placement
			(enabled no)
			(sheetname "")
		)
		(fill yes
			(thermal_gap 0.5)
			(thermal_bridge_width 0.5)
			(island_removal_mode 0)
		)
		(polygon
			(pts
				(arc
					(start 259.430266 -237.471458)
					(mid 259.445145 -237.507379)
					(end 259.481066 -237.522258)
				)
				(arc
					(start 260.880606 -237.522258)
					(mid 260.916527 -237.507379)
					(end 260.931406 -237.471458)
				)
				(arc
					(start 260.931406 -237.062518)
					(mid 260.916527 -237.026597)
					(end 260.880606 -237.011718)
				)
				(arc
					(start 259.481066 -237.011718)
					(mid 259.445145 -237.026597)
					(end 259.430266 -237.062518)
				)
			)
		)
	)
	(zone
		(layers "In1.Cu" "In2.Cu")
		(hatch none 0.5)
		(connect_pads
			(clearance 0)
		)
		(min_thickness 0.25)
		(keepout
			(tracks not_allowed)
			(vias allowed)
			(pads allowed)
			(copperpour not_allowed)
			(footprints allowed)
		)
		(placement
			(enabled no)
			(sheetname "")
		)
		(fill yes
			(thermal_gap 0.5)
			(thermal_bridge_width 0.5)
			(island_removal_mode 0)
		)
		(polygon
			(pts
				(arc
					(start 447.822066 -208.571338)
					(mid 447.836945 -208.607259)
					(end 447.872866 -208.622138)
				)
				(arc
					(start 449.272406 -208.622138)
					(mid 449.308327 -208.607259)
					(end 449.323206 -208.571338)
				)
				(arc
					(start 449.323206 -208.162398)
					(mid 449.308327 -208.126477)
					(end 449.272406 -208.111598)
				)
				(arc
					(start 447.872866 -208.111598)
					(mid 447.836945 -208.126477)
					(end 447.822066 -208.162398)
				)
			)
		)
	)
	(zone
		(layers "In1.Cu" "In2.Cu")
		(hatch none 0.5)
		(connect_pads
			(clearance 0)
		)
		(min_thickness 0.25)
		(keepout
			(tracks not_allowed)
			(vias allowed)
			(pads allowed)
			(copperpour not_allowed)
			(footprints allowed)
		)
		(placement
			(enabled no)
			(sheetname "")
		)
		(fill yes
			(thermal_gap 0.5)
			(thermal_bridge_width 0.5)
			(island_removal_mode 0)
		)
		(polygon
			(pts
				(arc
					(start 11.490198 -296.971466)
					(mid 11.505077 -297.007387)
					(end 11.540998 -297.022266)
				)
				(arc
					(start 12.940538 -297.022266)
					(mid 12.976459 -297.007387)
					(end 12.991338 -296.971466)
				)
				(arc
					(start 12.991338 -296.562526)
					(mid 12.976459 -296.526605)
					(end 12.940538 -296.511726)
				)
				(arc
					(start 11.540998 -296.511726)
					(mid 11.505077 -296.526605)
					(end 11.490198 -296.562526)
				)
			)
		)
	)
	(zone
		(layers "In1.Cu" "In2.Cu")
		(hatch none 0.5)
		(connect_pads
			(clearance 0)
		)
		(min_thickness 0.25)
		(keepout
			(tracks not_allowed)
			(vias allowed)
			(pads allowed)
			(copperpour not_allowed)
			(footprints allowed)
		)
		(placement
			(enabled no)
			(sheetname "")
		)
		(fill yes
			(thermal_gap 0.5)
			(thermal_bridge_width 0.5)
			(island_removal_mode 0)
		)
		(polygon
			(pts
				(arc
					(start 188.23813 -224.72142)
					(mid 188.253009 -224.757341)
					(end 188.28893 -224.77222)
				)
				(arc
					(start 189.68847 -224.77222)
					(mid 189.724391 -224.757341)
					(end 189.73927 -224.72142)
				)
				(arc
					(start 189.73927 -224.31248)
					(mid 189.724391 -224.276559)
					(end 189.68847 -224.26168)
				)
				(arc
					(start 188.28893 -224.26168)
					(mid 188.253009 -224.276559)
					(end 188.23813 -224.31248)
				)
			)
		)
	)
	(zone
		(layers "In1.Cu" "In2.Cu")
		(hatch none 0.5)
		(connect_pads
			(clearance 0)
		)
		(min_thickness 0.25)
		(keepout
			(tracks not_allowed)
			(vias allowed)
			(pads allowed)
			(copperpour not_allowed)
			(footprints allowed)
		)
		(placement
			(enabled no)
			(sheetname "")
		)
		(fill yes
			(thermal_gap 0.5)
			(thermal_bridge_width 0.5)
			(island_removal_mode 0)
		)
		(polygon
			(pts
				(arc
					(start 158.06293 -200.921366)
					(mid 158.077809 -200.957287)
					(end 158.11373 -200.972166)
				)
				(arc
					(start 159.51327 -200.972166)
					(mid 159.549191 -200.957287)
					(end 159.56407 -200.921366)
				)
				(arc
					(start 159.56407 -200.512426)
					(mid 159.549191 -200.476505)
					(end 159.51327 -200.461626)
				)
				(arc
					(start 158.11373 -200.461626)
					(mid 158.077809 -200.476505)
					(end 158.06293 -200.512426)
				)
			)
		)
	)
	(zone
		(layers "In1.Cu" "In2.Cu")
		(hatch none 0.5)
		(connect_pads
			(clearance 0)
		)
		(min_thickness 0.25)
		(keepout
			(tracks not_allowed)
			(vias allowed)
			(pads allowed)
			(copperpour not_allowed)
			(footprints allowed)
		)
		(placement
			(enabled no)
			(sheetname "")
		)
		(fill yes
			(thermal_gap 0.5)
			(thermal_bridge_width 0.5)
			(island_removal_mode 0)
		)
		(polygon
			(pts
				(arc
					(start 458.809598 -286.771334)
					(mid 458.824477 -286.807255)
					(end 458.860398 -286.822134)
				)
				(arc
					(start 460.259938 -286.822134)
					(mid 460.295859 -286.807255)
					(end 460.310738 -286.771334)
				)
				(arc
					(start 460.310738 -286.362394)
					(mid 460.295859 -286.326473)
					(end 460.259938 -286.311594)
				)
				(arc
					(start 458.860398 -286.311594)
					(mid 458.824477 -286.326473)
					(end 458.809598 -286.362394)
				)
			)
		)
	)
	(zone
		(layers "In1.Cu" "In2.Cu")
		(hatch none 0.5)
		(connect_pads
			(clearance 0)
		)
		(min_thickness 0.25)
		(keepout
			(tracks not_allowed)
			(vias allowed)
			(pads allowed)
			(copperpour not_allowed)
			(footprints allowed)
		)
		(placement
			(enabled no)
			(sheetname "")
		)
		(fill yes
			(thermal_gap 0.5)
			(thermal_bridge_width 0.5)
			(island_removal_mode 0)
		)
		(polygon
			(pts
				(arc
					(start 169.706798 -268.921484)
					(mid 169.721677 -268.957405)
					(end 169.757598 -268.972284)
				)
				(arc
					(start 171.157138 -268.972284)
					(mid 171.193059 -268.957405)
					(end 171.207938 -268.921484)
				)
				(arc
					(start 171.207938 -268.512544)
					(mid 171.193059 -268.476623)
					(end 171.157138 -268.461744)
				)
				(arc
					(start 169.757598 -268.461744)
					(mid 169.721677 -268.476623)
					(end 169.706798 -268.512544)
				)
			)
		)
	)
	(zone
		(layers "In1.Cu" "In2.Cu")
		(hatch none 0.5)
		(connect_pads
			(clearance 0)
		)
		(min_thickness 0.25)
		(keepout
			(tracks not_allowed)
			(vias allowed)
			(pads allowed)
			(copperpour not_allowed)
			(footprints allowed)
		)
		(placement
			(enabled no)
			(sheetname "")
		)
		(fill yes
			(thermal_gap 0.5)
			(thermal_bridge_width 0.5)
			(island_removal_mode 0)
		)
		(polygon
			(pts
				(arc
					(start 462.909666 -262.121396)
					(mid 462.924545 -262.157317)
					(end 462.960466 -262.172196)
				)
				(arc
					(start 464.360006 -262.172196)
					(mid 464.395927 -262.157317)
					(end 464.410806 -262.121396)
				)
				(arc
					(start 464.410806 -261.712456)
					(mid 464.395927 -261.676535)
					(end 464.360006 -261.661656)
				)
				(arc
					(start 462.960466 -261.661656)
					(mid 462.924545 -261.676535)
					(end 462.909666 -261.712456)
				)
			)
		)
	)
	(zone
		(layers "In1.Cu" "In2.Cu")
		(hatch none 0.5)
		(connect_pads
			(clearance 0)
		)
		(min_thickness 0.25)
		(keepout
			(tracks not_allowed)
			(vias allowed)
			(pads allowed)
			(copperpour not_allowed)
			(footprints allowed)
		)
		(placement
			(enabled no)
			(sheetname "")
		)
		(fill yes
			(thermal_gap 0.5)
			(thermal_bridge_width 0.5)
			(island_removal_mode 0)
		)
		(polygon
			(pts
				(arc
					(start 440.278266 -262.121396)
					(mid 440.293145 -262.157317)
					(end 440.329066 -262.172196)
				)
				(arc
					(start 441.728606 -262.172196)
					(mid 441.764527 -262.157317)
					(end 441.779406 -262.121396)
				)
				(arc
					(start 441.779406 -261.712456)
					(mid 441.764527 -261.676535)
					(end 441.728606 -261.661656)
				)
				(arc
					(start 440.329066 -261.661656)
					(mid 440.293145 -261.676535)
					(end 440.278266 -261.712456)
				)
			)
		)
	)
	(zone
		(layers "In1.Cu" "In2.Cu")
		(hatch none 0.5)
		(connect_pads
			(clearance 0)
		)
		(min_thickness 0.25)
		(keepout
			(tracks not_allowed)
			(vias allowed)
			(pads allowed)
			(copperpour not_allowed)
			(footprints allowed)
		)
		(placement
			(enabled no)
			(sheetname "")
		)
		(fill yes
			(thermal_gap 0.5)
			(thermal_bridge_width 0.5)
			(island_removal_mode 0)
		)
		(polygon
			(pts
				(arc
					(start 173.15053 -266.371324)
					(mid 173.165409 -266.407245)
					(end 173.20133 -266.422124)
				)
				(arc
					(start 174.60087 -266.422124)
					(mid 174.636791 -266.407245)
					(end 174.65167 -266.371324)
				)
				(arc
					(start 174.65167 -265.962384)
					(mid 174.636791 -265.926463)
					(end 174.60087 -265.911584)
				)
				(arc
					(start 173.20133 -265.911584)
					(mid 173.165409 -265.926463)
					(end 173.15053 -265.962384)
				)
			)
		)
	)
	(zone
		(layers "In1.Cu" "In2.Cu")
		(hatch none 0.5)
		(connect_pads
			(clearance 0)
		)
		(min_thickness 0.25)
		(keepout
			(tracks not_allowed)
			(vias allowed)
			(pads allowed)
			(copperpour not_allowed)
			(footprints allowed)
		)
		(placement
			(enabled no)
			(sheetname "")
		)
		(fill yes
			(thermal_gap 0.5)
			(thermal_bridge_width 0.5)
			(island_removal_mode 0)
		)
		(polygon
			(pts
				(arc
					(start 169.706798 -289.321494)
					(mid 169.721677 -289.357415)
					(end 169.757598 -289.372294)
				)
				(arc
					(start 171.157138 -289.372294)
					(mid 171.193059 -289.357415)
					(end 171.207938 -289.321494)
				)
				(arc
					(start 171.207938 -288.912554)
					(mid 171.193059 -288.876633)
					(end 171.157138 -288.861754)
				)
				(arc
					(start 169.757598 -288.861754)
					(mid 169.721677 -288.876633)
					(end 169.706798 -288.912554)
				)
			)
		)
	)
	(zone
		(layers "In1.Cu" "In2.Cu")
		(hatch none 0.5)
		(connect_pads
			(clearance 0)
		)
		(min_thickness 0.25)
		(keepout
			(tracks not_allowed)
			(vias allowed)
			(pads allowed)
			(copperpour not_allowed)
			(footprints allowed)
		)
		(placement
			(enabled no)
			(sheetname "")
		)
		(fill yes
			(thermal_gap 0.5)
			(thermal_bridge_width 0.5)
			(island_removal_mode 0)
		)
		(polygon
			(pts
				(arc
					(start 270.417798 -211.971382)
					(mid 270.432677 -212.007303)
					(end 270.468598 -212.022182)
				)
				(arc
					(start 271.868138 -212.022182)
					(mid 271.904059 -212.007303)
					(end 271.918938 -211.971382)
				)
				(arc
					(start 271.918938 -211.562442)
					(mid 271.904059 -211.526521)
					(end 271.868138 -211.511642)
				)
				(arc
					(start 270.468598 -211.511642)
					(mid 270.432677 -211.526521)
					(end 270.417798 -211.562442)
				)
			)
		)
	)
	(zone
		(layers "In1.Cu" "In2.Cu")
		(hatch none 0.5)
		(connect_pads
			(clearance 0)
		)
		(min_thickness 0.25)
		(keepout
			(tracks not_allowed)
			(vias allowed)
			(pads allowed)
			(copperpour not_allowed)
			(footprints allowed)
		)
		(placement
			(enabled no)
			(sheetname "")
		)
		(fill yes
			(thermal_gap 0.5)
			(thermal_bridge_width 0.5)
			(island_removal_mode 0)
		)
		(polygon
			(pts
				(arc
					(start 451.265798 -217.071448)
					(mid 451.280677 -217.107369)
					(end 451.316598 -217.122248)
				)
				(arc
					(start 452.716138 -217.122248)
					(mid 452.752059 -217.107369)
					(end 452.766938 -217.071448)
				)
				(arc
					(start 452.766938 -216.662508)
					(mid 452.752059 -216.626587)
					(end 452.716138 -216.611708)
				)
				(arc
					(start 451.316598 -216.611708)
					(mid 451.280677 -216.626587)
					(end 451.265798 -216.662508)
				)
			)
		)
	)
	(zone
		(layers "In1.Cu" "In2.Cu")
		(hatch none 0.5)
		(connect_pads
			(clearance 0)
		)
		(min_thickness 0.25)
		(keepout
			(tracks not_allowed)
			(vias allowed)
			(pads allowed)
			(copperpour not_allowed)
			(footprints allowed)
		)
		(placement
			(enabled no)
			(sheetname "")
		)
		(fill yes
			(thermal_gap 0.5)
			(thermal_bridge_width 0.5)
			(island_removal_mode 0)
		)
		(polygon
			(pts
				(arc
					(start 447.822066 -312.27141)
					(mid 447.836945 -312.307331)
					(end 447.872866 -312.32221)
				)
				(arc
					(start 449.272406 -312.32221)
					(mid 449.308327 -312.307331)
					(end 449.323206 -312.27141)
				)
				(arc
					(start 449.323206 -311.86247)
					(mid 449.308327 -311.826549)
					(end 449.272406 -311.81167)
				)
				(arc
					(start 447.872866 -311.81167)
					(mid 447.836945 -311.826549)
					(end 447.822066 -311.86247)
				)
			)
		)
	)
	(zone
		(layers "In1.Cu" "In2.Cu")
		(hatch none 0.5)
		(connect_pads
			(clearance 0)
		)
		(min_thickness 0.25)
		(keepout
			(tracks not_allowed)
			(vias allowed)
			(pads allowed)
			(copperpour not_allowed)
			(footprints allowed)
		)
		(placement
			(enabled no)
			(sheetname "")
		)
		(fill yes
			(thermal_gap 0.5)
			(thermal_bridge_width 0.5)
			(island_removal_mode 0)
		)
		(polygon
			(pts
				(arc
					(start 262.873998 -274.871434)
					(mid 262.888877 -274.907355)
					(end 262.924798 -274.922234)
				)
				(arc
					(start 264.324338 -274.922234)
					(mid 264.360259 -274.907355)
					(end 264.375138 -274.871434)
				)
				(arc
					(start 264.375138 -274.462494)
					(mid 264.360259 -274.426573)
					(end 264.324338 -274.411694)
				)
				(arc
					(start 262.924798 -274.411694)
					(mid 262.888877 -274.426573)
					(end 262.873998 -274.462494)
				)
			)
		)
	)
	(zone
		(layers "In1.Cu" "In2.Cu")
		(hatch none 0.5)
		(connect_pads
			(clearance 0)
		)
		(min_thickness 0.25)
		(keepout
			(tracks not_allowed)
			(vias allowed)
			(pads allowed)
			(copperpour not_allowed)
			(footprints allowed)
		)
		(placement
			(enabled no)
			(sheetname "")
		)
		(fill yes
			(thermal_gap 0.5)
			(thermal_bridge_width 0.5)
			(island_removal_mode 0)
		)
		(polygon
			(pts
				(arc
					(start 259.430266 -222.171514)
					(mid 259.445145 -222.207435)
					(end 259.481066 -222.222314)
				)
				(arc
					(start 260.880606 -222.222314)
					(mid 260.916527 -222.207435)
					(end 260.931406 -222.171514)
				)
				(arc
					(start 260.931406 -221.762574)
					(mid 260.916527 -221.726653)
					(end 260.880606 -221.711774)
				)
				(arc
					(start 259.481066 -221.711774)
					(mid 259.445145 -221.726653)
					(end 259.430266 -221.762574)
				)
			)
		)
	)
	(zone
		(layers "In1.Cu" "In2.Cu")
		(hatch none 0.5)
		(connect_pads
			(clearance 0)
		)
		(min_thickness 0.25)
		(keepout
			(tracks not_allowed)
			(vias allowed)
			(pads allowed)
			(copperpour not_allowed)
			(footprints allowed)
		)
		(placement
			(enabled no)
			(sheetname "")
		)
		(fill yes
			(thermal_gap 0.5)
			(thermal_bridge_width 0.5)
			(island_removal_mode 0)
		)
		(polygon
			(pts
				(arc
					(start 455.365866 -234.921298)
					(mid 455.380745 -234.957219)
					(end 455.416666 -234.972098)
				)
				(arc
					(start 456.816206 -234.972098)
					(mid 456.852127 -234.957219)
					(end 456.867006 -234.921298)
				)
				(arc
					(start 456.867006 -234.512358)
					(mid 456.852127 -234.476437)
					(end 456.816206 -234.461558)
				)
				(arc
					(start 455.416666 -234.461558)
					(mid 455.380745 -234.476437)
					(end 455.365866 -234.512358)
				)
			)
		)
	)
	(zone
		(layers "In1.Cu" "In2.Cu")
		(hatch none 0.5)
		(connect_pads
			(clearance 0)
		)
		(min_thickness 0.25)
		(keepout
			(tracks not_allowed)
			(vias allowed)
			(pads allowed)
			(copperpour not_allowed)
			(footprints allowed)
		)
		(placement
			(enabled no)
			(sheetname "")
		)
		(fill yes
			(thermal_gap 0.5)
			(thermal_bridge_width 0.5)
			(island_removal_mode 0)
		)
		(polygon
			(pts
				(arc
					(start 266.974066 -216.22131)
					(mid 266.988945 -216.257231)
					(end 267.024866 -216.27211)
				)
				(arc
					(start 268.424406 -216.27211)
					(mid 268.460327 -216.257231)
					(end 268.475206 -216.22131)
				)
				(arc
					(start 268.475206 -215.81237)
					(mid 268.460327 -215.776449)
					(end 268.424406 -215.76157)
				)
				(arc
					(start 267.024866 -215.76157)
					(mid 266.988945 -215.776449)
					(end 266.974066 -215.81237)
				)
			)
		)
	)
	(zone
		(layers "In1.Cu" "In2.Cu")
		(hatch none 0.5)
		(connect_pads
			(clearance 0)
		)
		(min_thickness 0.25)
		(keepout
			(tracks not_allowed)
			(vias allowed)
			(pads allowed)
			(copperpour not_allowed)
			(footprints allowed)
		)
		(placement
			(enabled no)
			(sheetname "")
		)
		(fill yes
			(thermal_gap 0.5)
			(thermal_bridge_width 0.5)
			(island_removal_mode 0)
		)
		(polygon
			(pts
				(arc
					(start 158.06293 -237.471458)
					(mid 158.077809 -237.507379)
					(end 158.11373 -237.522258)
				)
				(arc
					(start 159.51327 -237.522258)
					(mid 159.549191 -237.507379)
					(end 159.56407 -237.471458)
				)
				(arc
					(start 159.56407 -237.062518)
					(mid 159.549191 -237.026597)
					(end 159.51327 -237.011718)
				)
				(arc
					(start 158.11373 -237.011718)
					(mid 158.077809 -237.026597)
					(end 158.06293 -237.062518)
				)
			)
		)
	)
	(zone
		(layers "In1.Cu" "In2.Cu")
		(hatch none 0.5)
		(connect_pads
			(clearance 0)
		)
		(min_thickness 0.25)
		(keepout
			(tracks not_allowed)
			(vias allowed)
			(pads allowed)
			(copperpour not_allowed)
			(footprints allowed)
		)
		(placement
			(enabled no)
			(sheetname "")
		)
		(fill yes
			(thermal_gap 0.5)
			(thermal_bridge_width 0.5)
			(island_removal_mode 0)
		)
		(polygon
			(pts
				(arc
					(start 300.592998 -223.021398)
					(mid 300.607877 -223.057319)
					(end 300.643798 -223.072198)
				)
				(arc
					(start 302.043338 -223.072198)
					(mid 302.079259 -223.057319)
					(end 302.094138 -223.021398)
				)
				(arc
					(start 302.094138 -222.612458)
					(mid 302.079259 -222.576537)
					(end 302.043338 -222.561658)
				)
				(arc
					(start 300.643798 -222.561658)
					(mid 300.607877 -222.576537)
					(end 300.592998 -222.612458)
				)
			)
		)
	)
	(zone
		(layers "In1.Cu" "In2.Cu")
		(hatch none 0.5)
		(connect_pads
			(clearance 0)
		)
		(min_thickness 0.25)
		(keepout
			(tracks not_allowed)
			(vias allowed)
			(pads allowed)
			(copperpour not_allowed)
			(footprints allowed)
		)
		(placement
			(enabled no)
			(sheetname "")
		)
		(fill yes
			(thermal_gap 0.5)
			(thermal_bridge_width 0.5)
			(island_removal_mode 0)
		)
		(polygon
			(pts
				(arc
					(start 406.002998 -261.271512)
					(mid 406.017877 -261.307433)
					(end 406.053798 -261.322312)
				)
				(arc
					(start 407.453338 -261.322312)
					(mid 407.489259 -261.307433)
					(end 407.504138 -261.271512)
				)
				(arc
					(start 407.504138 -260.862572)
					(mid 407.489259 -260.826651)
					(end 407.453338 -260.811772)
				)
				(arc
					(start 406.053798 -260.811772)
					(mid 406.017877 -260.826651)
					(end 406.002998 -260.862572)
				)
			)
		)
	)
	(zone
		(layers "In1.Cu" "In2.Cu")
		(hatch none 0.5)
		(connect_pads
			(clearance 0)
		)
		(min_thickness 0.25)
		(keepout
			(tracks not_allowed)
			(vias allowed)
			(pads allowed)
			(copperpour not_allowed)
			(footprints allowed)
		)
		(placement
			(enabled no)
			(sheetname "")
		)
		(fill yes
			(thermal_gap 0.5)
			(thermal_bridge_width 0.5)
			(island_removal_mode 0)
		)
		(polygon
			(pts
				(arc
					(start 451.265798 -218.77147)
					(mid 451.280677 -218.807391)
					(end 451.316598 -218.82227)
				)
				(arc
					(start 452.716138 -218.82227)
					(mid 452.752059 -218.807391)
					(end 452.766938 -218.77147)
				)
				(arc
					(start 452.766938 -218.36253)
					(mid 452.752059 -218.326609)
					(end 452.716138 -218.31173)
				)
				(arc
					(start 451.316598 -218.31173)
					(mid 451.280677 -218.326609)
					(end 451.265798 -218.36253)
				)
			)
		)
	)
	(zone
		(layers "In1.Cu" "In2.Cu")
		(hatch none 0.5)
		(connect_pads
			(clearance 0)
		)
		(min_thickness 0.25)
		(keepout
			(tracks not_allowed)
			(vias allowed)
			(pads allowed)
			(copperpour not_allowed)
			(footprints allowed)
		)
		(placement
			(enabled no)
			(sheetname "")
		)
		(fill yes
			(thermal_gap 0.5)
			(thermal_bridge_width 0.5)
			(island_removal_mode 0)
		)
		(polygon
			(pts
				(arc
					(start 203.32573 -262.971534)
					(mid 203.340609 -263.007455)
					(end 203.37653 -263.022334)
				)
				(arc
					(start 204.77607 -263.022334)
					(mid 204.811991 -263.007455)
					(end 204.82687 -262.971534)
				)
				(arc
					(start 204.82687 -262.562594)
					(mid 204.811991 -262.526673)
					(end 204.77607 -262.511794)
				)
				(arc
					(start 203.37653 -262.511794)
					(mid 203.340609 -262.526673)
					(end 203.32573 -262.562594)
				)
			)
		)
	)
	(zone
		(layers "In1.Cu" "In2.Cu")
		(hatch none 0.5)
		(connect_pads
			(clearance 0)
		)
		(min_thickness 0.25)
		(keepout
			(tracks not_allowed)
			(vias allowed)
			(pads allowed)
			(copperpour not_allowed)
			(footprints allowed)
		)
		(placement
			(enabled no)
			(sheetname "")
		)
		(fill yes
			(thermal_gap 0.5)
			(thermal_bridge_width 0.5)
			(island_removal_mode 0)
		)
		(polygon
			(pts
				(arc
					(start 34.121598 -236.62132)
					(mid 34.136477 -236.657241)
					(end 34.172398 -236.67212)
				)
				(arc
					(start 35.571938 -236.67212)
					(mid 35.607859 -236.657241)
					(end 35.622738 -236.62132)
				)
				(arc
					(start 35.622738 -236.21238)
					(mid 35.607859 -236.176459)
					(end 35.571938 -236.16158)
				)
				(arc
					(start 34.172398 -236.16158)
					(mid 34.136477 -236.176459)
					(end 34.121598 -236.21238)
				)
			)
		)
	)
	(zone
		(layers "In1.Cu" "In2.Cu")
		(hatch none 0.5)
		(connect_pads
			(clearance 0)
		)
		(min_thickness 0.25)
		(keepout
			(tracks not_allowed)
			(vias allowed)
			(pads allowed)
			(copperpour not_allowed)
			(footprints allowed)
		)
		(placement
			(enabled no)
			(sheetname "")
		)
		(fill yes
			(thermal_gap 0.5)
			(thermal_bridge_width 0.5)
			(island_removal_mode 0)
		)
		(polygon
			(pts
				(arc
					(start 34.121598 -228.121464)
					(mid 34.136477 -228.157385)
					(end 34.172398 -228.172264)
				)
				(arc
					(start 35.571938 -228.172264)
					(mid 35.607859 -228.157385)
					(end 35.622738 -228.121464)
				)
				(arc
					(start 35.622738 -227.712524)
					(mid 35.607859 -227.676603)
					(end 35.571938 -227.661724)
				)
				(arc
					(start 34.172398 -227.661724)
					(mid 34.136477 -227.676603)
					(end 34.121598 -227.712524)
				)
			)
		)
	)
	(zone
		(layers "In1.Cu" "In2.Cu")
		(hatch none 0.5)
		(connect_pads
			(clearance 0)
		)
		(min_thickness 0.25)
		(keepout
			(tracks not_allowed)
			(vias allowed)
			(pads allowed)
			(copperpour not_allowed)
			(footprints allowed)
		)
		(placement
			(enabled no)
			(sheetname "")
		)
		(fill yes
			(thermal_gap 0.5)
			(thermal_bridge_width 0.5)
			(island_removal_mode 0)
		)
		(polygon
			(pts
				(arc
					(start 11.490198 -245.12143)
					(mid 11.505077 -245.157351)
					(end 11.540998 -245.17223)
				)
				(arc
					(start 12.940538 -245.17223)
					(mid 12.976459 -245.157351)
					(end 12.991338 -245.12143)
				)
				(arc
					(start 12.991338 -244.71249)
					(mid 12.976459 -244.676569)
					(end 12.940538 -244.66169)
				)
				(arc
					(start 11.540998 -244.66169)
					(mid 11.505077 -244.676569)
					(end 11.490198 -244.71249)
				)
			)
		)
	)
	(zone
		(layers "In1.Cu" "In2.Cu")
		(hatch none 0.5)
		(connect_pads
			(clearance 0)
		)
		(min_thickness 0.25)
		(keepout
			(tracks not_allowed)
			(vias allowed)
			(pads allowed)
			(copperpour not_allowed)
			(footprints allowed)
		)
		(placement
			(enabled no)
			(sheetname "")
		)
		(fill yes
			(thermal_gap 0.5)
			(thermal_bridge_width 0.5)
			(island_removal_mode 0)
		)
		(polygon
			(pts
				(arc
					(start 440.278266 -231.521508)
					(mid 440.293145 -231.557429)
					(end 440.329066 -231.572308)
				)
				(arc
					(start 441.728606 -231.572308)
					(mid 441.764527 -231.557429)
					(end 441.779406 -231.521508)
				)
				(arc
					(start 441.779406 -231.112568)
					(mid 441.764527 -231.076647)
					(end 441.728606 -231.061768)
				)
				(arc
					(start 440.329066 -231.061768)
					(mid 440.293145 -231.076647)
					(end 440.278266 -231.112568)
				)
			)
		)
	)
	(zone
		(layers "In1.Cu" "In2.Cu")
		(hatch none 0.5)
		(connect_pads
			(clearance 0)
		)
		(min_thickness 0.25)
		(keepout
			(tracks not_allowed)
			(vias allowed)
			(pads allowed)
			(copperpour not_allowed)
			(footprints allowed)
		)
		(placement
			(enabled no)
			(sheetname "")
		)
		(fill yes
			(thermal_gap 0.5)
			(thermal_bridge_width 0.5)
			(island_removal_mode 0)
		)
		(polygon
			(pts
				(arc
					(start 259.430266 -313.971432)
					(mid 259.445145 -314.007353)
					(end 259.481066 -314.022232)
				)
				(arc
					(start 260.880606 -314.022232)
					(mid 260.916527 -314.007353)
					(end 260.931406 -313.971432)
				)
				(arc
					(start 260.931406 -313.562492)
					(mid 260.916527 -313.526571)
					(end 260.880606 -313.511692)
				)
				(arc
					(start 259.481066 -313.511692)
					(mid 259.445145 -313.526571)
					(end 259.430266 -313.562492)
				)
			)
		)
	)
	(zone
		(layers "In1.Cu" "In2.Cu")
		(hatch none 0.5)
		(connect_pads
			(clearance 0)
		)
		(min_thickness 0.25)
		(keepout
			(tracks not_allowed)
			(vias allowed)
			(pads allowed)
			(copperpour not_allowed)
			(footprints allowed)
		)
		(placement
			(enabled no)
			(sheetname "")
		)
		(fill yes
			(thermal_gap 0.5)
			(thermal_bridge_width 0.5)
			(island_removal_mode 0)
		)
		(polygon
			(pts
				(arc
					(start 34.121598 -295.271444)
					(mid 34.136477 -295.307365)
					(end 34.172398 -295.322244)
				)
				(arc
					(start 35.571938 -295.322244)
					(mid 35.607859 -295.307365)
					(end 35.622738 -295.271444)
				)
				(arc
					(start 35.622738 -294.862504)
					(mid 35.607859 -294.826583)
					(end 35.571938 -294.811704)
				)
				(arc
					(start 34.172398 -294.811704)
					(mid 34.136477 -294.826583)
					(end 34.121598 -294.862504)
				)
			)
		)
	)
	(zone
		(layers "In1.Cu" "In2.Cu")
		(hatch none 0.5)
		(connect_pads
			(clearance 0)
		)
		(min_thickness 0.25)
		(keepout
			(tracks not_allowed)
			(vias allowed)
			(pads allowed)
			(copperpour not_allowed)
			(footprints allowed)
		)
		(placement
			(enabled no)
			(sheetname "")
		)
		(fill yes
			(thermal_gap 0.5)
			(thermal_bridge_width 0.5)
			(island_removal_mode 0)
		)
		(polygon
			(pts
				(arc
					(start 462.909666 -295.271444)
					(mid 462.924545 -295.307365)
					(end 462.960466 -295.322244)
				)
				(arc
					(start 464.360006 -295.322244)
					(mid 464.395927 -295.307365)
					(end 464.410806 -295.271444)
				)
				(arc
					(start 464.410806 -294.862504)
					(mid 464.395927 -294.826583)
					(end 464.360006 -294.811704)
				)
				(arc
					(start 462.960466 -294.811704)
					(mid 462.924545 -294.826583)
					(end 462.909666 -294.862504)
				)
			)
		)
	)
	(zone
		(layers "In1.Cu" "In2.Cu")
		(hatch none 0.5)
		(connect_pads
			(clearance 0)
		)
		(min_thickness 0.25)
		(keepout
			(tracks not_allowed)
			(vias allowed)
			(pads allowed)
			(copperpour not_allowed)
			(footprints allowed)
		)
		(placement
			(enabled no)
			(sheetname "")
		)
		(fill yes
			(thermal_gap 0.5)
			(thermal_bridge_width 0.5)
			(island_removal_mode 0)
		)
		(polygon
			(pts
				(arc
					(start 37.56533 -234.071414)
					(mid 37.580209 -234.107335)
					(end 37.61613 -234.122214)
				)
				(arc
					(start 39.01567 -234.122214)
					(mid 39.051591 -234.107335)
					(end 39.06647 -234.071414)
				)
				(arc
					(start 39.06647 -233.662474)
					(mid 39.051591 -233.626553)
					(end 39.01567 -233.611674)
				)
				(arc
					(start 37.61613 -233.611674)
					(mid 37.580209 -233.626553)
					(end 37.56533 -233.662474)
				)
			)
		)
	)
	(zone
		(layers "In1.Cu" "In2.Cu")
		(hatch none 0.5)
		(connect_pads
			(clearance 0)
		)
		(min_thickness 0.25)
		(keepout
			(tracks not_allowed)
			(vias allowed)
			(pads allowed)
			(copperpour not_allowed)
			(footprints allowed)
		)
		(placement
			(enabled no)
			(sheetname "")
		)
		(fill yes
			(thermal_gap 0.5)
			(thermal_bridge_width 0.5)
			(island_removal_mode 0)
		)
		(polygon
			(pts
				(arc
					(start 195.78193 -238.321342)
					(mid 195.796809 -238.357263)
					(end 195.83273 -238.372142)
				)
				(arc
					(start 197.23227 -238.372142)
					(mid 197.268191 -238.357263)
					(end 197.28307 -238.321342)
				)
				(arc
					(start 197.28307 -237.912402)
					(mid 197.268191 -237.876481)
					(end 197.23227 -237.861602)
				)
				(arc
					(start 195.83273 -237.861602)
					(mid 195.796809 -237.876481)
					(end 195.78193 -237.912402)
				)
			)
		)
	)
	(zone
		(layers "In1.Cu" "In2.Cu")
		(hatch none 0.5)
		(connect_pads
			(clearance 0)
		)
		(min_thickness 0.25)
		(keepout
			(tracks not_allowed)
			(vias allowed)
			(pads allowed)
			(copperpour not_allowed)
			(footprints allowed)
		)
		(placement
			(enabled no)
			(sheetname "")
		)
		(fill yes
			(thermal_gap 0.5)
			(thermal_bridge_width 0.5)
			(island_removal_mode 0)
		)
		(polygon
			(pts
				(arc
					(start 188.23813 -302.921416)
					(mid 188.253009 -302.957337)
					(end 188.28893 -302.972216)
				)
				(arc
					(start 189.68847 -302.972216)
					(mid 189.724391 -302.957337)
					(end 189.73927 -302.921416)
				)
				(arc
					(start 189.73927 -302.512476)
					(mid 189.724391 -302.476555)
					(end 189.68847 -302.461676)
				)
				(arc
					(start 188.28893 -302.461676)
					(mid 188.253009 -302.476555)
					(end 188.23813 -302.512476)
				)
			)
		)
	)
	(zone
		(layers "In1.Cu" "In2.Cu")
		(hatch none 0.5)
		(connect_pads
			(clearance 0)
		)
		(min_thickness 0.25)
		(keepout
			(tracks not_allowed)
			(vias allowed)
			(pads allowed)
			(copperpour not_allowed)
			(footprints allowed)
		)
		(placement
			(enabled no)
			(sheetname "")
		)
		(fill yes
			(thermal_gap 0.5)
			(thermal_bridge_width 0.5)
			(island_removal_mode 0)
		)
		(polygon
			(pts
				(arc
					(start 26.577798 -259.57149)
					(mid 26.592677 -259.607411)
					(end 26.628598 -259.62229)
				)
				(arc
					(start 28.028138 -259.62229)
					(mid 28.064059 -259.607411)
					(end 28.078938 -259.57149)
				)
				(arc
					(start 28.078938 -259.16255)
					(mid 28.064059 -259.126629)
					(end 28.028138 -259.11175)
				)
				(arc
					(start 26.628598 -259.11175)
					(mid 26.592677 -259.126629)
					(end 26.577798 -259.16255)
				)
			)
		)
	)
	(zone
		(layers "In1.Cu" "In2.Cu")
		(hatch none 0.5)
		(connect_pads
			(clearance 0)
		)
		(min_thickness 0.25)
		(keepout
			(tracks not_allowed)
			(vias allowed)
			(pads allowed)
			(copperpour not_allowed)
			(footprints allowed)
		)
		(placement
			(enabled no)
			(sheetname "")
		)
		(fill yes
			(thermal_gap 0.5)
			(thermal_bridge_width 0.5)
			(island_removal_mode 0)
		)
		(polygon
			(pts
				(arc
					(start 297.149266 -260.421374)
					(mid 297.164145 -260.457295)
					(end 297.200066 -260.472174)
				)
				(arc
					(start 298.599606 -260.472174)
					(mid 298.635527 -260.457295)
					(end 298.650406 -260.421374)
				)
				(arc
					(start 298.650406 -260.012434)
					(mid 298.635527 -259.976513)
					(end 298.599606 -259.961634)
				)
				(arc
					(start 297.200066 -259.961634)
					(mid 297.164145 -259.976513)
					(end 297.149266 -260.012434)
				)
			)
		)
	)
	(zone
		(layers "In1.Cu" "In2.Cu")
		(hatch none 0.5)
		(connect_pads
			(clearance 0)
		)
		(min_thickness 0.25)
		(keepout
			(tracks not_allowed)
			(vias allowed)
			(pads allowed)
			(copperpour not_allowed)
			(footprints allowed)
		)
		(placement
			(enabled no)
			(sheetname "")
		)
		(fill yes
			(thermal_gap 0.5)
			(thermal_bridge_width 0.5)
			(island_removal_mode 0)
		)
		(polygon
			(pts
				(arc
					(start 300.592998 -294.421306)
					(mid 300.607877 -294.457227)
					(end 300.643798 -294.472106)
				)
				(arc
					(start 302.043338 -294.472106)
					(mid 302.079259 -294.457227)
					(end 302.094138 -294.421306)
				)
				(arc
					(start 302.094138 -294.012366)
					(mid 302.079259 -293.976445)
					(end 302.043338 -293.961566)
				)
				(arc
					(start 300.643798 -293.961566)
					(mid 300.607877 -293.976445)
					(end 300.592998 -294.012366)
				)
			)
		)
	)
	(zone
		(layers "In1.Cu" "In2.Cu")
		(hatch none 0.5)
		(connect_pads
			(clearance 0)
		)
		(min_thickness 0.25)
		(keepout
			(tracks not_allowed)
			(vias allowed)
			(pads allowed)
			(copperpour not_allowed)
			(footprints allowed)
		)
		(placement
			(enabled no)
			(sheetname "")
		)
		(fill yes
			(thermal_gap 0.5)
			(thermal_bridge_width 0.5)
			(island_removal_mode 0)
		)
		(polygon
			(pts
				(arc
					(start 19.033998 -270.621506)
					(mid 19.048877 -270.657427)
					(end 19.084798 -270.672306)
				)
				(arc
					(start 20.484338 -270.672306)
					(mid 20.520259 -270.657427)
					(end 20.535138 -270.621506)
				)
				(arc
					(start 20.535138 -270.212566)
					(mid 20.520259 -270.176645)
					(end 20.484338 -270.161766)
				)
				(arc
					(start 19.084798 -270.161766)
					(mid 19.048877 -270.176645)
					(end 19.033998 -270.212566)
				)
			)
		)
	)
	(zone
		(layers "In1.Cu" "In2.Cu")
		(hatch none 0.5)
		(connect_pads
			(clearance 0)
		)
		(min_thickness 0.25)
		(keepout
			(tracks not_allowed)
			(vias allowed)
			(pads allowed)
			(copperpour not_allowed)
			(footprints allowed)
		)
		(placement
			(enabled no)
			(sheetname "")
		)
		(fill yes
			(thermal_gap 0.5)
			(thermal_bridge_width 0.5)
			(island_removal_mode 0)
		)
		(polygon
			(pts
				(arc
					(start 455.365866 -208.571338)
					(mid 455.380745 -208.607259)
					(end 455.416666 -208.622138)
				)
				(arc
					(start 456.816206 -208.622138)
					(mid 456.852127 -208.607259)
					(end 456.867006 -208.571338)
				)
				(arc
					(start 456.867006 -208.162398)
					(mid 456.852127 -208.126477)
					(end 456.816206 -208.111598)
				)
				(arc
					(start 455.416666 -208.111598)
					(mid 455.380745 -208.126477)
					(end 455.365866 -208.162398)
				)
			)
		)
	)
	(zone
		(layers "In1.Cu" "In2.Cu")
		(hatch none 0.5)
		(connect_pads
			(clearance 0)
		)
		(min_thickness 0.25)
		(keepout
			(tracks not_allowed)
			(vias allowed)
			(pads allowed)
			(copperpour not_allowed)
			(footprints allowed)
		)
		(placement
			(enabled no)
			(sheetname "")
		)
		(fill yes
			(thermal_gap 0.5)
			(thermal_bridge_width 0.5)
			(island_removal_mode 0)
		)
		(polygon
			(pts
				(arc
					(start 210.86953 -235.771436)
					(mid 210.884409 -235.807357)
					(end 210.92033 -235.822236)
				)
				(arc
					(start 212.31987 -235.822236)
					(mid 212.355791 -235.807357)
					(end 212.37067 -235.771436)
				)
				(arc
					(start 212.37067 -235.362496)
					(mid 212.355791 -235.326575)
					(end 212.31987 -235.311696)
				)
				(arc
					(start 210.92033 -235.311696)
					(mid 210.884409 -235.326575)
					(end 210.86953 -235.362496)
				)
			)
		)
	)
	(zone
		(layers "In1.Cu" "In2.Cu")
		(hatch none 0.5)
		(connect_pads
			(clearance 0)
		)
		(min_thickness 0.25)
		(keepout
			(tracks not_allowed)
			(vias allowed)
			(pads allowed)
			(copperpour not_allowed)
			(footprints allowed)
		)
		(placement
			(enabled no)
			(sheetname "")
		)
		(fill yes
			(thermal_gap 0.5)
			(thermal_bridge_width 0.5)
			(island_removal_mode 0)
		)
		(polygon
			(pts
				(arc
					(start 158.06293 -264.671302)
					(mid 158.077809 -264.707223)
					(end 158.11373 -264.722102)
				)
				(arc
					(start 159.51327 -264.722102)
					(mid 159.549191 -264.707223)
					(end 159.56407 -264.671302)
				)
				(arc
					(start 159.56407 -264.262362)
					(mid 159.549191 -264.226441)
					(end 159.51327 -264.211562)
				)
				(arc
					(start 158.11373 -264.211562)
					(mid 158.077809 -264.226441)
					(end 158.06293 -264.262362)
				)
			)
		)
	)
	(zone
		(layers "In1.Cu" "In2.Cu")
		(hatch none 0.5)
		(connect_pads
			(clearance 0)
		)
		(min_thickness 0.25)
		(keepout
			(tracks not_allowed)
			(vias allowed)
			(pads allowed)
			(copperpour not_allowed)
			(footprints allowed)
		)
		(placement
			(enabled no)
			(sheetname "")
		)
		(fill yes
			(thermal_gap 0.5)
			(thermal_bridge_width 0.5)
			(island_removal_mode 0)
		)
		(polygon
			(pts
				(arc
					(start 56.752998 -212.82152)
					(mid 56.767877 -212.857441)
					(end 56.803798 -212.87232)
				)
				(arc
					(start 58.203338 -212.87232)
					(mid 58.239259 -212.857441)
					(end 58.254138 -212.82152)
				)
				(arc
					(start 58.254138 -212.41258)
					(mid 58.239259 -212.376659)
					(end 58.203338 -212.36178)
				)
				(arc
					(start 56.803798 -212.36178)
					(mid 56.767877 -212.376659)
					(end 56.752998 -212.41258)
				)
			)
		)
	)
	(zone
		(layers "In1.Cu" "In2.Cu")
		(hatch none 0.5)
		(connect_pads
			(clearance 0)
		)
		(min_thickness 0.25)
		(keepout
			(tracks not_allowed)
			(vias allowed)
			(pads allowed)
			(copperpour not_allowed)
			(footprints allowed)
		)
		(placement
			(enabled no)
			(sheetname "")
		)
		(fill yes
			(thermal_gap 0.5)
			(thermal_bridge_width 0.5)
			(island_removal_mode 0)
		)
		(polygon
			(pts
				(arc
					(start 195.78193 -230.67137)
					(mid 195.796809 -230.707291)
					(end 195.83273 -230.72217)
				)
				(arc
					(start 197.23227 -230.72217)
					(mid 197.268191 -230.707291)
					(end 197.28307 -230.67137)
				)
				(arc
					(start 197.28307 -230.26243)
					(mid 197.268191 -230.226509)
					(end 197.23227 -230.21163)
				)
				(arc
					(start 195.83273 -230.21163)
					(mid 195.796809 -230.226509)
					(end 195.78193 -230.26243)
				)
			)
		)
	)
	(zone
		(layers "In1.Cu" "In2.Cu")
		(hatch none 0.5)
		(connect_pads
			(clearance 0)
		)
		(min_thickness 0.25)
		(keepout
			(tracks not_allowed)
			(vias allowed)
			(pads allowed)
			(copperpour not_allowed)
			(footprints allowed)
		)
		(placement
			(enabled no)
			(sheetname "")
		)
		(fill yes
			(thermal_gap 0.5)
			(thermal_bridge_width 0.5)
			(island_removal_mode 0)
		)
		(polygon
			(pts
				(arc
					(start 425.190666 -276.571456)
					(mid 425.205545 -276.607377)
					(end 425.241466 -276.622256)
				)
				(arc
					(start 426.641006 -276.622256)
					(mid 426.676927 -276.607377)
					(end 426.691806 -276.571456)
				)
				(arc
					(start 426.691806 -276.162516)
					(mid 426.676927 -276.126595)
					(end 426.641006 -276.111716)
				)
				(arc
					(start 425.241466 -276.111716)
					(mid 425.205545 -276.126595)
					(end 425.190666 -276.162516)
				)
			)
		)
	)
	(zone
		(layers "In1.Cu" "In2.Cu")
		(hatch none 0.5)
		(connect_pads
			(clearance 0)
		)
		(min_thickness 0.25)
		(keepout
			(tracks not_allowed)
			(vias allowed)
			(pads allowed)
			(copperpour not_allowed)
			(footprints allowed)
		)
		(placement
			(enabled no)
			(sheetname "")
		)
		(fill yes
			(thermal_gap 0.5)
			(thermal_bridge_width 0.5)
			(island_removal_mode 0)
		)
		(polygon
			(pts
				(arc
					(start 308.136798 -210.27136)
					(mid 308.151677 -210.307281)
					(end 308.187598 -210.32216)
				)
				(arc
					(start 309.587138 -210.32216)
					(mid 309.623059 -210.307281)
					(end 309.637938 -210.27136)
				)
				(arc
					(start 309.637938 -209.86242)
					(mid 309.623059 -209.826499)
					(end 309.587138 -209.81162)
				)
				(arc
					(start 308.187598 -209.81162)
					(mid 308.151677 -209.826499)
					(end 308.136798 -209.86242)
				)
			)
		)
	)
	(zone
		(layers "In1.Cu" "In2.Cu")
		(hatch none 0.5)
		(connect_pads
			(clearance 0)
		)
		(min_thickness 0.25)
		(keepout
			(tracks not_allowed)
			(vias allowed)
			(pads allowed)
			(copperpour not_allowed)
			(footprints allowed)
		)
		(placement
			(enabled no)
			(sheetname "")
		)
		(fill yes
			(thermal_gap 0.5)
			(thermal_bridge_width 0.5)
			(island_removal_mode 0)
		)
		(polygon
			(pts
				(arc
					(start 214.969598 -234.921298)
					(mid 214.984477 -234.957219)
					(end 215.020398 -234.972098)
				)
				(arc
					(start 216.419938 -234.972098)
					(mid 216.455859 -234.957219)
					(end 216.470738 -234.921298)
				)
				(arc
					(start 216.470738 -234.512358)
					(mid 216.455859 -234.476437)
					(end 216.419938 -234.461558)
				)
				(arc
					(start 215.020398 -234.461558)
					(mid 214.984477 -234.476437)
					(end 214.969598 -234.512358)
				)
			)
		)
	)
	(zone
		(layers "In1.Cu" "In2.Cu")
		(hatch none 0.5)
		(connect_pads
			(clearance 0)
		)
		(min_thickness 0.25)
		(keepout
			(tracks not_allowed)
			(vias allowed)
			(pads allowed)
			(copperpour not_allowed)
			(footprints allowed)
		)
		(placement
			(enabled no)
			(sheetname "")
		)
		(fill yes
			(thermal_gap 0.5)
			(thermal_bridge_width 0.5)
			(island_removal_mode 0)
		)
		(polygon
			(pts
				(arc
					(start 297.149266 -217.921332)
					(mid 297.164145 -217.957253)
					(end 297.200066 -217.972132)
				)
				(arc
					(start 298.599606 -217.972132)
					(mid 298.635527 -217.957253)
					(end 298.650406 -217.921332)
				)
				(arc
					(start 298.650406 -217.512392)
					(mid 298.635527 -217.476471)
					(end 298.599606 -217.461592)
				)
				(arc
					(start 297.200066 -217.461592)
					(mid 297.164145 -217.476471)
					(end 297.149266 -217.512392)
				)
			)
		)
	)
	(zone
		(layers "In1.Cu" "In2.Cu")
		(hatch none 0.5)
		(connect_pads
			(clearance 0)
		)
		(min_thickness 0.25)
		(keepout
			(tracks not_allowed)
			(vias allowed)
			(pads allowed)
			(copperpour not_allowed)
			(footprints allowed)
		)
		(placement
			(enabled no)
			(sheetname "")
		)
		(fill yes
			(thermal_gap 0.5)
			(thermal_bridge_width 0.5)
			(island_removal_mode 0)
		)
		(polygon
			(pts
				(arc
					(start 277.961598 -215.371426)
					(mid 277.976477 -215.407347)
					(end 278.012398 -215.422226)
				)
				(arc
					(start 279.411938 -215.422226)
					(mid 279.447859 -215.407347)
					(end 279.462738 -215.371426)
				)
				(arc
					(start 279.462738 -214.962486)
					(mid 279.447859 -214.926565)
					(end 279.411938 -214.911686)
				)
				(arc
					(start 278.012398 -214.911686)
					(mid 277.976477 -214.926565)
					(end 277.961598 -214.962486)
				)
			)
		)
	)
	(zone
		(layers "In1.Cu" "In2.Cu")
		(hatch none 0.5)
		(connect_pads
			(clearance 0)
		)
		(min_thickness 0.25)
		(keepout
			(tracks not_allowed)
			(vias allowed)
			(pads allowed)
			(copperpour not_allowed)
			(footprints allowed)
		)
		(placement
			(enabled no)
			(sheetname "")
		)
		(fill yes
			(thermal_gap 0.5)
			(thermal_bridge_width 0.5)
			(island_removal_mode 0)
		)
		(polygon
			(pts
				(arc
					(start 462.909666 -279.9715)
					(mid 462.924545 -280.007421)
					(end 462.960466 -280.0223)
				)
				(arc
					(start 464.360006 -280.0223)
					(mid 464.395927 -280.007421)
					(end 464.410806 -279.9715)
				)
				(arc
					(start 464.410806 -279.56256)
					(mid 464.395927 -279.526639)
					(end 464.360006 -279.51176)
				)
				(arc
					(start 462.960466 -279.51176)
					(mid 462.924545 -279.526639)
					(end 462.909666 -279.56256)
				)
			)
		)
	)
	(zone
		(layers "In1.Cu" "In2.Cu")
		(hatch none 0.5)
		(connect_pads
			(clearance 0)
		)
		(min_thickness 0.25)
		(keepout
			(tracks not_allowed)
			(vias allowed)
			(pads allowed)
			(copperpour not_allowed)
			(footprints allowed)
		)
		(placement
			(enabled no)
			(sheetname "")
		)
		(fill yes
			(thermal_gap 0.5)
			(thermal_bridge_width 0.5)
			(island_removal_mode 0)
		)
		(polygon
			(pts
				(arc
					(start 158.06293 -219.621354)
					(mid 158.077809 -219.657275)
					(end 158.11373 -219.672154)
				)
				(arc
					(start 159.51327 -219.672154)
					(mid 159.549191 -219.657275)
					(end 159.56407 -219.621354)
				)
				(arc
					(start 159.56407 -219.212414)
					(mid 159.549191 -219.176493)
					(end 159.51327 -219.161614)
				)
				(arc
					(start 158.11373 -219.161614)
					(mid 158.077809 -219.176493)
					(end 158.06293 -219.212414)
				)
			)
		)
	)
	(zone
		(layers "In1.Cu" "In2.Cu")
		(hatch none 0.5)
		(connect_pads
			(clearance 0)
		)
		(min_thickness 0.25)
		(keepout
			(tracks not_allowed)
			(vias allowed)
			(pads allowed)
			(copperpour not_allowed)
			(footprints allowed)
		)
		(placement
			(enabled no)
			(sheetname "")
		)
		(fill yes
			(thermal_gap 0.5)
			(thermal_bridge_width 0.5)
			(island_removal_mode 0)
		)
		(polygon
			(pts
				(arc
					(start 428.634398 -243.421408)
					(mid 428.649277 -243.457329)
					(end 428.685198 -243.472208)
				)
				(arc
					(start 430.084738 -243.472208)
					(mid 430.120659 -243.457329)
					(end 430.135538 -243.421408)
				)
				(arc
					(start 430.135538 -243.012468)
					(mid 430.120659 -242.976547)
					(end 430.084738 -242.961668)
				)
				(arc
					(start 428.685198 -242.961668)
					(mid 428.649277 -242.976547)
					(end 428.634398 -243.012468)
				)
			)
		)
	)
	(zone
		(layers "In1.Cu" "In2.Cu")
		(hatch none 0.5)
		(connect_pads
			(clearance 0)
		)
		(min_thickness 0.25)
		(keepout
			(tracks not_allowed)
			(vias allowed)
			(pads allowed)
			(copperpour not_allowed)
			(footprints allowed)
		)
		(placement
			(enabled no)
			(sheetname "")
		)
		(fill yes
			(thermal_gap 0.5)
			(thermal_bridge_width 0.5)
			(island_removal_mode 0)
		)
		(polygon
			(pts
				(arc
					(start 277.961598 -291.8714)
					(mid 277.976477 -291.907321)
					(end 278.012398 -291.9222)
				)
				(arc
					(start 279.411938 -291.9222)
					(mid 279.447859 -291.907321)
					(end 279.462738 -291.8714)
				)
				(arc
					(start 279.462738 -291.46246)
					(mid 279.447859 -291.426539)
					(end 279.411938 -291.41166)
				)
				(arc
					(start 278.012398 -291.41166)
					(mid 277.976477 -291.426539)
					(end 277.961598 -291.46246)
				)
			)
		)
	)
	(zone
		(layers "In1.Cu" "In2.Cu")
		(hatch none 0.5)
		(connect_pads
			(clearance 0)
		)
		(min_thickness 0.25)
		(keepout
			(tracks not_allowed)
			(vias allowed)
			(pads allowed)
			(copperpour not_allowed)
			(footprints allowed)
		)
		(placement
			(enabled no)
			(sheetname "")
		)
		(fill yes
			(thermal_gap 0.5)
			(thermal_bridge_width 0.5)
			(island_removal_mode 0)
		)
		(polygon
			(pts
				(arc
					(start 308.136798 -228.971348)
					(mid 308.151677 -229.007269)
					(end 308.187598 -229.022148)
				)
				(arc
					(start 309.587138 -229.022148)
					(mid 309.623059 -229.007269)
					(end 309.637938 -228.971348)
				)
				(arc
					(start 309.637938 -228.562408)
					(mid 309.623059 -228.526487)
					(end 309.587138 -228.511608)
				)
				(arc
					(start 308.187598 -228.511608)
					(mid 308.151677 -228.526487)
					(end 308.136798 -228.562408)
				)
			)
		)
	)
	(zone
		(layers "In1.Cu" "In2.Cu")
		(hatch none 0.5)
		(connect_pads
			(clearance 0)
		)
		(min_thickness 0.25)
		(keepout
			(tracks not_allowed)
			(vias allowed)
			(pads allowed)
			(copperpour not_allowed)
			(footprints allowed)
		)
		(placement
			(enabled no)
			(sheetname "")
		)
		(fill yes
			(thermal_gap 0.5)
			(thermal_bridge_width 0.5)
			(island_removal_mode 0)
		)
		(polygon
			(pts
				(arc
					(start 214.969598 -237.471458)
					(mid 214.984477 -237.507379)
					(end 215.020398 -237.522258)
				)
				(arc
					(start 216.419938 -237.522258)
					(mid 216.455859 -237.507379)
					(end 216.470738 -237.471458)
				)
				(arc
					(start 216.470738 -237.062518)
					(mid 216.455859 -237.026597)
					(end 216.419938 -237.011718)
				)
				(arc
					(start 215.020398 -237.011718)
					(mid 214.984477 -237.026597)
					(end 214.969598 -237.062518)
				)
			)
		)
	)
	(zone
		(layers "In1.Cu" "In2.Cu")
		(hatch none 0.5)
		(connect_pads
			(clearance 0)
		)
		(min_thickness 0.25)
		(keepout
			(tracks not_allowed)
			(vias allowed)
			(pads allowed)
			(copperpour not_allowed)
			(footprints allowed)
		)
		(placement
			(enabled no)
			(sheetname "")
		)
		(fill yes
			(thermal_gap 0.5)
			(thermal_bridge_width 0.5)
			(island_removal_mode 0)
		)
		(polygon
			(pts
				(arc
					(start 421.090598 -291.8714)
					(mid 421.105477 -291.907321)
					(end 421.141398 -291.9222)
				)
				(arc
					(start 422.540938 -291.9222)
					(mid 422.576859 -291.907321)
					(end 422.591738 -291.8714)
				)
				(arc
					(start 422.591738 -291.46246)
					(mid 422.576859 -291.426539)
					(end 422.540938 -291.41166)
				)
				(arc
					(start 421.141398 -291.41166)
					(mid 421.105477 -291.426539)
					(end 421.090598 -291.46246)
				)
			)
		)
	)
	(zone
		(layers "In1.Cu" "In2.Cu")
		(hatch none 0.5)
		(connect_pads
			(clearance 0)
		)
		(min_thickness 0.25)
		(keepout
			(tracks not_allowed)
			(vias allowed)
			(pads allowed)
			(copperpour not_allowed)
			(footprints allowed)
		)
		(placement
			(enabled no)
			(sheetname "")
		)
		(fill yes
			(thermal_gap 0.5)
			(thermal_bridge_width 0.5)
			(island_removal_mode 0)
		)
		(polygon
			(pts
				(arc
					(start 56.752998 -302.921416)
					(mid 56.767877 -302.957337)
					(end 56.803798 -302.972216)
				)
				(arc
					(start 58.203338 -302.972216)
					(mid 58.239259 -302.957337)
					(end 58.254138 -302.921416)
				)
				(arc
					(start 58.254138 -302.512476)
					(mid 58.239259 -302.476555)
					(end 58.203338 -302.461676)
				)
				(arc
					(start 56.803798 -302.461676)
					(mid 56.767877 -302.476555)
					(end 56.752998 -302.512476)
				)
			)
		)
	)
	(zone
		(layers "In1.Cu" "In2.Cu")
		(hatch none 0.5)
		(connect_pads
			(clearance 0)
		)
		(min_thickness 0.25)
		(keepout
			(tracks not_allowed)
			(vias allowed)
			(pads allowed)
			(copperpour not_allowed)
			(footprints allowed)
		)
		(placement
			(enabled no)
			(sheetname "")
		)
		(fill yes
			(thermal_gap 0.5)
			(thermal_bridge_width 0.5)
			(island_removal_mode 0)
		)
		(polygon
			(pts
				(arc
					(start 447.822066 -200.071482)
					(mid 447.836945 -200.107403)
					(end 447.872866 -200.122282)
				)
				(arc
					(start 449.272406 -200.122282)
					(mid 449.308327 -200.107403)
					(end 449.323206 -200.071482)
				)
				(arc
					(start 449.323206 -199.662542)
					(mid 449.308327 -199.626621)
					(end 449.272406 -199.611742)
				)
				(arc
					(start 447.872866 -199.611742)
					(mid 447.836945 -199.626621)
					(end 447.822066 -199.662542)
				)
			)
		)
	)
	(zone
		(layers "In1.Cu" "In2.Cu")
		(hatch none 0.5)
		(connect_pads
			(clearance 0)
		)
		(min_thickness 0.25)
		(keepout
			(tracks not_allowed)
			(vias allowed)
			(pads allowed)
			(copperpour not_allowed)
			(footprints allowed)
		)
		(placement
			(enabled no)
			(sheetname "")
		)
		(fill yes
			(thermal_gap 0.5)
			(thermal_bridge_width 0.5)
			(island_removal_mode 0)
		)
		(polygon
			(pts
				(arc
					(start 177.250598 -229.821486)
					(mid 177.265477 -229.857407)
					(end 177.301398 -229.872286)
				)
				(arc
					(start 178.700938 -229.872286)
					(mid 178.736859 -229.857407)
					(end 178.751738 -229.821486)
				)
				(arc
					(start 178.751738 -229.412546)
					(mid 178.736859 -229.376625)
					(end 178.700938 -229.361746)
				)
				(arc
					(start 177.301398 -229.361746)
					(mid 177.265477 -229.376625)
					(end 177.250598 -229.412546)
				)
			)
		)
	)
	(zone
		(layers "In1.Cu" "In2.Cu")
		(hatch none 0.5)
		(connect_pads
			(clearance 0)
		)
		(min_thickness 0.25)
		(keepout
			(tracks not_allowed)
			(vias allowed)
			(pads allowed)
			(copperpour not_allowed)
			(footprints allowed)
		)
		(placement
			(enabled no)
			(sheetname "")
		)
		(fill yes
			(thermal_gap 0.5)
			(thermal_bridge_width 0.5)
			(island_removal_mode 0)
		)
		(polygon
			(pts
				(arc
					(start 11.490198 -231.521508)
					(mid 11.505077 -231.557429)
					(end 11.540998 -231.572308)
				)
				(arc
					(start 12.940538 -231.572308)
					(mid 12.976459 -231.557429)
					(end 12.991338 -231.521508)
				)
				(arc
					(start 12.991338 -231.112568)
					(mid 12.976459 -231.076647)
					(end 12.940538 -231.061768)
				)
				(arc
					(start 11.540998 -231.061768)
					(mid 11.505077 -231.076647)
					(end 11.490198 -231.112568)
				)
			)
		)
	)
	(zone
		(layers "In1.Cu" "In2.Cu")
		(hatch none 0.5)
		(connect_pads
			(clearance 0)
		)
		(min_thickness 0.25)
		(keepout
			(tracks not_allowed)
			(vias allowed)
			(pads allowed)
			(copperpour not_allowed)
			(footprints allowed)
		)
		(placement
			(enabled no)
			(sheetname "")
		)
		(fill yes
			(thermal_gap 0.5)
			(thermal_bridge_width 0.5)
			(island_removal_mode 0)
		)
		(polygon
			(pts
				(arc
					(start 195.78193 -269.771368)
					(mid 195.796809 -269.807289)
					(end 195.83273 -269.822168)
				)
				(arc
					(start 197.23227 -269.822168)
					(mid 197.268191 -269.807289)
					(end 197.28307 -269.771368)
				)
				(arc
					(start 197.28307 -269.362428)
					(mid 197.268191 -269.326507)
					(end 197.23227 -269.311628)
				)
				(arc
					(start 195.83273 -269.311628)
					(mid 195.796809 -269.326507)
					(end 195.78193 -269.362428)
				)
			)
		)
	)
	(zone
		(layers "In1.Cu" "In2.Cu")
		(hatch none 0.5)
		(connect_pads
			(clearance 0)
		)
		(min_thickness 0.25)
		(keepout
			(tracks not_allowed)
			(vias allowed)
			(pads allowed)
			(copperpour not_allowed)
			(footprints allowed)
		)
		(placement
			(enabled no)
			(sheetname "")
		)
		(fill yes
			(thermal_gap 0.5)
			(thermal_bridge_width 0.5)
			(island_removal_mode 0)
		)
		(polygon
			(pts
				(arc
					(start 293.049198 -307.171344)
					(mid 293.064077 -307.207265)
					(end 293.099998 -307.222144)
				)
				(arc
					(start 294.499538 -307.222144)
					(mid 294.535459 -307.207265)
					(end 294.550338 -307.171344)
				)
				(arc
					(start 294.550338 -306.762404)
					(mid 294.535459 -306.726483)
					(end 294.499538 -306.711604)
				)
				(arc
					(start 293.099998 -306.711604)
					(mid 293.064077 -306.726483)
					(end 293.049198 -306.762404)
				)
			)
		)
	)
	(zone
		(layers "In1.Cu" "In2.Cu")
		(hatch none 0.5)
		(connect_pads
			(clearance 0)
		)
		(min_thickness 0.25)
		(keepout
			(tracks not_allowed)
			(vias allowed)
			(pads allowed)
			(copperpour not_allowed)
			(footprints allowed)
		)
		(placement
			(enabled no)
			(sheetname "")
		)
		(fill yes
			(thermal_gap 0.5)
			(thermal_bridge_width 0.5)
			(island_removal_mode 0)
		)
		(polygon
			(pts
				(arc
					(start 262.873998 -223.021398)
					(mid 262.888877 -223.057319)
					(end 262.924798 -223.072198)
				)
				(arc
					(start 264.324338 -223.072198)
					(mid 264.360259 -223.057319)
					(end 264.375138 -223.021398)
				)
				(arc
					(start 264.375138 -222.612458)
					(mid 264.360259 -222.576537)
					(end 264.324338 -222.561658)
				)
				(arc
					(start 262.924798 -222.561658)
					(mid 262.888877 -222.576537)
					(end 262.873998 -222.612458)
				)
			)
		)
	)
	(zone
		(layers "In1.Cu" "In2.Cu")
		(hatch none 0.5)
		(connect_pads
			(clearance 0)
		)
		(min_thickness 0.25)
		(keepout
			(tracks not_allowed)
			(vias allowed)
			(pads allowed)
			(copperpour not_allowed)
			(footprints allowed)
		)
		(placement
			(enabled no)
			(sheetname "")
		)
		(fill yes
			(thermal_gap 0.5)
			(thermal_bridge_width 0.5)
			(island_removal_mode 0)
		)
		(polygon
			(pts
				(arc
					(start 443.721998 -284.221428)
					(mid 443.736877 -284.257349)
					(end 443.772798 -284.272228)
				)
				(arc
					(start 445.172338 -284.272228)
					(mid 445.208259 -284.257349)
					(end 445.223138 -284.221428)
				)
				(arc
					(start 445.223138 -283.812488)
					(mid 445.208259 -283.776567)
					(end 445.172338 -283.761688)
				)
				(arc
					(start 443.772798 -283.761688)
					(mid 443.736877 -283.776567)
					(end 443.721998 -283.812488)
				)
			)
		)
	)
	(zone
		(layers "In1.Cu" "In2.Cu")
		(hatch none 0.5)
		(connect_pads
			(clearance 0)
		)
		(min_thickness 0.25)
		(keepout
			(tracks not_allowed)
			(vias allowed)
			(pads allowed)
			(copperpour not_allowed)
			(footprints allowed)
		)
		(placement
			(enabled no)
			(sheetname "")
		)
		(fill yes
			(thermal_gap 0.5)
			(thermal_bridge_width 0.5)
			(island_removal_mode 0)
		)
		(polygon
			(pts
				(arc
					(start 203.32573 -313.121294)
					(mid 203.340609 -313.157215)
					(end 203.37653 -313.172094)
				)
				(arc
					(start 204.77607 -313.172094)
					(mid 204.811991 -313.157215)
					(end 204.82687 -313.121294)
				)
				(arc
					(start 204.82687 -312.712354)
					(mid 204.811991 -312.676433)
					(end 204.77607 -312.661554)
				)
				(arc
					(start 203.37653 -312.661554)
					(mid 203.340609 -312.676433)
					(end 203.32573 -312.712354)
				)
			)
		)
	)
	(zone
		(layers "In1.Cu" "In2.Cu")
		(hatch none 0.5)
		(connect_pads
			(clearance 0)
		)
		(min_thickness 0.25)
		(keepout
			(tracks not_allowed)
			(vias allowed)
			(pads allowed)
			(copperpour not_allowed)
			(footprints allowed)
		)
		(placement
			(enabled no)
			(sheetname "")
		)
		(fill yes
			(thermal_gap 0.5)
			(thermal_bridge_width 0.5)
			(island_removal_mode 0)
		)
		(polygon
			(pts
				(arc
					(start 300.592998 -305.471322)
					(mid 300.607877 -305.507243)
					(end 300.643798 -305.522122)
				)
				(arc
					(start 302.043338 -305.522122)
					(mid 302.079259 -305.507243)
					(end 302.094138 -305.471322)
				)
				(arc
					(start 302.094138 -305.062382)
					(mid 302.079259 -305.026461)
					(end 302.043338 -305.011582)
				)
				(arc
					(start 300.643798 -305.011582)
					(mid 300.607877 -305.026461)
					(end 300.592998 -305.062382)
				)
			)
		)
	)
	(zone
		(layers "In1.Cu" "In2.Cu")
		(hatch none 0.5)
		(connect_pads
			(clearance 0)
		)
		(min_thickness 0.25)
		(keepout
			(tracks not_allowed)
			(vias allowed)
			(pads allowed)
			(copperpour not_allowed)
			(footprints allowed)
		)
		(placement
			(enabled no)
			(sheetname "")
		)
		(fill yes
			(thermal_gap 0.5)
			(thermal_bridge_width 0.5)
			(island_removal_mode 0)
		)
		(polygon
			(pts
				(arc
					(start 266.974066 -302.921416)
					(mid 266.988945 -302.957337)
					(end 267.024866 -302.972216)
				)
				(arc
					(start 268.424406 -302.972216)
					(mid 268.460327 -302.957337)
					(end 268.475206 -302.921416)
				)
				(arc
					(start 268.475206 -302.512476)
					(mid 268.460327 -302.476555)
					(end 268.424406 -302.461676)
				)
				(arc
					(start 267.024866 -302.461676)
					(mid 266.988945 -302.476555)
					(end 266.974066 -302.512476)
				)
			)
		)
	)
	(zone
		(layers "In1.Cu" "In2.Cu")
		(hatch none 0.5)
		(connect_pads
			(clearance 0)
		)
		(min_thickness 0.25)
		(keepout
			(tracks not_allowed)
			(vias allowed)
			(pads allowed)
			(copperpour not_allowed)
			(footprints allowed)
		)
		(placement
			(enabled no)
			(sheetname "")
		)
		(fill yes
			(thermal_gap 0.5)
			(thermal_bridge_width 0.5)
			(island_removal_mode 0)
		)
		(polygon
			(pts
				(arc
					(start 421.090598 -196.671438)
					(mid 421.105477 -196.707359)
					(end 421.141398 -196.722238)
				)
				(arc
					(start 422.540938 -196.722238)
					(mid 422.576859 -196.707359)
					(end 422.591738 -196.671438)
				)
				(arc
					(start 422.591738 -196.262498)
					(mid 422.576859 -196.226577)
					(end 422.540938 -196.211698)
				)
				(arc
					(start 421.141398 -196.211698)
					(mid 421.105477 -196.226577)
					(end 421.090598 -196.262498)
				)
			)
		)
	)
	(zone
		(layers "In1.Cu" "In2.Cu")
		(hatch none 0.5)
		(connect_pads
			(clearance 0)
		)
		(min_thickness 0.25)
		(keepout
			(tracks not_allowed)
			(vias allowed)
			(pads allowed)
			(copperpour not_allowed)
			(footprints allowed)
		)
		(placement
			(enabled no)
			(sheetname "")
		)
		(fill yes
			(thermal_gap 0.5)
			(thermal_bridge_width 0.5)
			(island_removal_mode 0)
		)
		(polygon
			(pts
				(arc
					(start 207.425798 -315.671454)
					(mid 207.440677 -315.707375)
					(end 207.476598 -315.722254)
				)
				(arc
					(start 208.876138 -315.722254)
					(mid 208.912059 -315.707375)
					(end 208.926938 -315.671454)
				)
				(arc
					(start 208.926938 -315.262514)
					(mid 208.912059 -315.226593)
					(end 208.876138 -315.211714)
				)
				(arc
					(start 207.476598 -315.211714)
					(mid 207.440677 -315.226593)
					(end 207.425798 -315.262514)
				)
			)
		)
	)
	(zone
		(layers "In1.Cu" "In2.Cu")
		(hatch none 0.5)
		(connect_pads
			(clearance 0)
		)
		(min_thickness 0.25)
		(keepout
			(tracks not_allowed)
			(vias allowed)
			(pads allowed)
			(copperpour not_allowed)
			(footprints allowed)
		)
		(placement
			(enabled no)
			(sheetname "")
		)
		(fill yes
			(thermal_gap 0.5)
			(thermal_bridge_width 0.5)
			(island_removal_mode 0)
		)
		(polygon
			(pts
				(arc
					(start 34.121598 -281.671522)
					(mid 34.136477 -281.707443)
					(end 34.172398 -281.722322)
				)
				(arc
					(start 35.571938 -281.722322)
					(mid 35.607859 -281.707443)
					(end 35.622738 -281.671522)
				)
				(arc
					(start 35.622738 -281.262582)
					(mid 35.607859 -281.226661)
					(end 35.571938 -281.211782)
				)
				(arc
					(start 34.172398 -281.211782)
					(mid 34.136477 -281.226661)
					(end 34.121598 -281.262582)
				)
			)
		)
	)
	(zone
		(layers "In1.Cu" "In2.Cu")
		(hatch none 0.5)
		(connect_pads
			(clearance 0)
		)
		(min_thickness 0.25)
		(keepout
			(tracks not_allowed)
			(vias allowed)
			(pads allowed)
			(copperpour not_allowed)
			(footprints allowed)
		)
		(placement
			(enabled no)
			(sheetname "")
		)
		(fill yes
			(thermal_gap 0.5)
			(thermal_bridge_width 0.5)
			(island_removal_mode 0)
		)
		(polygon
			(pts
				(arc
					(start 162.162998 -251.921518)
					(mid 162.177877 -251.957439)
					(end 162.213798 -251.972318)
				)
				(arc
					(start 163.613338 -251.972318)
					(mid 163.649259 -251.957439)
					(end 163.664138 -251.921518)
				)
				(arc
					(start 163.664138 -251.512578)
					(mid 163.649259 -251.476657)
					(end 163.613338 -251.461778)
				)
				(arc
					(start 162.213798 -251.461778)
					(mid 162.177877 -251.476657)
					(end 162.162998 -251.512578)
				)
			)
		)
	)
	(zone
		(layers "In1.Cu" "In2.Cu")
		(hatch none 0.5)
		(connect_pads
			(clearance 0)
		)
		(min_thickness 0.25)
		(keepout
			(tracks not_allowed)
			(vias allowed)
			(pads allowed)
			(copperpour not_allowed)
			(footprints allowed)
		)
		(placement
			(enabled no)
			(sheetname "")
		)
		(fill yes
			(thermal_gap 0.5)
			(thermal_bridge_width 0.5)
			(island_removal_mode 0)
		)
		(polygon
			(pts
				(arc
					(start 169.706798 -295.271444)
					(mid 169.721677 -295.307365)
					(end 169.757598 -295.322244)
				)
				(arc
					(start 171.157138 -295.322244)
					(mid 171.193059 -295.307365)
					(end 171.207938 -295.271444)
				)
				(arc
					(start 171.207938 -294.862504)
					(mid 171.193059 -294.826583)
					(end 171.157138 -294.811704)
				)
				(arc
					(start 169.757598 -294.811704)
					(mid 169.721677 -294.826583)
					(end 169.706798 -294.862504)
				)
			)
		)
	)
	(zone
		(layers "In1.Cu" "In2.Cu")
		(hatch none 0.5)
		(connect_pads
			(clearance 0)
		)
		(min_thickness 0.25)
		(keepout
			(tracks not_allowed)
			(vias allowed)
			(pads allowed)
			(copperpour not_allowed)
			(footprints allowed)
		)
		(placement
			(enabled no)
			(sheetname "")
		)
		(fill yes
			(thermal_gap 0.5)
			(thermal_bridge_width 0.5)
			(island_removal_mode 0)
		)
		(polygon
			(pts
				(arc
					(start 432.734466 -283.371544)
					(mid 432.749345 -283.407465)
					(end 432.785266 -283.422344)
				)
				(arc
					(start 434.184806 -283.422344)
					(mid 434.220727 -283.407465)
					(end 434.235606 -283.371544)
				)
				(arc
					(start 434.235606 -282.962604)
					(mid 434.220727 -282.926683)
					(end 434.184806 -282.911804)
				)
				(arc
					(start 432.785266 -282.911804)
					(mid 432.749345 -282.926683)
					(end 432.734466 -282.962604)
				)
			)
		)
	)
	(zone
		(layers "In1.Cu" "In2.Cu")
		(hatch none 0.5)
		(connect_pads
			(clearance 0)
		)
		(min_thickness 0.25)
		(keepout
			(tracks not_allowed)
			(vias allowed)
			(pads allowed)
			(copperpour not_allowed)
			(footprints allowed)
		)
		(placement
			(enabled no)
			(sheetname "")
		)
		(fill yes
			(thermal_gap 0.5)
			(thermal_bridge_width 0.5)
			(island_removal_mode 0)
		)
		(polygon
			(pts
				(arc
					(start 417.646866 -209.421476)
					(mid 417.661745 -209.457397)
					(end 417.697666 -209.472276)
				)
				(arc
					(start 419.097206 -209.472276)
					(mid 419.133127 -209.457397)
					(end 419.148006 -209.421476)
				)
				(arc
					(start 419.148006 -209.012536)
					(mid 419.133127 -208.976615)
					(end 419.097206 -208.961736)
				)
				(arc
					(start 417.697666 -208.961736)
					(mid 417.661745 -208.976615)
					(end 417.646866 -209.012536)
				)
			)
		)
	)
	(zone
		(layers "In1.Cu" "In2.Cu")
		(hatch none 0.5)
		(connect_pads
			(clearance 0)
		)
		(min_thickness 0.25)
		(keepout
			(tracks not_allowed)
			(vias allowed)
			(pads allowed)
			(copperpour not_allowed)
			(footprints allowed)
		)
		(placement
			(enabled no)
			(sheetname "")
		)
		(fill yes
			(thermal_gap 0.5)
			(thermal_bridge_width 0.5)
			(island_removal_mode 0)
		)
		(polygon
			(pts
				(arc
					(start 207.425798 -295.271444)
					(mid 207.440677 -295.307365)
					(end 207.476598 -295.322244)
				)
				(arc
					(start 208.876138 -295.322244)
					(mid 208.912059 -295.307365)
					(end 208.926938 -295.271444)
				)
				(arc
					(start 208.926938 -294.862504)
					(mid 208.912059 -294.826583)
					(end 208.876138 -294.811704)
				)
				(arc
					(start 207.476598 -294.811704)
					(mid 207.440677 -294.826583)
					(end 207.425798 -294.862504)
				)
			)
		)
	)
	(zone
		(layers "In1.Cu" "In2.Cu")
		(hatch none 0.5)
		(connect_pads
			(clearance 0)
		)
		(min_thickness 0.25)
		(keepout
			(tracks not_allowed)
			(vias allowed)
			(pads allowed)
			(copperpour not_allowed)
			(footprints allowed)
		)
		(placement
			(enabled no)
			(sheetname "")
		)
		(fill yes
			(thermal_gap 0.5)
			(thermal_bridge_width 0.5)
			(island_removal_mode 0)
		)
		(polygon
			(pts
				(arc
					(start 285.505398 -296.121328)
					(mid 285.520277 -296.157249)
					(end 285.556198 -296.172128)
				)
				(arc
					(start 286.955738 -296.172128)
					(mid 286.991659 -296.157249)
					(end 287.006538 -296.121328)
				)
				(arc
					(start 287.006538 -295.712388)
					(mid 286.991659 -295.676467)
					(end 286.955738 -295.661588)
				)
				(arc
					(start 285.556198 -295.661588)
					(mid 285.520277 -295.676467)
					(end 285.505398 -295.712388)
				)
			)
		)
	)
	(zone
		(layers "In1.Cu" "In2.Cu")
		(hatch none 0.5)
		(connect_pads
			(clearance 0)
		)
		(min_thickness 0.25)
		(keepout
			(tracks not_allowed)
			(vias allowed)
			(pads allowed)
			(copperpour not_allowed)
			(footprints allowed)
		)
		(placement
			(enabled no)
			(sheetname "")
		)
		(fill yes
			(thermal_gap 0.5)
			(thermal_bridge_width 0.5)
			(island_removal_mode 0)
		)
		(polygon
			(pts
				(arc
					(start 297.149266 -225.571304)
					(mid 297.164145 -225.607225)
					(end 297.200066 -225.622104)
				)
				(arc
					(start 298.599606 -225.622104)
					(mid 298.635527 -225.607225)
					(end 298.650406 -225.571304)
				)
				(arc
					(start 298.650406 -225.162364)
					(mid 298.635527 -225.126443)
					(end 298.599606 -225.111564)
				)
				(arc
					(start 297.200066 -225.111564)
					(mid 297.164145 -225.126443)
					(end 297.149266 -225.162364)
				)
			)
		)
	)
	(zone
		(layers "In1.Cu" "In2.Cu")
		(hatch none 0.5)
		(connect_pads
			(clearance 0)
		)
		(min_thickness 0.25)
		(keepout
			(tracks not_allowed)
			(vias allowed)
			(pads allowed)
			(copperpour not_allowed)
			(footprints allowed)
		)
		(placement
			(enabled no)
			(sheetname "")
		)
		(fill yes
			(thermal_gap 0.5)
			(thermal_bridge_width 0.5)
			(island_removal_mode 0)
		)
		(polygon
			(pts
				(arc
					(start 428.634398 -213.671404)
					(mid 428.649277 -213.707325)
					(end 428.685198 -213.722204)
				)
				(arc
					(start 430.084738 -213.722204)
					(mid 430.120659 -213.707325)
					(end 430.135538 -213.671404)
				)
				(arc
					(start 430.135538 -213.262464)
					(mid 430.120659 -213.226543)
					(end 430.084738 -213.211664)
				)
				(arc
					(start 428.685198 -213.211664)
					(mid 428.649277 -213.226543)
					(end 428.634398 -213.262464)
				)
			)
		)
	)
	(zone
		(layers "In1.Cu" "In2.Cu")
		(hatch none 0.5)
		(connect_pads
			(clearance 0)
		)
		(min_thickness 0.25)
		(keepout
			(tracks not_allowed)
			(vias allowed)
			(pads allowed)
			(copperpour not_allowed)
			(footprints allowed)
		)
		(placement
			(enabled no)
			(sheetname "")
		)
		(fill yes
			(thermal_gap 0.5)
			(thermal_bridge_width 0.5)
			(island_removal_mode 0)
		)
		(polygon
			(pts
				(arc
					(start 56.752998 -298.671488)
					(mid 56.767877 -298.707409)
					(end 56.803798 -298.722288)
				)
				(arc
					(start 58.203338 -298.722288)
					(mid 58.239259 -298.707409)
					(end 58.254138 -298.671488)
				)
				(arc
					(start 58.254138 -298.262548)
					(mid 58.239259 -298.226627)
					(end 58.203338 -298.211748)
				)
				(arc
					(start 56.803798 -298.211748)
					(mid 56.767877 -298.226627)
					(end 56.752998 -298.262548)
				)
			)
		)
	)
	(zone
		(layers "In1.Cu" "In2.Cu")
		(hatch none 0.5)
		(connect_pads
			(clearance 0)
		)
		(min_thickness 0.25)
		(keepout
			(tracks not_allowed)
			(vias allowed)
			(pads allowed)
			(copperpour not_allowed)
			(footprints allowed)
		)
		(placement
			(enabled no)
			(sheetname "")
		)
		(fill yes
			(thermal_gap 0.5)
			(thermal_bridge_width 0.5)
			(island_removal_mode 0)
		)
		(polygon
			(pts
				(arc
					(start 64.296798 -212.82152)
					(mid 64.311677 -212.857441)
					(end 64.347598 -212.87232)
				)
				(arc
					(start 65.747138 -212.87232)
					(mid 65.783059 -212.857441)
					(end 65.797938 -212.82152)
				)
				(arc
					(start 65.797938 -212.41258)
					(mid 65.783059 -212.376659)
					(end 65.747138 -212.36178)
				)
				(arc
					(start 64.347598 -212.36178)
					(mid 64.311677 -212.376659)
					(end 64.296798 -212.41258)
				)
			)
		)
	)
	(zone
		(layers "In1.Cu" "In2.Cu")
		(hatch none 0.5)
		(connect_pads
			(clearance 0)
		)
		(min_thickness 0.25)
		(keepout
			(tracks not_allowed)
			(vias allowed)
			(pads allowed)
			(copperpour not_allowed)
			(footprints allowed)
		)
		(placement
			(enabled no)
			(sheetname "")
		)
		(fill yes
			(thermal_gap 0.5)
			(thermal_bridge_width 0.5)
			(island_removal_mode 0)
		)
		(polygon
			(pts
				(arc
					(start 293.049198 -290.171378)
					(mid 293.064077 -290.207299)
					(end 293.099998 -290.222178)
				)
				(arc
					(start 294.499538 -290.222178)
					(mid 294.535459 -290.207299)
					(end 294.550338 -290.171378)
				)
				(arc
					(start 294.550338 -289.762438)
					(mid 294.535459 -289.726517)
					(end 294.499538 -289.711638)
				)
				(arc
					(start 293.099998 -289.711638)
					(mid 293.064077 -289.726517)
					(end 293.049198 -289.762438)
				)
			)
		)
	)
	(zone
		(layers "In1.Cu" "In2.Cu")
		(hatch none 0.5)
		(connect_pads
			(clearance 0)
		)
		(min_thickness 0.25)
		(keepout
			(tracks not_allowed)
			(vias allowed)
			(pads allowed)
			(copperpour not_allowed)
			(footprints allowed)
		)
		(placement
			(enabled no)
			(sheetname "")
		)
		(fill yes
			(thermal_gap 0.5)
			(thermal_bridge_width 0.5)
			(island_removal_mode 0)
		)
		(polygon
			(pts
				(arc
					(start 207.425798 -245.12143)
					(mid 207.440677 -245.157351)
					(end 207.476598 -245.17223)
				)
				(arc
					(start 208.876138 -245.17223)
					(mid 208.912059 -245.157351)
					(end 208.926938 -245.12143)
				)
				(arc
					(start 208.926938 -244.71249)
					(mid 208.912059 -244.676569)
					(end 208.876138 -244.66169)
				)
				(arc
					(start 207.476598 -244.66169)
					(mid 207.440677 -244.676569)
					(end 207.425798 -244.71249)
				)
			)
		)
	)
	(zone
		(layers "In1.Cu" "In2.Cu")
		(hatch none 0.5)
		(connect_pads
			(clearance 0)
		)
		(min_thickness 0.25)
		(keepout
			(tracks not_allowed)
			(vias allowed)
			(pads allowed)
			(copperpour not_allowed)
			(footprints allowed)
		)
		(placement
			(enabled no)
			(sheetname "")
		)
		(fill yes
			(thermal_gap 0.5)
			(thermal_bridge_width 0.5)
			(island_removal_mode 0)
		)
		(polygon
			(pts
				(arc
					(start 417.646866 -248.521474)
					(mid 417.661745 -248.557395)
					(end 417.697666 -248.572274)
				)
				(arc
					(start 419.097206 -248.572274)
					(mid 419.133127 -248.557395)
					(end 419.148006 -248.521474)
				)
				(arc
					(start 419.148006 -248.112534)
					(mid 419.133127 -248.076613)
					(end 419.097206 -248.061734)
				)
				(arc
					(start 417.697666 -248.061734)
					(mid 417.661745 -248.076613)
					(end 417.646866 -248.112534)
				)
			)
		)
	)
	(zone
		(layers "In1.Cu" "In2.Cu")
		(hatch none 0.5)
		(connect_pads
			(clearance 0)
		)
		(min_thickness 0.25)
		(keepout
			(tracks not_allowed)
			(vias allowed)
			(pads allowed)
			(copperpour not_allowed)
			(footprints allowed)
		)
		(placement
			(enabled no)
			(sheetname "")
		)
		(fill yes
			(thermal_gap 0.5)
			(thermal_bridge_width 0.5)
			(island_removal_mode 0)
		)
		(polygon
			(pts
				(arc
					(start 406.002998 -312.27141)
					(mid 406.017877 -312.307331)
					(end 406.053798 -312.32221)
				)
				(arc
					(start 407.453338 -312.32221)
					(mid 407.489259 -312.307331)
					(end 407.504138 -312.27141)
				)
				(arc
					(start 407.504138 -311.86247)
					(mid 407.489259 -311.826549)
					(end 407.453338 -311.81167)
				)
				(arc
					(start 406.053798 -311.81167)
					(mid 406.017877 -311.826549)
					(end 406.002998 -311.86247)
				)
			)
		)
	)
	(zone
		(layers "In1.Cu" "In2.Cu")
		(hatch none 0.5)
		(connect_pads
			(clearance 0)
		)
		(min_thickness 0.25)
		(keepout
			(tracks not_allowed)
			(vias allowed)
			(pads allowed)
			(copperpour not_allowed)
			(footprints allowed)
		)
		(placement
			(enabled no)
			(sheetname "")
		)
		(fill yes
			(thermal_gap 0.5)
			(thermal_bridge_width 0.5)
			(island_removal_mode 0)
		)
		(polygon
			(pts
				(arc
					(start 262.873998 -252.771402)
					(mid 262.888877 -252.807323)
					(end 262.924798 -252.822202)
				)
				(arc
					(start 264.324338 -252.822202)
					(mid 264.360259 -252.807323)
					(end 264.375138 -252.771402)
				)
				(arc
					(start 264.375138 -252.362462)
					(mid 264.360259 -252.326541)
					(end 264.324338 -252.311662)
				)
				(arc
					(start 262.924798 -252.311662)
					(mid 262.888877 -252.326541)
					(end 262.873998 -252.362462)
				)
			)
		)
	)
	(zone
		(layers "In1.Cu" "In2.Cu")
		(hatch none 0.5)
		(connect_pads
			(clearance 0)
		)
		(min_thickness 0.25)
		(keepout
			(tracks not_allowed)
			(vias allowed)
			(pads allowed)
			(copperpour not_allowed)
			(footprints allowed)
		)
		(placement
			(enabled no)
			(sheetname "")
		)
		(fill yes
			(thermal_gap 0.5)
			(thermal_bridge_width 0.5)
			(island_removal_mode 0)
		)
		(polygon
			(pts
				(arc
					(start 428.634398 -238.321342)
					(mid 428.649277 -238.357263)
					(end 428.685198 -238.372142)
				)
				(arc
					(start 430.084738 -238.372142)
					(mid 430.120659 -238.357263)
					(end 430.135538 -238.321342)
				)
				(arc
					(start 430.135538 -237.912402)
					(mid 430.120659 -237.876481)
					(end 430.084738 -237.861602)
				)
				(arc
					(start 428.685198 -237.861602)
					(mid 428.649277 -237.876481)
					(end 428.634398 -237.912402)
				)
			)
		)
	)
	(zone
		(layers "In1.Cu" "In2.Cu")
		(hatch none 0.5)
		(connect_pads
			(clearance 0)
		)
		(min_thickness 0.25)
		(keepout
			(tracks not_allowed)
			(vias allowed)
			(pads allowed)
			(copperpour not_allowed)
			(footprints allowed)
		)
		(placement
			(enabled no)
			(sheetname "")
		)
		(fill yes
			(thermal_gap 0.5)
			(thermal_bridge_width 0.5)
			(island_removal_mode 0)
		)
		(polygon
			(pts
				(arc
					(start 282.061666 -284.221428)
					(mid 282.076545 -284.257349)
					(end 282.112466 -284.272228)
				)
				(arc
					(start 283.512006 -284.272228)
					(mid 283.547927 -284.257349)
					(end 283.562806 -284.221428)
				)
				(arc
					(start 283.562806 -283.812488)
					(mid 283.547927 -283.776567)
					(end 283.512006 -283.761688)
				)
				(arc
					(start 282.112466 -283.761688)
					(mid 282.076545 -283.776567)
					(end 282.061666 -283.812488)
				)
			)
		)
	)
	(zone
		(layers "In1.Cu" "In2.Cu")
		(hatch none 0.5)
		(connect_pads
			(clearance 0)
		)
		(min_thickness 0.25)
		(keepout
			(tracks not_allowed)
			(vias allowed)
			(pads allowed)
			(copperpour not_allowed)
			(footprints allowed)
		)
		(placement
			(enabled no)
			(sheetname "")
		)
		(fill yes
			(thermal_gap 0.5)
			(thermal_bridge_width 0.5)
			(island_removal_mode 0)
		)
		(polygon
			(pts
				(arc
					(start 22.47773 -303.7713)
					(mid 22.492609 -303.807221)
					(end 22.52853 -303.8221)
				)
				(arc
					(start 23.92807 -303.8221)
					(mid 23.963991 -303.807221)
					(end 23.97887 -303.7713)
				)
				(arc
					(start 23.97887 -303.36236)
					(mid 23.963991 -303.326439)
					(end 23.92807 -303.31156)
				)
				(arc
					(start 22.52853 -303.31156)
					(mid 22.492609 -303.326439)
					(end 22.47773 -303.36236)
				)
			)
		)
	)
	(zone
		(layers "In1.Cu" "In2.Cu")
		(hatch none 0.5)
		(connect_pads
			(clearance 0)
		)
		(min_thickness 0.25)
		(keepout
			(tracks not_allowed)
			(vias allowed)
			(pads allowed)
			(copperpour not_allowed)
			(footprints allowed)
		)
		(placement
			(enabled no)
			(sheetname "")
		)
		(fill yes
			(thermal_gap 0.5)
			(thermal_bridge_width 0.5)
			(island_removal_mode 0)
		)
		(polygon
			(pts
				(arc
					(start 173.15053 -301.221394)
					(mid 173.165409 -301.257315)
					(end 173.20133 -301.272194)
				)
				(arc
					(start 174.60087 -301.272194)
					(mid 174.636791 -301.257315)
					(end 174.65167 -301.221394)
				)
				(arc
					(start 174.65167 -300.812454)
					(mid 174.636791 -300.776533)
					(end 174.60087 -300.761654)
				)
				(arc
					(start 173.20133 -300.761654)
					(mid 173.165409 -300.776533)
					(end 173.15053 -300.812454)
				)
			)
		)
	)
	(zone
		(layers "In1.Cu" "In2.Cu")
		(hatch none 0.5)
		(connect_pads
			(clearance 0)
		)
		(min_thickness 0.25)
		(keepout
			(tracks not_allowed)
			(vias allowed)
			(pads allowed)
			(copperpour not_allowed)
			(footprints allowed)
		)
		(placement
			(enabled no)
			(sheetname "")
		)
		(fill yes
			(thermal_gap 0.5)
			(thermal_bridge_width 0.5)
			(island_removal_mode 0)
		)
		(polygon
			(pts
				(arc
					(start 266.974066 -296.971466)
					(mid 266.988945 -297.007387)
					(end 267.024866 -297.022266)
				)
				(arc
					(start 268.424406 -297.022266)
					(mid 268.460327 -297.007387)
					(end 268.475206 -296.971466)
				)
				(arc
					(start 268.475206 -296.562526)
					(mid 268.460327 -296.526605)
					(end 268.424406 -296.511726)
				)
				(arc
					(start 267.024866 -296.511726)
					(mid 266.988945 -296.526605)
					(end 266.974066 -296.562526)
				)
			)
		)
	)
	(zone
		(layers "In1.Cu" "In2.Cu")
		(hatch none 0.5)
		(connect_pads
			(clearance 0)
		)
		(min_thickness 0.25)
		(keepout
			(tracks not_allowed)
			(vias allowed)
			(pads allowed)
			(copperpour not_allowed)
			(footprints allowed)
		)
		(placement
			(enabled no)
			(sheetname "")
		)
		(fill yes
			(thermal_gap 0.5)
			(thermal_bridge_width 0.5)
			(island_removal_mode 0)
		)
		(polygon
			(pts
				(arc
					(start 270.417798 -294.421306)
					(mid 270.432677 -294.457227)
					(end 270.468598 -294.472106)
				)
				(arc
					(start 271.868138 -294.472106)
					(mid 271.904059 -294.457227)
					(end 271.918938 -294.421306)
				)
				(arc
					(start 271.918938 -294.012366)
					(mid 271.904059 -293.976445)
					(end 271.868138 -293.961566)
				)
				(arc
					(start 270.468598 -293.961566)
					(mid 270.432677 -293.976445)
					(end 270.417798 -294.012366)
				)
			)
		)
	)
	(zone
		(layers "In1.Cu" "In2.Cu")
		(hatch none 0.5)
		(connect_pads
			(clearance 0)
		)
		(min_thickness 0.25)
		(keepout
			(tracks not_allowed)
			(vias allowed)
			(pads allowed)
			(copperpour not_allowed)
			(footprints allowed)
		)
		(placement
			(enabled no)
			(sheetname "")
		)
		(fill yes
			(thermal_gap 0.5)
			(thermal_bridge_width 0.5)
			(island_removal_mode 0)
		)
		(polygon
			(pts
				(arc
					(start 440.278266 -236.62132)
					(mid 440.293145 -236.657241)
					(end 440.329066 -236.67212)
				)
				(arc
					(start 441.728606 -236.67212)
					(mid 441.764527 -236.657241)
					(end 441.779406 -236.62132)
				)
				(arc
					(start 441.779406 -236.21238)
					(mid 441.764527 -236.176459)
					(end 441.728606 -236.16158)
				)
				(arc
					(start 440.329066 -236.16158)
					(mid 440.293145 -236.176459)
					(end 440.278266 -236.21238)
				)
			)
		)
	)
	(zone
		(layers "In1.Cu" "In2.Cu")
		(hatch none 0.5)
		(connect_pads
			(clearance 0)
		)
		(min_thickness 0.25)
		(keepout
			(tracks not_allowed)
			(vias allowed)
			(pads allowed)
			(copperpour not_allowed)
			(footprints allowed)
		)
		(placement
			(enabled no)
			(sheetname "")
		)
		(fill yes
			(thermal_gap 0.5)
			(thermal_bridge_width 0.5)
			(island_removal_mode 0)
		)
		(polygon
			(pts
				(arc
					(start 417.646866 -237.471458)
					(mid 417.661745 -237.507379)
					(end 417.697666 -237.522258)
				)
				(arc
					(start 419.097206 -237.522258)
					(mid 419.133127 -237.507379)
					(end 419.148006 -237.471458)
				)
				(arc
					(start 419.148006 -237.062518)
					(mid 419.133127 -237.026597)
					(end 419.097206 -237.011718)
				)
				(arc
					(start 417.697666 -237.011718)
					(mid 417.661745 -237.026597)
					(end 417.646866 -237.062518)
				)
			)
		)
	)
	(zone
		(layers "In1.Cu" "In2.Cu")
		(hatch none 0.5)
		(connect_pads
			(clearance 0)
		)
		(min_thickness 0.25)
		(keepout
			(tracks not_allowed)
			(vias allowed)
			(pads allowed)
			(copperpour not_allowed)
			(footprints allowed)
		)
		(placement
			(enabled no)
			(sheetname "")
		)
		(fill yes
			(thermal_gap 0.5)
			(thermal_bridge_width 0.5)
			(island_removal_mode 0)
		)
		(polygon
			(pts
				(arc
					(start 7.39013 -211.971382)
					(mid 7.405009 -212.007303)
					(end 7.44093 -212.022182)
				)
				(arc
					(start 8.84047 -212.022182)
					(mid 8.876391 -212.007303)
					(end 8.89127 -211.971382)
				)
				(arc
					(start 8.89127 -211.562442)
					(mid 8.876391 -211.526521)
					(end 8.84047 -211.511642)
				)
				(arc
					(start 7.44093 -211.511642)
					(mid 7.405009 -211.526521)
					(end 7.39013 -211.562442)
				)
			)
		)
	)
	(zone
		(layers "In1.Cu" "In2.Cu")
		(hatch none 0.5)
		(connect_pads
			(clearance 0)
		)
		(min_thickness 0.25)
		(keepout
			(tracks not_allowed)
			(vias allowed)
			(pads allowed)
			(copperpour not_allowed)
			(footprints allowed)
		)
		(placement
			(enabled no)
			(sheetname "")
		)
		(fill yes
			(thermal_gap 0.5)
			(thermal_bridge_width 0.5)
			(island_removal_mode 0)
		)
		(polygon
			(pts
				(arc
					(start 7.39013 -301.221394)
					(mid 7.405009 -301.257315)
					(end 7.44093 -301.272194)
				)
				(arc
					(start 8.84047 -301.272194)
					(mid 8.876391 -301.257315)
					(end 8.89127 -301.221394)
				)
				(arc
					(start 8.89127 -300.812454)
					(mid 8.876391 -300.776533)
					(end 8.84047 -300.761654)
				)
				(arc
					(start 7.44093 -300.761654)
					(mid 7.405009 -300.776533)
					(end 7.39013 -300.812454)
				)
			)
		)
	)
	(zone
		(layers "In1.Cu" "In2.Cu")
		(hatch none 0.5)
		(connect_pads
			(clearance 0)
		)
		(min_thickness 0.25)
		(keepout
			(tracks not_allowed)
			(vias allowed)
			(pads allowed)
			(copperpour not_allowed)
			(footprints allowed)
		)
		(placement
			(enabled no)
			(sheetname "")
		)
		(fill yes
			(thermal_gap 0.5)
			(thermal_bridge_width 0.5)
			(island_removal_mode 0)
		)
		(polygon
			(pts
				(arc
					(start 277.961598 -301.221394)
					(mid 277.976477 -301.257315)
					(end 278.012398 -301.272194)
				)
				(arc
					(start 279.411938 -301.272194)
					(mid 279.447859 -301.257315)
					(end 279.462738 -301.221394)
				)
				(arc
					(start 279.462738 -300.812454)
					(mid 279.447859 -300.776533)
					(end 279.411938 -300.761654)
				)
				(arc
					(start 278.012398 -300.761654)
					(mid 277.976477 -300.776533)
					(end 277.961598 -300.812454)
				)
			)
		)
	)
	(zone
		(layers "In1.Cu" "In2.Cu")
		(hatch none 0.5)
		(connect_pads
			(clearance 0)
		)
		(min_thickness 0.25)
		(keepout
			(tracks not_allowed)
			(vias allowed)
			(pads allowed)
			(copperpour not_allowed)
			(footprints allowed)
		)
		(placement
			(enabled no)
			(sheetname "")
		)
		(fill yes
			(thermal_gap 0.5)
			(thermal_bridge_width 0.5)
			(island_removal_mode 0)
		)
		(polygon
			(pts
				(arc
					(start 308.136798 -271.47139)
					(mid 308.151677 -271.507311)
					(end 308.187598 -271.52219)
				)
				(arc
					(start 309.587138 -271.52219)
					(mid 309.623059 -271.507311)
					(end 309.637938 -271.47139)
				)
				(arc
					(start 309.637938 -271.06245)
					(mid 309.623059 -271.026529)
					(end 309.587138 -271.01165)
				)
				(arc
					(start 308.187598 -271.01165)
					(mid 308.151677 -271.026529)
					(end 308.136798 -271.06245)
				)
			)
		)
	)
	(zone
		(layers "In1.Cu" "In2.Cu")
		(hatch none 0.5)
		(connect_pads
			(clearance 0)
		)
		(min_thickness 0.25)
		(keepout
			(tracks not_allowed)
			(vias allowed)
			(pads allowed)
			(copperpour not_allowed)
			(footprints allowed)
		)
		(placement
			(enabled no)
			(sheetname "")
		)
		(fill yes
			(thermal_gap 0.5)
			(thermal_bridge_width 0.5)
			(island_removal_mode 0)
		)
		(polygon
			(pts
				(arc
					(start 64.296798 -237.471458)
					(mid 64.311677 -237.507379)
					(end 64.347598 -237.522258)
				)
				(arc
					(start 65.747138 -237.522258)
					(mid 65.783059 -237.507379)
					(end 65.797938 -237.471458)
				)
				(arc
					(start 65.797938 -237.062518)
					(mid 65.783059 -237.026597)
					(end 65.747138 -237.011718)
				)
				(arc
					(start 64.347598 -237.011718)
					(mid 64.311677 -237.026597)
					(end 64.296798 -237.062518)
				)
			)
		)
	)
	(zone
		(layers "In1.Cu" "In2.Cu")
		(hatch none 0.5)
		(connect_pads
			(clearance 0)
		)
		(min_thickness 0.25)
		(keepout
			(tracks not_allowed)
			(vias allowed)
			(pads allowed)
			(copperpour not_allowed)
			(footprints allowed)
		)
		(placement
			(enabled no)
			(sheetname "")
		)
		(fill yes
			(thermal_gap 0.5)
			(thermal_bridge_width 0.5)
			(island_removal_mode 0)
		)
		(polygon
			(pts
				(arc
					(start 455.365866 -308.021482)
					(mid 455.380745 -308.057403)
					(end 455.416666 -308.072282)
				)
				(arc
					(start 456.816206 -308.072282)
					(mid 456.852127 -308.057403)
					(end 456.867006 -308.021482)
				)
				(arc
					(start 456.867006 -307.612542)
					(mid 456.852127 -307.576621)
					(end 456.816206 -307.561742)
				)
				(arc
					(start 455.416666 -307.561742)
					(mid 455.380745 -307.576621)
					(end 455.365866 -307.612542)
				)
			)
		)
	)
	(zone
		(layers "In1.Cu" "In2.Cu")
		(hatch none 0.5)
		(connect_pads
			(clearance 0)
		)
		(min_thickness 0.25)
		(keepout
			(tracks not_allowed)
			(vias allowed)
			(pads allowed)
			(copperpour not_allowed)
			(footprints allowed)
		)
		(placement
			(enabled no)
			(sheetname "")
		)
		(fill yes
			(thermal_gap 0.5)
			(thermal_bridge_width 0.5)
			(island_removal_mode 0)
		)
		(polygon
			(pts
				(arc
					(start 304.693066 -302.921416)
					(mid 304.707945 -302.957337)
					(end 304.743866 -302.972216)
				)
				(arc
					(start 306.143406 -302.972216)
					(mid 306.179327 -302.957337)
					(end 306.194206 -302.921416)
				)
				(arc
					(start 306.194206 -302.512476)
					(mid 306.179327 -302.476555)
					(end 306.143406 -302.461676)
				)
				(arc
					(start 304.743866 -302.461676)
					(mid 304.707945 -302.476555)
					(end 304.693066 -302.512476)
				)
			)
		)
	)
	(zone
		(layers "In1.Cu" "In2.Cu")
		(hatch none 0.5)
		(connect_pads
			(clearance 0)
		)
		(min_thickness 0.25)
		(keepout
			(tracks not_allowed)
			(vias allowed)
			(pads allowed)
			(copperpour not_allowed)
			(footprints allowed)
		)
		(placement
			(enabled no)
			(sheetname "")
		)
		(fill yes
			(thermal_gap 0.5)
			(thermal_bridge_width 0.5)
			(island_removal_mode 0)
		)
		(polygon
			(pts
				(arc
					(start 158.06293 -269.771368)
					(mid 158.077809 -269.807289)
					(end 158.11373 -269.822168)
				)
				(arc
					(start 159.51327 -269.822168)
					(mid 159.549191 -269.807289)
					(end 159.56407 -269.771368)
				)
				(arc
					(start 159.56407 -269.362428)
					(mid 159.549191 -269.326507)
					(end 159.51327 -269.311628)
				)
				(arc
					(start 158.11373 -269.311628)
					(mid 158.077809 -269.326507)
					(end 158.06293 -269.362428)
				)
			)
		)
	)
	(zone
		(layers "In1.Cu" "In2.Cu")
		(hatch none 0.5)
		(connect_pads
			(clearance 0)
		)
		(min_thickness 0.25)
		(keepout
			(tracks not_allowed)
			(vias allowed)
			(pads allowed)
			(copperpour not_allowed)
			(footprints allowed)
		)
		(placement
			(enabled no)
			(sheetname "")
		)
		(fill yes
			(thermal_gap 0.5)
			(thermal_bridge_width 0.5)
			(island_removal_mode 0)
		)
		(polygon
			(pts
				(arc
					(start 432.734466 -298.671488)
					(mid 432.749345 -298.707409)
					(end 432.785266 -298.722288)
				)
				(arc
					(start 434.184806 -298.722288)
					(mid 434.220727 -298.707409)
					(end 434.235606 -298.671488)
				)
				(arc
					(start 434.235606 -298.262548)
					(mid 434.220727 -298.226627)
					(end 434.184806 -298.211748)
				)
				(arc
					(start 432.785266 -298.211748)
					(mid 432.749345 -298.226627)
					(end 432.734466 -298.262548)
				)
			)
		)
	)
	(zone
		(layers "In1.Cu" "In2.Cu")
		(hatch none 0.5)
		(connect_pads
			(clearance 0)
		)
		(min_thickness 0.25)
		(keepout
			(tracks not_allowed)
			(vias allowed)
			(pads allowed)
			(copperpour not_allowed)
			(footprints allowed)
		)
		(placement
			(enabled no)
			(sheetname "")
		)
		(fill yes
			(thermal_gap 0.5)
			(thermal_bridge_width 0.5)
			(island_removal_mode 0)
		)
		(polygon
			(pts
				(arc
					(start 207.425798 -229.821486)
					(mid 207.440677 -229.857407)
					(end 207.476598 -229.872286)
				)
				(arc
					(start 208.876138 -229.872286)
					(mid 208.912059 -229.857407)
					(end 208.926938 -229.821486)
				)
				(arc
					(start 208.926938 -229.412546)
					(mid 208.912059 -229.376625)
					(end 208.876138 -229.361746)
				)
				(arc
					(start 207.476598 -229.361746)
					(mid 207.440677 -229.376625)
					(end 207.425798 -229.412546)
				)
			)
		)
	)
	(zone
		(layers "In1.Cu" "In2.Cu")
		(hatch none 0.5)
		(connect_pads
			(clearance 0)
		)
		(min_thickness 0.25)
		(keepout
			(tracks not_allowed)
			(vias allowed)
			(pads allowed)
			(copperpour not_allowed)
			(footprints allowed)
		)
		(placement
			(enabled no)
			(sheetname "")
		)
		(fill yes
			(thermal_gap 0.5)
			(thermal_bridge_width 0.5)
			(island_removal_mode 0)
		)
		(polygon
			(pts
				(arc
					(start 282.061666 -220.471492)
					(mid 282.076545 -220.507413)
					(end 282.112466 -220.522292)
				)
				(arc
					(start 283.512006 -220.522292)
					(mid 283.547927 -220.507413)
					(end 283.562806 -220.471492)
				)
				(arc
					(start 283.562806 -220.062552)
					(mid 283.547927 -220.026631)
					(end 283.512006 -220.011752)
				)
				(arc
					(start 282.112466 -220.011752)
					(mid 282.076545 -220.026631)
					(end 282.061666 -220.062552)
				)
			)
		)
	)
	(zone
		(layers "In1.Cu" "In2.Cu")
		(hatch none 0.5)
		(connect_pads
			(clearance 0)
		)
		(min_thickness 0.25)
		(keepout
			(tracks not_allowed)
			(vias allowed)
			(pads allowed)
			(copperpour not_allowed)
			(footprints allowed)
		)
		(placement
			(enabled no)
			(sheetname "")
		)
		(fill yes
			(thermal_gap 0.5)
			(thermal_bridge_width 0.5)
			(island_removal_mode 0)
		)
		(polygon
			(pts
				(arc
					(start 184.794398 -251.921518)
					(mid 184.809277 -251.957439)
					(end 184.845198 -251.972318)
				)
				(arc
					(start 186.244738 -251.972318)
					(mid 186.280659 -251.957439)
					(end 186.295538 -251.921518)
				)
				(arc
					(start 186.295538 -251.512578)
					(mid 186.280659 -251.476657)
					(end 186.244738 -251.461778)
				)
				(arc
					(start 184.845198 -251.461778)
					(mid 184.809277 -251.476657)
					(end 184.794398 -251.512578)
				)
			)
		)
	)
	(zone
		(layers "In1.Cu" "In2.Cu")
		(hatch none 0.5)
		(connect_pads
			(clearance 0)
		)
		(min_thickness 0.25)
		(keepout
			(tracks not_allowed)
			(vias allowed)
			(pads allowed)
			(copperpour not_allowed)
			(footprints allowed)
		)
		(placement
			(enabled no)
			(sheetname "")
		)
		(fill yes
			(thermal_gap 0.5)
			(thermal_bridge_width 0.5)
			(island_removal_mode 0)
		)
		(polygon
			(pts
				(arc
					(start 277.961598 -210.27136)
					(mid 277.976477 -210.307281)
					(end 278.012398 -210.32216)
				)
				(arc
					(start 279.411938 -210.32216)
					(mid 279.447859 -210.307281)
					(end 279.462738 -210.27136)
				)
				(arc
					(start 279.462738 -209.86242)
					(mid 279.447859 -209.826499)
					(end 279.411938 -209.81162)
				)
				(arc
					(start 278.012398 -209.81162)
					(mid 277.976477 -209.826499)
					(end 277.961598 -209.86242)
				)
			)
		)
	)
	(zone
		(layers "In1.Cu" "In2.Cu")
		(hatch none 0.5)
		(connect_pads
			(clearance 0)
		)
		(min_thickness 0.25)
		(keepout
			(tracks not_allowed)
			(vias allowed)
			(pads allowed)
			(copperpour not_allowed)
			(footprints allowed)
		)
		(placement
			(enabled no)
			(sheetname "")
		)
		(fill yes
			(thermal_gap 0.5)
			(thermal_bridge_width 0.5)
			(island_removal_mode 0)
		)
		(polygon
			(pts
				(arc
					(start 37.56533 -271.47139)
					(mid 37.580209 -271.507311)
					(end 37.61613 -271.52219)
				)
				(arc
					(start 39.01567 -271.52219)
					(mid 39.051591 -271.507311)
					(end 39.06647 -271.47139)
				)
				(arc
					(start 39.06647 -271.06245)
					(mid 39.051591 -271.026529)
					(end 39.01567 -271.01165)
				)
				(arc
					(start 37.61613 -271.01165)
					(mid 37.580209 -271.026529)
					(end 37.56533 -271.06245)
				)
			)
		)
	)
	(zone
		(layers "In1.Cu" "In2.Cu")
		(hatch none 0.5)
		(connect_pads
			(clearance 0)
		)
		(min_thickness 0.25)
		(keepout
			(tracks not_allowed)
			(vias allowed)
			(pads allowed)
			(copperpour not_allowed)
			(footprints allowed)
		)
		(placement
			(enabled no)
			(sheetname "")
		)
		(fill yes
			(thermal_gap 0.5)
			(thermal_bridge_width 0.5)
			(island_removal_mode 0)
		)
		(polygon
			(pts
				(arc
					(start 210.86953 -301.221394)
					(mid 210.884409 -301.257315)
					(end 210.92033 -301.272194)
				)
				(arc
					(start 212.31987 -301.272194)
					(mid 212.355791 -301.257315)
					(end 212.37067 -301.221394)
				)
				(arc
					(start 212.37067 -300.812454)
					(mid 212.355791 -300.776533)
					(end 212.31987 -300.761654)
				)
				(arc
					(start 210.92033 -300.761654)
					(mid 210.884409 -300.776533)
					(end 210.86953 -300.812454)
				)
			)
		)
	)
	(zone
		(layers "In1.Cu" "In2.Cu")
		(hatch none 0.5)
		(connect_pads
			(clearance 0)
		)
		(min_thickness 0.25)
		(keepout
			(tracks not_allowed)
			(vias allowed)
			(pads allowed)
			(copperpour not_allowed)
			(footprints allowed)
		)
		(placement
			(enabled no)
			(sheetname "")
		)
		(fill yes
			(thermal_gap 0.5)
			(thermal_bridge_width 0.5)
			(island_removal_mode 0)
		)
		(polygon
			(pts
				(arc
					(start 158.06293 -275.721318)
					(mid 158.077809 -275.757239)
					(end 158.11373 -275.772118)
				)
				(arc
					(start 159.51327 -275.772118)
					(mid 159.549191 -275.757239)
					(end 159.56407 -275.721318)
				)
				(arc
					(start 159.56407 -275.312378)
					(mid 159.549191 -275.276457)
					(end 159.51327 -275.261578)
				)
				(arc
					(start 158.11373 -275.261578)
					(mid 158.077809 -275.276457)
					(end 158.06293 -275.312378)
				)
			)
		)
	)
	(zone
		(layers "In1.Cu" "In2.Cu")
		(hatch none 0.5)
		(connect_pads
			(clearance 0)
		)
		(min_thickness 0.25)
		(keepout
			(tracks not_allowed)
			(vias allowed)
			(pads allowed)
			(copperpour not_allowed)
			(footprints allowed)
		)
		(placement
			(enabled no)
			(sheetname "")
		)
		(fill yes
			(thermal_gap 0.5)
			(thermal_bridge_width 0.5)
			(island_removal_mode 0)
		)
		(polygon
			(pts
				(arc
					(start 417.646866 -201.771504)
					(mid 417.661745 -201.807425)
					(end 417.697666 -201.822304)
				)
				(arc
					(start 419.097206 -201.822304)
					(mid 419.133127 -201.807425)
					(end 419.148006 -201.771504)
				)
				(arc
					(start 419.148006 -201.362564)
					(mid 419.133127 -201.326643)
					(end 419.097206 -201.311764)
				)
				(arc
					(start 417.697666 -201.311764)
					(mid 417.661745 -201.326643)
					(end 417.646866 -201.362564)
				)
			)
		)
	)
	(zone
		(layers "In1.Cu" "In2.Cu")
		(hatch none 0.5)
		(connect_pads
			(clearance 0)
		)
		(min_thickness 0.25)
		(keepout
			(tracks not_allowed)
			(vias allowed)
			(pads allowed)
			(copperpour not_allowed)
			(footprints allowed)
		)
		(placement
			(enabled no)
			(sheetname "")
		)
		(fill yes
			(thermal_gap 0.5)
			(thermal_bridge_width 0.5)
			(island_removal_mode 0)
		)
		(polygon
			(pts
				(arc
					(start 188.23813 -237.471458)
					(mid 188.253009 -237.507379)
					(end 188.28893 -237.522258)
				)
				(arc
					(start 189.68847 -237.522258)
					(mid 189.724391 -237.507379)
					(end 189.73927 -237.471458)
				)
				(arc
					(start 189.73927 -237.062518)
					(mid 189.724391 -237.026597)
					(end 189.68847 -237.011718)
				)
				(arc
					(start 188.28893 -237.011718)
					(mid 188.253009 -237.026597)
					(end 188.23813 -237.062518)
				)
			)
		)
	)
	(zone
		(layers "In1.Cu" "In2.Cu")
		(hatch none 0.5)
		(connect_pads
			(clearance 0)
		)
		(min_thickness 0.25)
		(keepout
			(tracks not_allowed)
			(vias allowed)
			(pads allowed)
			(copperpour not_allowed)
			(footprints allowed)
		)
		(placement
			(enabled no)
			(sheetname "")
		)
		(fill yes
			(thermal_gap 0.5)
			(thermal_bridge_width 0.5)
			(island_removal_mode 0)
		)
		(polygon
			(pts
				(arc
					(start 447.822066 -300.37151)
					(mid 447.836945 -300.407431)
					(end 447.872866 -300.42231)
				)
				(arc
					(start 449.272406 -300.42231)
					(mid 449.308327 -300.407431)
					(end 449.323206 -300.37151)
				)
				(arc
					(start 449.323206 -299.96257)
					(mid 449.308327 -299.926649)
					(end 449.272406 -299.91177)
				)
				(arc
					(start 447.872866 -299.91177)
					(mid 447.836945 -299.926649)
					(end 447.822066 -299.96257)
				)
			)
		)
	)
	(zone
		(layers "In1.Cu" "In2.Cu")
		(hatch none 0.5)
		(connect_pads
			(clearance 0)
		)
		(min_thickness 0.25)
		(keepout
			(tracks not_allowed)
			(vias allowed)
			(pads allowed)
			(copperpour not_allowed)
			(footprints allowed)
		)
		(placement
			(enabled no)
			(sheetname "")
		)
		(fill yes
			(thermal_gap 0.5)
			(thermal_bridge_width 0.5)
			(island_removal_mode 0)
		)
		(polygon
			(pts
				(arc
					(start 64.296798 -220.471492)
					(mid 64.311677 -220.507413)
					(end 64.347598 -220.522292)
				)
				(arc
					(start 65.747138 -220.522292)
					(mid 65.783059 -220.507413)
					(end 65.797938 -220.471492)
				)
				(arc
					(start 65.797938 -220.062552)
					(mid 65.783059 -220.026631)
					(end 65.747138 -220.011752)
				)
				(arc
					(start 64.347598 -220.011752)
					(mid 64.311677 -220.026631)
					(end 64.296798 -220.062552)
				)
			)
		)
	)
	(zone
		(layers "In1.Cu" "In2.Cu")
		(hatch none 0.5)
		(connect_pads
			(clearance 0)
		)
		(min_thickness 0.25)
		(keepout
			(tracks not_allowed)
			(vias allowed)
			(pads allowed)
			(copperpour not_allowed)
			(footprints allowed)
		)
		(placement
			(enabled no)
			(sheetname "")
		)
		(fill yes
			(thermal_gap 0.5)
			(thermal_bridge_width 0.5)
			(island_removal_mode 0)
		)
		(polygon
			(pts
				(arc
					(start 26.577798 -217.921332)
					(mid 26.592677 -217.957253)
					(end 26.628598 -217.972132)
				)
				(arc
					(start 28.028138 -217.972132)
					(mid 28.064059 -217.957253)
					(end 28.078938 -217.921332)
				)
				(arc
					(start 28.078938 -217.512392)
					(mid 28.064059 -217.476471)
					(end 28.028138 -217.461592)
				)
				(arc
					(start 26.628598 -217.461592)
					(mid 26.592677 -217.476471)
					(end 26.577798 -217.512392)
				)
			)
		)
	)
	(zone
		(layers "In1.Cu" "In2.Cu")
		(hatch none 0.5)
		(connect_pads
			(clearance 0)
		)
		(min_thickness 0.25)
		(keepout
			(tracks not_allowed)
			(vias allowed)
			(pads allowed)
			(copperpour not_allowed)
			(footprints allowed)
		)
		(placement
			(enabled no)
			(sheetname "")
		)
		(fill yes
			(thermal_gap 0.5)
			(thermal_bridge_width 0.5)
			(island_removal_mode 0)
		)
		(polygon
			(pts
				(arc
					(start 308.136798 -274.871434)
					(mid 308.151677 -274.907355)
					(end 308.187598 -274.922234)
				)
				(arc
					(start 309.587138 -274.922234)
					(mid 309.623059 -274.907355)
					(end 309.637938 -274.871434)
				)
				(arc
					(start 309.637938 -274.462494)
					(mid 309.623059 -274.426573)
					(end 309.587138 -274.411694)
				)
				(arc
					(start 308.187598 -274.411694)
					(mid 308.151677 -274.426573)
					(end 308.136798 -274.462494)
				)
			)
		)
	)
	(zone
		(layers "In1.Cu" "In2.Cu")
		(hatch none 0.5)
		(connect_pads
			(clearance 0)
		)
		(min_thickness 0.25)
		(keepout
			(tracks not_allowed)
			(vias allowed)
			(pads allowed)
			(copperpour not_allowed)
			(footprints allowed)
		)
		(placement
			(enabled no)
			(sheetname "")
		)
		(fill yes
			(thermal_gap 0.5)
			(thermal_bridge_width 0.5)
			(island_removal_mode 0)
		)
		(polygon
			(pts
				(arc
					(start 410.103066 -260.421374)
					(mid 410.117945 -260.457295)
					(end 410.153866 -260.472174)
				)
				(arc
					(start 411.553406 -260.472174)
					(mid 411.589327 -260.457295)
					(end 411.604206 -260.421374)
				)
				(arc
					(start 411.604206 -260.012434)
					(mid 411.589327 -259.976513)
					(end 411.553406 -259.961634)
				)
				(arc
					(start 410.153866 -259.961634)
					(mid 410.117945 -259.976513)
					(end 410.103066 -260.012434)
				)
			)
		)
	)
	(zone
		(layers "In1.Cu" "In2.Cu")
		(hatch none 0.5)
		(connect_pads
			(clearance 0)
		)
		(min_thickness 0.25)
		(keepout
			(tracks not_allowed)
			(vias allowed)
			(pads allowed)
			(copperpour not_allowed)
			(footprints allowed)
		)
		(placement
			(enabled no)
			(sheetname "")
		)
		(fill yes
			(thermal_gap 0.5)
			(thermal_bridge_width 0.5)
			(island_removal_mode 0)
		)
		(polygon
			(pts
				(arc
					(start 289.605466 -233.22153)
					(mid 289.620345 -233.257451)
					(end 289.656266 -233.27233)
				)
				(arc
					(start 291.055806 -233.27233)
					(mid 291.091727 -233.257451)
					(end 291.106606 -233.22153)
				)
				(arc
					(start 291.106606 -232.81259)
					(mid 291.091727 -232.776669)
					(end 291.055806 -232.76179)
				)
				(arc
					(start 289.656266 -232.76179)
					(mid 289.620345 -232.776669)
					(end 289.605466 -232.81259)
				)
			)
		)
	)
	(zone
		(layers "In1.Cu" "In2.Cu")
		(hatch none 0.5)
		(connect_pads
			(clearance 0)
		)
		(min_thickness 0.25)
		(keepout
			(tracks not_allowed)
			(vias allowed)
			(pads allowed)
			(copperpour not_allowed)
			(footprints allowed)
		)
		(placement
			(enabled no)
			(sheetname "")
		)
		(fill yes
			(thermal_gap 0.5)
			(thermal_bridge_width 0.5)
			(island_removal_mode 0)
		)
		(polygon
			(pts
				(arc
					(start 274.517866 -272.321528)
					(mid 274.532745 -272.357449)
					(end 274.568666 -272.372328)
				)
				(arc
					(start 275.968206 -272.372328)
					(mid 276.004127 -272.357449)
					(end 276.019006 -272.321528)
				)
				(arc
					(start 276.019006 -271.912588)
					(mid 276.004127 -271.876667)
					(end 275.968206 -271.861788)
				)
				(arc
					(start 274.568666 -271.861788)
					(mid 274.532745 -271.876667)
					(end 274.517866 -271.912588)
				)
			)
		)
	)
	(zone
		(layers "In1.Cu" "In2.Cu")
		(hatch none 0.5)
		(connect_pads
			(clearance 0)
		)
		(min_thickness 0.25)
		(keepout
			(tracks not_allowed)
			(vias allowed)
			(pads allowed)
			(copperpour not_allowed)
			(footprints allowed)
		)
		(placement
			(enabled no)
			(sheetname "")
		)
		(fill yes
			(thermal_gap 0.5)
			(thermal_bridge_width 0.5)
			(island_removal_mode 0)
		)
		(polygon
			(pts
				(arc
					(start 282.061666 -311.421526)
					(mid 282.076545 -311.457447)
					(end 282.112466 -311.472326)
				)
				(arc
					(start 283.512006 -311.472326)
					(mid 283.547927 -311.457447)
					(end 283.562806 -311.421526)
				)
				(arc
					(start 283.562806 -311.012586)
					(mid 283.547927 -310.976665)
					(end 283.512006 -310.961786)
				)
				(arc
					(start 282.112466 -310.961786)
					(mid 282.076545 -310.976665)
					(end 282.061666 -311.012586)
				)
			)
		)
	)
	(zone
		(layers "In1.Cu" "In2.Cu")
		(hatch none 0.5)
		(connect_pads
			(clearance 0)
		)
		(min_thickness 0.25)
		(keepout
			(tracks not_allowed)
			(vias allowed)
			(pads allowed)
			(copperpour not_allowed)
			(footprints allowed)
		)
		(placement
			(enabled no)
			(sheetname "")
		)
		(fill yes
			(thermal_gap 0.5)
			(thermal_bridge_width 0.5)
			(island_removal_mode 0)
		)
		(polygon
			(pts
				(arc
					(start 180.69433 -277.42134)
					(mid 180.709209 -277.457261)
					(end 180.74513 -277.47214)
				)
				(arc
					(start 182.14467 -277.47214)
					(mid 182.180591 -277.457261)
					(end 182.19547 -277.42134)
				)
				(arc
					(start 182.19547 -277.0124)
					(mid 182.180591 -276.976479)
					(end 182.14467 -276.9616)
				)
				(arc
					(start 180.74513 -276.9616)
					(mid 180.709209 -276.976479)
					(end 180.69433 -277.0124)
				)
			)
		)
	)
	(zone
		(layers "In1.Cu" "In2.Cu")
		(hatch none 0.5)
		(connect_pads
			(clearance 0)
		)
		(min_thickness 0.25)
		(keepout
			(tracks not_allowed)
			(vias allowed)
			(pads allowed)
			(copperpour not_allowed)
			(footprints allowed)
		)
		(placement
			(enabled no)
			(sheetname "")
		)
		(fill yes
			(thermal_gap 0.5)
			(thermal_bridge_width 0.5)
			(island_removal_mode 0)
		)
		(polygon
			(pts
				(arc
					(start 11.490198 -239.17148)
					(mid 11.505077 -239.207401)
					(end 11.540998 -239.22228)
				)
				(arc
					(start 12.940538 -239.22228)
					(mid 12.976459 -239.207401)
					(end 12.991338 -239.17148)
				)
				(arc
					(start 12.991338 -238.76254)
					(mid 12.976459 -238.726619)
					(end 12.940538 -238.71174)
				)
				(arc
					(start 11.540998 -238.71174)
					(mid 11.505077 -238.726619)
					(end 11.490198 -238.76254)
				)
			)
		)
	)
	(zone
		(layers "In1.Cu" "In2.Cu")
		(hatch none 0.5)
		(connect_pads
			(clearance 0)
		)
		(min_thickness 0.25)
		(keepout
			(tracks not_allowed)
			(vias allowed)
			(pads allowed)
			(copperpour not_allowed)
			(footprints allowed)
		)
		(placement
			(enabled no)
			(sheetname "")
		)
		(fill yes
			(thermal_gap 0.5)
			(thermal_bridge_width 0.5)
			(island_removal_mode 0)
		)
		(polygon
			(pts
				(arc
					(start 45.10913 -279.121362)
					(mid 45.124009 -279.157283)
					(end 45.15993 -279.172162)
				)
				(arc
					(start 46.55947 -279.172162)
					(mid 46.595391 -279.157283)
					(end 46.61027 -279.121362)
				)
				(arc
					(start 46.61027 -278.712422)
					(mid 46.595391 -278.676501)
					(end 46.55947 -278.661622)
				)
				(arc
					(start 45.15993 -278.661622)
					(mid 45.124009 -278.676501)
					(end 45.10913 -278.712422)
				)
			)
		)
	)
	(zone
		(layers "In1.Cu" "In2.Cu")
		(hatch none 0.5)
		(connect_pads
			(clearance 0)
		)
		(min_thickness 0.25)
		(keepout
			(tracks not_allowed)
			(vias allowed)
			(pads allowed)
			(copperpour not_allowed)
			(footprints allowed)
		)
		(placement
			(enabled no)
			(sheetname "")
		)
		(fill yes
			(thermal_gap 0.5)
			(thermal_bridge_width 0.5)
			(island_removal_mode 0)
		)
		(polygon
			(pts
				(arc
					(start 406.002998 -293.571422)
					(mid 406.017877 -293.607343)
					(end 406.053798 -293.622222)
				)
				(arc
					(start 407.453338 -293.622222)
					(mid 407.489259 -293.607343)
					(end 407.504138 -293.571422)
				)
				(arc
					(start 407.504138 -293.162482)
					(mid 407.489259 -293.126561)
					(end 407.453338 -293.111682)
				)
				(arc
					(start 406.053798 -293.111682)
					(mid 406.017877 -293.126561)
					(end 406.002998 -293.162482)
				)
			)
		)
	)
	(zone
		(layers "In1.Cu" "In2.Cu")
		(hatch none 0.5)
		(connect_pads
			(clearance 0)
		)
		(min_thickness 0.25)
		(keepout
			(tracks not_allowed)
			(vias allowed)
			(pads allowed)
			(copperpour not_allowed)
			(footprints allowed)
		)
		(placement
			(enabled no)
			(sheetname "")
		)
		(fill yes
			(thermal_gap 0.5)
			(thermal_bridge_width 0.5)
			(island_removal_mode 0)
		)
		(polygon
			(pts
				(arc
					(start 312.236866 -248.521474)
					(mid 312.251745 -248.557395)
					(end 312.287666 -248.572274)
				)
				(arc
					(start 313.687206 -248.572274)
					(mid 313.723127 -248.557395)
					(end 313.738006 -248.521474)
				)
				(arc
					(start 313.738006 -248.112534)
					(mid 313.723127 -248.076613)
					(end 313.687206 -248.061734)
				)
				(arc
					(start 312.287666 -248.061734)
					(mid 312.251745 -248.076613)
					(end 312.236866 -248.112534)
				)
			)
		)
	)
	(zone
		(layers "In1.Cu" "In2.Cu")
		(hatch none 0.5)
		(connect_pads
			(clearance 0)
		)
		(min_thickness 0.25)
		(keepout
			(tracks not_allowed)
			(vias allowed)
			(pads allowed)
			(copperpour not_allowed)
			(footprints allowed)
		)
		(placement
			(enabled no)
			(sheetname "")
		)
		(fill yes
			(thermal_gap 0.5)
			(thermal_bridge_width 0.5)
			(island_removal_mode 0)
		)
		(polygon
			(pts
				(arc
					(start 413.546798 -279.121362)
					(mid 413.561677 -279.157283)
					(end 413.597598 -279.172162)
				)
				(arc
					(start 414.997138 -279.172162)
					(mid 415.033059 -279.157283)
					(end 415.047938 -279.121362)
				)
				(arc
					(start 415.047938 -278.712422)
					(mid 415.033059 -278.676501)
					(end 414.997138 -278.661622)
				)
				(arc
					(start 413.597598 -278.661622)
					(mid 413.561677 -278.676501)
					(end 413.546798 -278.712422)
				)
			)
		)
	)
	(zone
		(layers "In1.Cu" "In2.Cu")
		(hatch none 0.5)
		(connect_pads
			(clearance 0)
		)
		(min_thickness 0.25)
		(keepout
			(tracks not_allowed)
			(vias allowed)
			(pads allowed)
			(copperpour not_allowed)
			(footprints allowed)
		)
		(placement
			(enabled no)
			(sheetname "")
		)
		(fill yes
			(thermal_gap 0.5)
			(thermal_bridge_width 0.5)
			(island_removal_mode 0)
		)
		(polygon
			(pts
				(arc
					(start 11.490198 -283.371544)
					(mid 11.505077 -283.407465)
					(end 11.540998 -283.422344)
				)
				(arc
					(start 12.940538 -283.422344)
					(mid 12.976459 -283.407465)
					(end 12.991338 -283.371544)
				)
				(arc
					(start 12.991338 -282.962604)
					(mid 12.976459 -282.926683)
					(end 12.940538 -282.911804)
				)
				(arc
					(start 11.540998 -282.911804)
					(mid 11.505077 -282.926683)
					(end 11.490198 -282.962604)
				)
			)
		)
	)
	(zone
		(layers "In1.Cu" "In2.Cu")
		(hatch none 0.5)
		(connect_pads
			(clearance 0)
		)
		(min_thickness 0.25)
		(keepout
			(tracks not_allowed)
			(vias allowed)
			(pads allowed)
			(copperpour not_allowed)
			(footprints allowed)
		)
		(placement
			(enabled no)
			(sheetname "")
		)
		(fill yes
			(thermal_gap 0.5)
			(thermal_bridge_width 0.5)
			(island_removal_mode 0)
		)
		(polygon
			(pts
				(arc
					(start 214.969598 -211.121498)
					(mid 214.984477 -211.157419)
					(end 215.020398 -211.172298)
				)
				(arc
					(start 216.419938 -211.172298)
					(mid 216.455859 -211.157419)
					(end 216.470738 -211.121498)
				)
				(arc
					(start 216.470738 -210.712558)
					(mid 216.455859 -210.676637)
					(end 216.419938 -210.661758)
				)
				(arc
					(start 215.020398 -210.661758)
					(mid 214.984477 -210.676637)
					(end 214.969598 -210.712558)
				)
			)
		)
	)
	(zone
		(layers "In1.Cu" "In2.Cu")
		(hatch none 0.5)
		(connect_pads
			(clearance 0)
		)
		(min_thickness 0.25)
		(keepout
			(tracks not_allowed)
			(vias allowed)
			(pads allowed)
			(copperpour not_allowed)
			(footprints allowed)
		)
		(placement
			(enabled no)
			(sheetname "")
		)
		(fill yes
			(thermal_gap 0.5)
			(thermal_bridge_width 0.5)
			(island_removal_mode 0)
		)
		(polygon
			(pts
				(arc
					(start 308.136798 -202.621388)
					(mid 308.151677 -202.657309)
					(end 308.187598 -202.672188)
				)
				(arc
					(start 309.587138 -202.672188)
					(mid 309.623059 -202.657309)
					(end 309.637938 -202.621388)
				)
				(arc
					(start 309.637938 -202.212448)
					(mid 309.623059 -202.176527)
					(end 309.587138 -202.161648)
				)
				(arc
					(start 308.187598 -202.161648)
					(mid 308.151677 -202.176527)
					(end 308.136798 -202.212448)
				)
			)
		)
	)
	(zone
		(layers "In1.Cu" "In2.Cu")
		(hatch none 0.5)
		(connect_pads
			(clearance 0)
		)
		(min_thickness 0.25)
		(keepout
			(tracks not_allowed)
			(vias allowed)
			(pads allowed)
			(copperpour not_allowed)
			(footprints allowed)
		)
		(placement
			(enabled no)
			(sheetname "")
		)
		(fill yes
			(thermal_gap 0.5)
			(thermal_bridge_width 0.5)
			(island_removal_mode 0)
		)
		(polygon
			(pts
				(arc
					(start 52.65293 -277.42134)
					(mid 52.667809 -277.457261)
					(end 52.70373 -277.47214)
				)
				(arc
					(start 54.10327 -277.47214)
					(mid 54.139191 -277.457261)
					(end 54.15407 -277.42134)
				)
				(arc
					(start 54.15407 -277.0124)
					(mid 54.139191 -276.976479)
					(end 54.10327 -276.9616)
				)
				(arc
					(start 52.70373 -276.9616)
					(mid 52.667809 -276.976479)
					(end 52.65293 -277.0124)
				)
			)
		)
	)
	(zone
		(layers "In1.Cu" "In2.Cu")
		(hatch none 0.5)
		(connect_pads
			(clearance 0)
		)
		(min_thickness 0.25)
		(keepout
			(tracks not_allowed)
			(vias allowed)
			(pads allowed)
			(copperpour not_allowed)
			(footprints allowed)
		)
		(placement
			(enabled no)
			(sheetname "")
		)
		(fill yes
			(thermal_gap 0.5)
			(thermal_bridge_width 0.5)
			(island_removal_mode 0)
		)
		(polygon
			(pts
				(arc
					(start 406.002998 -275.721318)
					(mid 406.017877 -275.757239)
					(end 406.053798 -275.772118)
				)
				(arc
					(start 407.453338 -275.772118)
					(mid 407.489259 -275.757239)
					(end 407.504138 -275.721318)
				)
				(arc
					(start 407.504138 -275.312378)
					(mid 407.489259 -275.276457)
					(end 407.453338 -275.261578)
				)
				(arc
					(start 406.053798 -275.261578)
					(mid 406.017877 -275.276457)
					(end 406.002998 -275.312378)
				)
			)
		)
	)
	(zone
		(layers "In1.Cu" "In2.Cu")
		(hatch none 0.5)
		(connect_pads
			(clearance 0)
		)
		(min_thickness 0.25)
		(keepout
			(tracks not_allowed)
			(vias allowed)
			(pads allowed)
			(copperpour not_allowed)
			(footprints allowed)
		)
		(placement
			(enabled no)
			(sheetname "")
		)
		(fill yes
			(thermal_gap 0.5)
			(thermal_bridge_width 0.5)
			(island_removal_mode 0)
		)
		(polygon
			(pts
				(arc
					(start 173.15053 -228.971348)
					(mid 173.165409 -229.007269)
					(end 173.20133 -229.022148)
				)
				(arc
					(start 174.60087 -229.022148)
					(mid 174.636791 -229.007269)
					(end 174.65167 -228.971348)
				)
				(arc
					(start 174.65167 -228.562408)
					(mid 174.636791 -228.526487)
					(end 174.60087 -228.511608)
				)
				(arc
					(start 173.20133 -228.511608)
					(mid 173.165409 -228.526487)
					(end 173.15053 -228.562408)
				)
			)
		)
	)
	(zone
		(layers "In1.Cu" "In2.Cu")
		(hatch none 0.5)
		(connect_pads
			(clearance 0)
		)
		(min_thickness 0.25)
		(keepout
			(tracks not_allowed)
			(vias allowed)
			(pads allowed)
			(copperpour not_allowed)
			(footprints allowed)
		)
		(placement
			(enabled no)
			(sheetname "")
		)
		(fill yes
			(thermal_gap 0.5)
			(thermal_bridge_width 0.5)
			(island_removal_mode 0)
		)
		(polygon
			(pts
				(arc
					(start 203.32573 -196.671438)
					(mid 203.340609 -196.707359)
					(end 203.37653 -196.722238)
				)
				(arc
					(start 204.77607 -196.722238)
					(mid 204.811991 -196.707359)
					(end 204.82687 -196.671438)
				)
				(arc
					(start 204.82687 -196.262498)
					(mid 204.811991 -196.226577)
					(end 204.77607 -196.211698)
				)
				(arc
					(start 203.37653 -196.211698)
					(mid 203.340609 -196.226577)
					(end 203.32573 -196.262498)
				)
			)
		)
	)
	(zone
		(layers "In1.Cu" "In2.Cu")
		(hatch none 0.5)
		(connect_pads
			(clearance 0)
		)
		(min_thickness 0.25)
		(keepout
			(tracks not_allowed)
			(vias allowed)
			(pads allowed)
			(copperpour not_allowed)
			(footprints allowed)
		)
		(placement
			(enabled no)
			(sheetname "")
		)
		(fill yes
			(thermal_gap 0.5)
			(thermal_bridge_width 0.5)
			(island_removal_mode 0)
		)
		(polygon
			(pts
				(arc
					(start 410.103066 -216.22131)
					(mid 410.117945 -216.257231)
					(end 410.153866 -216.27211)
				)
				(arc
					(start 411.553406 -216.27211)
					(mid 411.589327 -216.257231)
					(end 411.604206 -216.22131)
				)
				(arc
					(start 411.604206 -215.81237)
					(mid 411.589327 -215.776449)
					(end 411.553406 -215.76157)
				)
				(arc
					(start 410.153866 -215.76157)
					(mid 410.117945 -215.776449)
					(end 410.103066 -215.81237)
				)
			)
		)
	)
	(zone
		(layers "In1.Cu" "In2.Cu")
		(hatch none 0.5)
		(connect_pads
			(clearance 0)
		)
		(min_thickness 0.25)
		(keepout
			(tracks not_allowed)
			(vias allowed)
			(pads allowed)
			(copperpour not_allowed)
			(footprints allowed)
		)
		(placement
			(enabled no)
			(sheetname "")
		)
		(fill yes
			(thermal_gap 0.5)
			(thermal_bridge_width 0.5)
			(island_removal_mode 0)
		)
		(polygon
			(pts
				(arc
					(start 49.209198 -285.92145)
					(mid 49.224077 -285.957371)
					(end 49.259998 -285.97225)
				)
				(arc
					(start 50.659538 -285.97225)
					(mid 50.695459 -285.957371)
					(end 50.710338 -285.92145)
				)
				(arc
					(start 50.710338 -285.51251)
					(mid 50.695459 -285.476589)
					(end 50.659538 -285.46171)
				)
				(arc
					(start 49.259998 -285.46171)
					(mid 49.224077 -285.476589)
					(end 49.209198 -285.51251)
				)
			)
		)
	)
	(zone
		(layers "In1.Cu" "In2.Cu")
		(hatch none 0.5)
		(connect_pads
			(clearance 0)
		)
		(min_thickness 0.25)
		(keepout
			(tracks not_allowed)
			(vias allowed)
			(pads allowed)
			(copperpour not_allowed)
			(footprints allowed)
		)
		(placement
			(enabled no)
			(sheetname "")
		)
		(fill yes
			(thermal_gap 0.5)
			(thermal_bridge_width 0.5)
			(island_removal_mode 0)
		)
		(polygon
			(pts
				(arc
					(start 428.634398 -294.421306)
					(mid 428.649277 -294.457227)
					(end 428.685198 -294.472106)
				)
				(arc
					(start 430.084738 -294.472106)
					(mid 430.120659 -294.457227)
					(end 430.135538 -294.421306)
				)
				(arc
					(start 430.135538 -294.012366)
					(mid 430.120659 -293.976445)
					(end 430.084738 -293.961566)
				)
				(arc
					(start 428.685198 -293.961566)
					(mid 428.649277 -293.976445)
					(end 428.634398 -294.012366)
				)
			)
		)
	)
	(zone
		(layers "In1.Cu" "In2.Cu")
		(hatch none 0.5)
		(connect_pads
			(clearance 0)
		)
		(min_thickness 0.25)
		(keepout
			(tracks not_allowed)
			(vias allowed)
			(pads allowed)
			(copperpour not_allowed)
			(footprints allowed)
		)
		(placement
			(enabled no)
			(sheetname "")
		)
		(fill yes
			(thermal_gap 0.5)
			(thermal_bridge_width 0.5)
			(island_removal_mode 0)
		)
		(polygon
			(pts
				(arc
					(start 425.190666 -217.921332)
					(mid 425.205545 -217.957253)
					(end 425.241466 -217.972132)
				)
				(arc
					(start 426.641006 -217.972132)
					(mid 426.676927 -217.957253)
					(end 426.691806 -217.921332)
				)
				(arc
					(start 426.691806 -217.512392)
					(mid 426.676927 -217.476471)
					(end 426.641006 -217.461592)
				)
				(arc
					(start 425.241466 -217.461592)
					(mid 425.205545 -217.476471)
					(end 425.190666 -217.512392)
				)
			)
		)
	)
	(zone
		(layers "In1.Cu" "In2.Cu")
		(hatch none 0.5)
		(connect_pads
			(clearance 0)
		)
		(min_thickness 0.25)
		(keepout
			(tracks not_allowed)
			(vias allowed)
			(pads allowed)
			(copperpour not_allowed)
			(footprints allowed)
		)
		(placement
			(enabled no)
			(sheetname "")
		)
		(fill yes
			(thermal_gap 0.5)
			(thermal_bridge_width 0.5)
			(island_removal_mode 0)
		)
		(polygon
			(pts
				(arc
					(start 56.752998 -281.671522)
					(mid 56.767877 -281.707443)
					(end 56.803798 -281.722322)
				)
				(arc
					(start 58.203338 -281.722322)
					(mid 58.239259 -281.707443)
					(end 58.254138 -281.671522)
				)
				(arc
					(start 58.254138 -281.262582)
					(mid 58.239259 -281.226661)
					(end 58.203338 -281.211782)
				)
				(arc
					(start 56.803798 -281.211782)
					(mid 56.767877 -281.226661)
					(end 56.752998 -281.262582)
				)
			)
		)
	)
	(zone
		(layers "In1.Cu" "In2.Cu")
		(hatch none 0.5)
		(connect_pads
			(clearance 0)
		)
		(min_thickness 0.25)
		(keepout
			(tracks not_allowed)
			(vias allowed)
			(pads allowed)
			(copperpour not_allowed)
			(footprints allowed)
		)
		(placement
			(enabled no)
			(sheetname "")
		)
		(fill yes
			(thermal_gap 0.5)
			(thermal_bridge_width 0.5)
			(island_removal_mode 0)
		)
		(polygon
			(pts
				(arc
					(start 274.517866 -289.321494)
					(mid 274.532745 -289.357415)
					(end 274.568666 -289.372294)
				)
				(arc
					(start 275.968206 -289.372294)
					(mid 276.004127 -289.357415)
					(end 276.019006 -289.321494)
				)
				(arc
					(start 276.019006 -288.912554)
					(mid 276.004127 -288.876633)
					(end 275.968206 -288.861754)
				)
				(arc
					(start 274.568666 -288.861754)
					(mid 274.532745 -288.876633)
					(end 274.517866 -288.912554)
				)
			)
		)
	)
	(zone
		(layers "In1.Cu" "In2.Cu")
		(hatch none 0.5)
		(connect_pads
			(clearance 0)
		)
		(min_thickness 0.25)
		(keepout
			(tracks not_allowed)
			(vias allowed)
			(pads allowed)
			(copperpour not_allowed)
			(footprints allowed)
		)
		(placement
			(enabled no)
			(sheetname "")
		)
		(fill yes
			(thermal_gap 0.5)
			(thermal_bridge_width 0.5)
			(island_removal_mode 0)
		)
		(polygon
			(pts
				(arc
					(start 177.250598 -251.921518)
					(mid 177.265477 -251.957439)
					(end 177.301398 -251.972318)
				)
				(arc
					(start 178.700938 -251.972318)
					(mid 178.736859 -251.957439)
					(end 178.751738 -251.921518)
				)
				(arc
					(start 178.751738 -251.512578)
					(mid 178.736859 -251.476657)
					(end 178.700938 -251.461778)
				)
				(arc
					(start 177.301398 -251.461778)
					(mid 177.265477 -251.476657)
					(end 177.250598 -251.512578)
				)
			)
		)
	)
	(zone
		(layers "In1.Cu" "In2.Cu")
		(hatch none 0.5)
		(connect_pads
			(clearance 0)
		)
		(min_thickness 0.25)
		(keepout
			(tracks not_allowed)
			(vias allowed)
			(pads allowed)
			(copperpour not_allowed)
			(footprints allowed)
		)
		(placement
			(enabled no)
			(sheetname "")
		)
		(fill yes
			(thermal_gap 0.5)
			(thermal_bridge_width 0.5)
			(island_removal_mode 0)
		)
		(polygon
			(pts
				(arc
					(start 19.033998 -300.37151)
					(mid 19.048877 -300.407431)
					(end 19.084798 -300.42231)
				)
				(arc
					(start 20.484338 -300.42231)
					(mid 20.520259 -300.407431)
					(end 20.535138 -300.37151)
				)
				(arc
					(start 20.535138 -299.96257)
					(mid 20.520259 -299.926649)
					(end 20.484338 -299.91177)
				)
				(arc
					(start 19.084798 -299.91177)
					(mid 19.048877 -299.926649)
					(end 19.033998 -299.96257)
				)
			)
		)
	)
	(zone
		(layers "In1.Cu" "In2.Cu")
		(hatch none 0.5)
		(connect_pads
			(clearance 0)
		)
		(min_thickness 0.25)
		(keepout
			(tracks not_allowed)
			(vias allowed)
			(pads allowed)
			(copperpour not_allowed)
			(footprints allowed)
		)
		(placement
			(enabled no)
			(sheetname "")
		)
		(fill yes
			(thermal_gap 0.5)
			(thermal_bridge_width 0.5)
			(island_removal_mode 0)
		)
		(polygon
			(pts
				(arc
					(start 34.121598 -234.921298)
					(mid 34.136477 -234.957219)
					(end 34.172398 -234.972098)
				)
				(arc
					(start 35.571938 -234.972098)
					(mid 35.607859 -234.957219)
					(end 35.622738 -234.921298)
				)
				(arc
					(start 35.622738 -234.512358)
					(mid 35.607859 -234.476437)
					(end 35.571938 -234.461558)
				)
				(arc
					(start 34.172398 -234.461558)
					(mid 34.136477 -234.476437)
					(end 34.121598 -234.512358)
				)
			)
		)
	)
	(zone
		(layers "In1.Cu" "In2.Cu")
		(hatch none 0.5)
		(connect_pads
			(clearance 0)
		)
		(min_thickness 0.25)
		(keepout
			(tracks not_allowed)
			(vias allowed)
			(pads allowed)
			(copperpour not_allowed)
			(footprints allowed)
		)
		(placement
			(enabled no)
			(sheetname "")
		)
		(fill yes
			(thermal_gap 0.5)
			(thermal_bridge_width 0.5)
			(island_removal_mode 0)
		)
		(polygon
			(pts
				(arc
					(start 274.517866 -309.721504)
					(mid 274.532745 -309.757425)
					(end 274.568666 -309.772304)
				)
				(arc
					(start 275.968206 -309.772304)
					(mid 276.004127 -309.757425)
					(end 276.019006 -309.721504)
				)
				(arc
					(start 276.019006 -309.312564)
					(mid 276.004127 -309.276643)
					(end 275.968206 -309.261764)
				)
				(arc
					(start 274.568666 -309.261764)
					(mid 274.532745 -309.276643)
					(end 274.517866 -309.312564)
				)
			)
		)
	)
	(zone
		(layers "In1.Cu" "In2.Cu")
		(hatch none 0.5)
		(connect_pads
			(clearance 0)
		)
		(min_thickness 0.25)
		(keepout
			(tracks not_allowed)
			(vias allowed)
			(pads allowed)
			(copperpour not_allowed)
			(footprints allowed)
		)
		(placement
			(enabled no)
			(sheetname "")
		)
		(fill yes
			(thermal_gap 0.5)
			(thermal_bridge_width 0.5)
			(island_removal_mode 0)
		)
		(polygon
			(pts
				(arc
					(start 207.425798 -276.571456)
					(mid 207.440677 -276.607377)
					(end 207.476598 -276.622256)
				)
				(arc
					(start 208.876138 -276.622256)
					(mid 208.912059 -276.607377)
					(end 208.926938 -276.571456)
				)
				(arc
					(start 208.926938 -276.162516)
					(mid 208.912059 -276.126595)
					(end 208.876138 -276.111716)
				)
				(arc
					(start 207.476598 -276.111716)
					(mid 207.440677 -276.126595)
					(end 207.425798 -276.162516)
				)
			)
		)
	)
	(zone
		(layers "In1.Cu" "In2.Cu")
		(hatch none 0.5)
		(connect_pads
			(clearance 0)
		)
		(min_thickness 0.25)
		(keepout
			(tracks not_allowed)
			(vias allowed)
			(pads allowed)
			(copperpour not_allowed)
			(footprints allowed)
		)
		(placement
			(enabled no)
			(sheetname "")
		)
		(fill yes
			(thermal_gap 0.5)
			(thermal_bridge_width 0.5)
			(island_removal_mode 0)
		)
		(polygon
			(pts
				(arc
					(start 406.002998 -296.121328)
					(mid 406.017877 -296.157249)
					(end 406.053798 -296.172128)
				)
				(arc
					(start 407.453338 -296.172128)
					(mid 407.489259 -296.157249)
					(end 407.504138 -296.121328)
				)
				(arc
					(start 407.504138 -295.712388)
					(mid 407.489259 -295.676467)
					(end 407.453338 -295.661588)
				)
				(arc
					(start 406.053798 -295.661588)
					(mid 406.017877 -295.676467)
					(end 406.002998 -295.712388)
				)
			)
		)
	)
	(zone
		(layers "In1.Cu" "In2.Cu")
		(hatch none 0.5)
		(connect_pads
			(clearance 0)
		)
		(min_thickness 0.25)
		(keepout
			(tracks not_allowed)
			(vias allowed)
			(pads allowed)
			(copperpour not_allowed)
			(footprints allowed)
		)
		(placement
			(enabled no)
			(sheetname "")
		)
		(fill yes
			(thermal_gap 0.5)
			(thermal_bridge_width 0.5)
			(island_removal_mode 0)
		)
		(polygon
			(pts
				(arc
					(start 277.961598 -308.871366)
					(mid 277.976477 -308.907287)
					(end 278.012398 -308.922166)
				)
				(arc
					(start 279.411938 -308.922166)
					(mid 279.447859 -308.907287)
					(end 279.462738 -308.871366)
				)
				(arc
					(start 279.462738 -308.462426)
					(mid 279.447859 -308.426505)
					(end 279.411938 -308.411626)
				)
				(arc
					(start 278.012398 -308.411626)
					(mid 277.976477 -308.426505)
					(end 277.961598 -308.462426)
				)
			)
		)
	)
	(zone
		(layers "In1.Cu" "In2.Cu")
		(hatch none 0.5)
		(connect_pads
			(clearance 0)
		)
		(min_thickness 0.25)
		(keepout
			(tracks not_allowed)
			(vias allowed)
			(pads allowed)
			(copperpour not_allowed)
			(footprints allowed)
		)
		(placement
			(enabled no)
			(sheetname "")
		)
		(fill yes
			(thermal_gap 0.5)
			(thermal_bridge_width 0.5)
			(island_removal_mode 0)
		)
		(polygon
			(pts
				(arc
					(start 41.665398 -308.021482)
					(mid 41.680277 -308.057403)
					(end 41.716198 -308.072282)
				)
				(arc
					(start 43.115738 -308.072282)
					(mid 43.151659 -308.057403)
					(end 43.166538 -308.021482)
				)
				(arc
					(start 43.166538 -307.612542)
					(mid 43.151659 -307.576621)
					(end 43.115738 -307.561742)
				)
				(arc
					(start 41.716198 -307.561742)
					(mid 41.680277 -307.576621)
					(end 41.665398 -307.612542)
				)
			)
		)
	)
	(zone
		(layers "In1.Cu" "In2.Cu")
		(hatch none 0.5)
		(connect_pads
			(clearance 0)
		)
		(min_thickness 0.25)
		(keepout
			(tracks not_allowed)
			(vias allowed)
			(pads allowed)
			(copperpour not_allowed)
			(footprints allowed)
		)
		(placement
			(enabled no)
			(sheetname "")
		)
		(fill yes
			(thermal_gap 0.5)
			(thermal_bridge_width 0.5)
			(island_removal_mode 0)
		)
		(polygon
			(pts
				(arc
					(start 270.417798 -316.521338)
					(mid 270.432677 -316.557259)
					(end 270.468598 -316.572138)
				)
				(arc
					(start 271.868138 -316.572138)
					(mid 271.904059 -316.557259)
					(end 271.918938 -316.521338)
				)
				(arc
					(start 271.918938 -316.112398)
					(mid 271.904059 -316.076477)
					(end 271.868138 -316.061598)
				)
				(arc
					(start 270.468598 -316.061598)
					(mid 270.432677 -316.076477)
					(end 270.417798 -316.112398)
				)
			)
		)
	)
	(zone
		(layers "In1.Cu" "In2.Cu")
		(hatch none 0.5)
		(connect_pads
			(clearance 0)
		)
		(min_thickness 0.25)
		(keepout
			(tracks not_allowed)
			(vias allowed)
			(pads allowed)
			(copperpour not_allowed)
			(footprints allowed)
		)
		(placement
			(enabled no)
			(sheetname "")
		)
		(fill yes
			(thermal_gap 0.5)
			(thermal_bridge_width 0.5)
			(island_removal_mode 0)
		)
		(polygon
			(pts
				(arc
					(start 447.822066 -195.821554)
					(mid 447.836945 -195.857475)
					(end 447.872866 -195.872354)
				)
				(arc
					(start 449.272406 -195.872354)
					(mid 449.308327 -195.857475)
					(end 449.323206 -195.821554)
				)
				(arc
					(start 449.323206 -195.412614)
					(mid 449.308327 -195.376693)
					(end 449.272406 -195.361814)
				)
				(arc
					(start 447.872866 -195.361814)
					(mid 447.836945 -195.376693)
					(end 447.822066 -195.412614)
				)
			)
		)
	)
	(zone
		(layers "In1.Cu" "In2.Cu")
		(hatch none 0.5)
		(connect_pads
			(clearance 0)
		)
		(min_thickness 0.25)
		(keepout
			(tracks not_allowed)
			(vias allowed)
			(pads allowed)
			(copperpour not_allowed)
			(footprints allowed)
		)
		(placement
			(enabled no)
			(sheetname "")
		)
		(fill yes
			(thermal_gap 0.5)
			(thermal_bridge_width 0.5)
			(island_removal_mode 0)
		)
		(polygon
			(pts
				(arc
					(start 195.78193 -271.47139)
					(mid 195.796809 -271.507311)
					(end 195.83273 -271.52219)
				)
				(arc
					(start 197.23227 -271.52219)
					(mid 197.268191 -271.507311)
					(end 197.28307 -271.47139)
				)
				(arc
					(start 197.28307 -271.06245)
					(mid 197.268191 -271.026529)
					(end 197.23227 -271.01165)
				)
				(arc
					(start 195.83273 -271.01165)
					(mid 195.796809 -271.026529)
					(end 195.78193 -271.06245)
				)
			)
		)
	)
	(zone
		(layers "In1.Cu" "In2.Cu")
		(hatch none 0.5)
		(connect_pads
			(clearance 0)
		)
		(min_thickness 0.25)
		(keepout
			(tracks not_allowed)
			(vias allowed)
			(pads allowed)
			(copperpour not_allowed)
			(footprints allowed)
		)
		(placement
			(enabled no)
			(sheetname "")
		)
		(fill yes
			(thermal_gap 0.5)
			(thermal_bridge_width 0.5)
			(island_removal_mode 0)
		)
		(polygon
			(pts
				(arc
					(start 282.061666 -195.821554)
					(mid 282.076545 -195.857475)
					(end 282.112466 -195.872354)
				)
				(arc
					(start 283.512006 -195.872354)
					(mid 283.547927 -195.857475)
					(end 283.562806 -195.821554)
				)
				(arc
					(start 283.562806 -195.412614)
					(mid 283.547927 -195.376693)
					(end 283.512006 -195.361814)
				)
				(arc
					(start 282.112466 -195.361814)
					(mid 282.076545 -195.376693)
					(end 282.061666 -195.412614)
				)
			)
		)
	)
	(zone
		(layers "In1.Cu" "In2.Cu")
		(hatch none 0.5)
		(connect_pads
			(clearance 0)
		)
		(min_thickness 0.25)
		(keepout
			(tracks not_allowed)
			(vias allowed)
			(pads allowed)
			(copperpour not_allowed)
			(footprints allowed)
		)
		(placement
			(enabled no)
			(sheetname "")
		)
		(fill yes
			(thermal_gap 0.5)
			(thermal_bridge_width 0.5)
			(island_removal_mode 0)
		)
		(polygon
			(pts
				(arc
					(start 30.02153 -271.47139)
					(mid 30.036409 -271.507311)
					(end 30.07233 -271.52219)
				)
				(arc
					(start 31.47187 -271.52219)
					(mid 31.507791 -271.507311)
					(end 31.52267 -271.47139)
				)
				(arc
					(start 31.52267 -271.06245)
					(mid 31.507791 -271.026529)
					(end 31.47187 -271.01165)
				)
				(arc
					(start 30.07233 -271.01165)
					(mid 30.036409 -271.026529)
					(end 30.02153 -271.06245)
				)
			)
		)
	)
	(zone
		(layers "In1.Cu" "In2.Cu")
		(hatch none 0.5)
		(connect_pads
			(clearance 0)
		)
		(min_thickness 0.25)
		(keepout
			(tracks not_allowed)
			(vias allowed)
			(pads allowed)
			(copperpour not_allowed)
			(footprints allowed)
		)
		(placement
			(enabled no)
			(sheetname "")
		)
		(fill yes
			(thermal_gap 0.5)
			(thermal_bridge_width 0.5)
			(island_removal_mode 0)
		)
		(polygon
			(pts
				(arc
					(start 266.974066 -234.921298)
					(mid 266.988945 -234.957219)
					(end 267.024866 -234.972098)
				)
				(arc
					(start 268.424406 -234.972098)
					(mid 268.460327 -234.957219)
					(end 268.475206 -234.921298)
				)
				(arc
					(start 268.475206 -234.512358)
					(mid 268.460327 -234.476437)
					(end 268.424406 -234.461558)
				)
				(arc
					(start 267.024866 -234.461558)
					(mid 266.988945 -234.476437)
					(end 266.974066 -234.512358)
				)
			)
		)
	)
	(zone
		(layers "In1.Cu" "In2.Cu")
		(hatch none 0.5)
		(connect_pads
			(clearance 0)
		)
		(min_thickness 0.25)
		(keepout
			(tracks not_allowed)
			(vias allowed)
			(pads allowed)
			(copperpour not_allowed)
			(footprints allowed)
		)
		(placement
			(enabled no)
			(sheetname "")
		)
		(fill yes
			(thermal_gap 0.5)
			(thermal_bridge_width 0.5)
			(island_removal_mode 0)
		)
		(polygon
			(pts
				(arc
					(start 165.60673 -200.071482)
					(mid 165.621609 -200.107403)
					(end 165.65753 -200.122282)
				)
				(arc
					(start 167.05707 -200.122282)
					(mid 167.092991 -200.107403)
					(end 167.10787 -200.071482)
				)
				(arc
					(start 167.10787 -199.662542)
					(mid 167.092991 -199.626621)
					(end 167.05707 -199.611742)
				)
				(arc
					(start 165.65753 -199.611742)
					(mid 165.621609 -199.626621)
					(end 165.60673 -199.662542)
				)
			)
		)
	)
	(zone
		(layers "In1.Cu" "In2.Cu")
		(hatch none 0.5)
		(connect_pads
			(clearance 0)
		)
		(min_thickness 0.25)
		(keepout
			(tracks not_allowed)
			(vias allowed)
			(pads allowed)
			(copperpour not_allowed)
			(footprints allowed)
		)
		(placement
			(enabled no)
			(sheetname "")
		)
		(fill yes
			(thermal_gap 0.5)
			(thermal_bridge_width 0.5)
			(island_removal_mode 0)
		)
		(polygon
			(pts
				(arc
					(start 436.178198 -285.071312)
					(mid 436.193077 -285.107233)
					(end 436.228998 -285.122112)
				)
				(arc
					(start 437.628538 -285.122112)
					(mid 437.664459 -285.107233)
					(end 437.679338 -285.071312)
				)
				(arc
					(start 437.679338 -284.662372)
					(mid 437.664459 -284.626451)
					(end 437.628538 -284.611572)
				)
				(arc
					(start 436.228998 -284.611572)
					(mid 436.193077 -284.626451)
					(end 436.178198 -284.662372)
				)
			)
		)
	)
	(zone
		(layers "In1.Cu" "In2.Cu")
		(hatch none 0.5)
		(connect_pads
			(clearance 0)
		)
		(min_thickness 0.25)
		(keepout
			(tracks not_allowed)
			(vias allowed)
			(pads allowed)
			(copperpour not_allowed)
			(footprints allowed)
		)
		(placement
			(enabled no)
			(sheetname "")
		)
		(fill yes
			(thermal_gap 0.5)
			(thermal_bridge_width 0.5)
			(island_removal_mode 0)
		)
		(polygon
			(pts
				(arc
					(start 169.706798 -233.22153)
					(mid 169.721677 -233.257451)
					(end 169.757598 -233.27233)
				)
				(arc
					(start 171.157138 -233.27233)
					(mid 171.193059 -233.257451)
					(end 171.207938 -233.22153)
				)
				(arc
					(start 171.207938 -232.81259)
					(mid 171.193059 -232.776669)
					(end 171.157138 -232.76179)
				)
				(arc
					(start 169.757598 -232.76179)
					(mid 169.721677 -232.776669)
					(end 169.706798 -232.81259)
				)
			)
		)
	)
	(zone
		(layers "In1.Cu" "In2.Cu")
		(hatch none 0.5)
		(connect_pads
			(clearance 0)
		)
		(min_thickness 0.25)
		(keepout
			(tracks not_allowed)
			(vias allowed)
			(pads allowed)
			(copperpour not_allowed)
			(footprints allowed)
		)
		(placement
			(enabled no)
			(sheetname "")
		)
		(fill yes
			(thermal_gap 0.5)
			(thermal_bridge_width 0.5)
			(island_removal_mode 0)
		)
		(polygon
			(pts
				(arc
					(start 270.417798 -307.171344)
					(mid 270.432677 -307.207265)
					(end 270.468598 -307.222144)
				)
				(arc
					(start 271.868138 -307.222144)
					(mid 271.904059 -307.207265)
					(end 271.918938 -307.171344)
				)
				(arc
					(start 271.918938 -306.762404)
					(mid 271.904059 -306.726483)
					(end 271.868138 -306.711604)
				)
				(arc
					(start 270.468598 -306.711604)
					(mid 270.432677 -306.726483)
					(end 270.417798 -306.762404)
				)
			)
		)
	)
	(zone
		(layers "In1.Cu" "In2.Cu")
		(hatch none 0.5)
		(connect_pads
			(clearance 0)
		)
		(min_thickness 0.25)
		(keepout
			(tracks not_allowed)
			(vias allowed)
			(pads allowed)
			(copperpour not_allowed)
			(footprints allowed)
		)
		(placement
			(enabled no)
			(sheetname "")
		)
		(fill yes
			(thermal_gap 0.5)
			(thermal_bridge_width 0.5)
			(island_removal_mode 0)
		)
		(polygon
			(pts
				(arc
					(start 259.430266 -220.471492)
					(mid 259.445145 -220.507413)
					(end 259.481066 -220.522292)
				)
				(arc
					(start 260.880606 -220.522292)
					(mid 260.916527 -220.507413)
					(end 260.931406 -220.471492)
				)
				(arc
					(start 260.931406 -220.062552)
					(mid 260.916527 -220.026631)
					(end 260.880606 -220.011752)
				)
				(arc
					(start 259.481066 -220.011752)
					(mid 259.445145 -220.026631)
					(end 259.430266 -220.062552)
				)
			)
		)
	)
	(zone
		(layers "In1.Cu" "In2.Cu")
		(hatch none 0.5)
		(connect_pads
			(clearance 0)
		)
		(min_thickness 0.25)
		(keepout
			(tracks not_allowed)
			(vias allowed)
			(pads allowed)
			(copperpour not_allowed)
			(footprints allowed)
		)
		(placement
			(enabled no)
			(sheetname "")
		)
		(fill yes
			(thermal_gap 0.5)
			(thermal_bridge_width 0.5)
			(island_removal_mode 0)
		)
		(polygon
			(pts
				(arc
					(start 410.103066 -302.921416)
					(mid 410.117945 -302.957337)
					(end 410.153866 -302.972216)
				)
				(arc
					(start 411.553406 -302.972216)
					(mid 411.589327 -302.957337)
					(end 411.604206 -302.921416)
				)
				(arc
					(start 411.604206 -302.512476)
					(mid 411.589327 -302.476555)
					(end 411.553406 -302.461676)
				)
				(arc
					(start 410.153866 -302.461676)
					(mid 410.117945 -302.476555)
					(end 410.103066 -302.512476)
				)
			)
		)
	)
	(zone
		(layers "In1.Cu" "In2.Cu")
		(hatch none 0.5)
		(connect_pads
			(clearance 0)
		)
		(min_thickness 0.25)
		(keepout
			(tracks not_allowed)
			(vias allowed)
			(pads allowed)
			(copperpour not_allowed)
			(footprints allowed)
		)
		(placement
			(enabled no)
			(sheetname "")
		)
		(fill yes
			(thermal_gap 0.5)
			(thermal_bridge_width 0.5)
			(island_removal_mode 0)
		)
		(polygon
			(pts
				(arc
					(start 214.969598 -296.971466)
					(mid 214.984477 -297.007387)
					(end 215.020398 -297.022266)
				)
				(arc
					(start 216.419938 -297.022266)
					(mid 216.455859 -297.007387)
					(end 216.470738 -296.971466)
				)
				(arc
					(start 216.470738 -296.562526)
					(mid 216.455859 -296.526605)
					(end 216.419938 -296.511726)
				)
				(arc
					(start 215.020398 -296.511726)
					(mid 214.984477 -296.526605)
					(end 214.969598 -296.562526)
				)
			)
		)
	)
	(zone
		(layers "In1.Cu" "In2.Cu")
		(hatch none 0.5)
		(connect_pads
			(clearance 0)
		)
		(min_thickness 0.25)
		(keepout
			(tracks not_allowed)
			(vias allowed)
			(pads allowed)
			(copperpour not_allowed)
			(footprints allowed)
		)
		(placement
			(enabled no)
			(sheetname "")
		)
		(fill yes
			(thermal_gap 0.5)
			(thermal_bridge_width 0.5)
			(island_removal_mode 0)
		)
		(polygon
			(pts
				(arc
					(start 289.605466 -234.921298)
					(mid 289.620345 -234.957219)
					(end 289.656266 -234.972098)
				)
				(arc
					(start 291.055806 -234.972098)
					(mid 291.091727 -234.957219)
					(end 291.106606 -234.921298)
				)
				(arc
					(start 291.106606 -234.512358)
					(mid 291.091727 -234.476437)
					(end 291.055806 -234.461558)
				)
				(arc
					(start 289.656266 -234.461558)
					(mid 289.620345 -234.476437)
					(end 289.605466 -234.512358)
				)
			)
		)
	)
	(zone
		(layers "In1.Cu" "In2.Cu")
		(hatch none 0.5)
		(connect_pads
			(clearance 0)
		)
		(min_thickness 0.25)
		(keepout
			(tracks not_allowed)
			(vias allowed)
			(pads allowed)
			(copperpour not_allowed)
			(footprints allowed)
		)
		(placement
			(enabled no)
			(sheetname "")
		)
		(fill yes
			(thermal_gap 0.5)
			(thermal_bridge_width 0.5)
			(island_removal_mode 0)
		)
		(polygon
			(pts
				(arc
					(start 173.15053 -302.921416)
					(mid 173.165409 -302.957337)
					(end 173.20133 -302.972216)
				)
				(arc
					(start 174.60087 -302.972216)
					(mid 174.636791 -302.957337)
					(end 174.65167 -302.921416)
				)
				(arc
					(start 174.65167 -302.512476)
					(mid 174.636791 -302.476555)
					(end 174.60087 -302.461676)
				)
				(arc
					(start 173.20133 -302.461676)
					(mid 173.165409 -302.476555)
					(end 173.15053 -302.512476)
				)
			)
		)
	)
	(zone
		(layers "In1.Cu" "In2.Cu")
		(hatch none 0.5)
		(connect_pads
			(clearance 0)
		)
		(min_thickness 0.25)
		(keepout
			(tracks not_allowed)
			(vias allowed)
			(pads allowed)
			(copperpour not_allowed)
			(footprints allowed)
		)
		(placement
			(enabled no)
			(sheetname "")
		)
		(fill yes
			(thermal_gap 0.5)
			(thermal_bridge_width 0.5)
			(island_removal_mode 0)
		)
		(polygon
			(pts
				(arc
					(start 52.65293 -262.971534)
					(mid 52.667809 -263.007455)
					(end 52.70373 -263.022334)
				)
				(arc
					(start 54.10327 -263.022334)
					(mid 54.139191 -263.007455)
					(end 54.15407 -262.971534)
				)
				(arc
					(start 54.15407 -262.562594)
					(mid 54.139191 -262.526673)
					(end 54.10327 -262.511794)
				)
				(arc
					(start 52.70373 -262.511794)
					(mid 52.667809 -262.526673)
					(end 52.65293 -262.562594)
				)
			)
		)
	)
	(zone
		(layers "In1.Cu" "In2.Cu")
		(hatch none 0.5)
		(connect_pads
			(clearance 0)
		)
		(min_thickness 0.25)
		(keepout
			(tracks not_allowed)
			(vias allowed)
			(pads allowed)
			(copperpour not_allowed)
			(footprints allowed)
		)
		(placement
			(enabled no)
			(sheetname "")
		)
		(fill yes
			(thermal_gap 0.5)
			(thermal_bridge_width 0.5)
			(island_removal_mode 0)
		)
		(polygon
			(pts
				(arc
					(start 266.974066 -285.92145)
					(mid 266.988945 -285.957371)
					(end 267.024866 -285.97225)
				)
				(arc
					(start 268.424406 -285.97225)
					(mid 268.460327 -285.957371)
					(end 268.475206 -285.92145)
				)
				(arc
					(start 268.475206 -285.51251)
					(mid 268.460327 -285.476589)
					(end 268.424406 -285.46171)
				)
				(arc
					(start 267.024866 -285.46171)
					(mid 266.988945 -285.476589)
					(end 266.974066 -285.51251)
				)
			)
		)
	)
	(zone
		(layers "In1.Cu" "In2.Cu")
		(hatch none 0.5)
		(connect_pads
			(clearance 0)
		)
		(min_thickness 0.25)
		(keepout
			(tracks not_allowed)
			(vias allowed)
			(pads allowed)
			(copperpour not_allowed)
			(footprints allowed)
		)
		(placement
			(enabled no)
			(sheetname "")
		)
		(fill yes
			(thermal_gap 0.5)
			(thermal_bridge_width 0.5)
			(island_removal_mode 0)
		)
		(polygon
			(pts
				(arc
					(start 443.721998 -217.071448)
					(mid 443.736877 -217.107369)
					(end 443.772798 -217.122248)
				)
				(arc
					(start 445.172338 -217.122248)
					(mid 445.208259 -217.107369)
					(end 445.223138 -217.071448)
				)
				(arc
					(start 445.223138 -216.662508)
					(mid 445.208259 -216.626587)
					(end 445.172338 -216.611708)
				)
				(arc
					(start 443.772798 -216.611708)
					(mid 443.736877 -216.626587)
					(end 443.721998 -216.662508)
				)
			)
		)
	)
	(zone
		(layers "In1.Cu" "In2.Cu")
		(hatch none 0.5)
		(connect_pads
			(clearance 0)
		)
		(min_thickness 0.25)
		(keepout
			(tracks not_allowed)
			(vias allowed)
			(pads allowed)
			(copperpour not_allowed)
			(footprints allowed)
		)
		(placement
			(enabled no)
			(sheetname "")
		)
		(fill yes
			(thermal_gap 0.5)
			(thermal_bridge_width 0.5)
			(island_removal_mode 0)
		)
		(polygon
			(pts
				(arc
					(start 11.490198 -203.471526)
					(mid 11.505077 -203.507447)
					(end 11.540998 -203.522326)
				)
				(arc
					(start 12.940538 -203.522326)
					(mid 12.976459 -203.507447)
					(end 12.991338 -203.471526)
				)
				(arc
					(start 12.991338 -203.062586)
					(mid 12.976459 -203.026665)
					(end 12.940538 -203.011786)
				)
				(arc
					(start 11.540998 -203.011786)
					(mid 11.505077 -203.026665)
					(end 11.490198 -203.062586)
				)
			)
		)
	)
	(zone
		(layers "In1.Cu" "In2.Cu")
		(hatch none 0.5)
		(connect_pads
			(clearance 0)
		)
		(min_thickness 0.25)
		(keepout
			(tracks not_allowed)
			(vias allowed)
			(pads allowed)
			(copperpour not_allowed)
			(footprints allowed)
		)
		(placement
			(enabled no)
			(sheetname "")
		)
		(fill yes
			(thermal_gap 0.5)
			(thermal_bridge_width 0.5)
			(island_removal_mode 0)
		)
		(polygon
			(pts
				(arc
					(start 60.19673 -277.42134)
					(mid 60.211609 -277.457261)
					(end 60.24753 -277.47214)
				)
				(arc
					(start 61.64707 -277.47214)
					(mid 61.682991 -277.457261)
					(end 61.69787 -277.42134)
				)
				(arc
					(start 61.69787 -277.0124)
					(mid 61.682991 -276.976479)
					(end 61.64707 -276.9616)
				)
				(arc
					(start 60.24753 -276.9616)
					(mid 60.211609 -276.976479)
					(end 60.19673 -277.0124)
				)
			)
		)
	)
	(zone
		(layers "In1.Cu" "In2.Cu")
		(hatch none 0.5)
		(connect_pads
			(clearance 0)
		)
		(min_thickness 0.25)
		(keepout
			(tracks not_allowed)
			(vias allowed)
			(pads allowed)
			(copperpour not_allowed)
			(footprints allowed)
		)
		(placement
			(enabled no)
			(sheetname "")
		)
		(fill yes
			(thermal_gap 0.5)
			(thermal_bridge_width 0.5)
			(island_removal_mode 0)
		)
		(polygon
			(pts
				(arc
					(start 169.706798 -281.671522)
					(mid 169.721677 -281.707443)
					(end 169.757598 -281.722322)
				)
				(arc
					(start 171.157138 -281.722322)
					(mid 171.193059 -281.707443)
					(end 171.207938 -281.671522)
				)
				(arc
					(start 171.207938 -281.262582)
					(mid 171.193059 -281.226661)
					(end 171.157138 -281.211782)
				)
				(arc
					(start 169.757598 -281.211782)
					(mid 169.721677 -281.226661)
					(end 169.706798 -281.262582)
				)
			)
		)
	)
	(zone
		(layers "In1.Cu" "In2.Cu")
		(hatch none 0.5)
		(connect_pads
			(clearance 0)
		)
		(min_thickness 0.25)
		(keepout
			(tracks not_allowed)
			(vias allowed)
			(pads allowed)
			(copperpour not_allowed)
			(footprints allowed)
		)
		(placement
			(enabled no)
			(sheetname "")
		)
		(fill yes
			(thermal_gap 0.5)
			(thermal_bridge_width 0.5)
			(island_removal_mode 0)
		)
		(polygon
			(pts
				(arc
					(start 214.969598 -259.57149)
					(mid 214.984477 -259.607411)
					(end 215.020398 -259.62229)
				)
				(arc
					(start 216.419938 -259.62229)
					(mid 216.455859 -259.607411)
					(end 216.470738 -259.57149)
				)
				(arc
					(start 216.470738 -259.16255)
					(mid 216.455859 -259.126629)
					(end 216.419938 -259.11175)
				)
				(arc
					(start 215.020398 -259.11175)
					(mid 214.984477 -259.126629)
					(end 214.969598 -259.16255)
				)
			)
		)
	)
	(zone
		(layers "In1.Cu" "In2.Cu")
		(hatch none 0.5)
		(connect_pads
			(clearance 0)
		)
		(min_thickness 0.25)
		(keepout
			(tracks not_allowed)
			(vias allowed)
			(pads allowed)
			(copperpour not_allowed)
			(footprints allowed)
		)
		(placement
			(enabled no)
			(sheetname "")
		)
		(fill yes
			(thermal_gap 0.5)
			(thermal_bridge_width 0.5)
			(island_removal_mode 0)
		)
		(polygon
			(pts
				(arc
					(start 417.646866 -197.521322)
					(mid 417.661745 -197.557243)
					(end 417.697666 -197.572122)
				)
				(arc
					(start 419.097206 -197.572122)
					(mid 419.133127 -197.557243)
					(end 419.148006 -197.521322)
				)
				(arc
					(start 419.148006 -197.112382)
					(mid 419.133127 -197.076461)
					(end 419.097206 -197.061582)
				)
				(arc
					(start 417.697666 -197.061582)
					(mid 417.661745 -197.076461)
					(end 417.646866 -197.112382)
				)
			)
		)
	)
	(zone
		(layers "In1.Cu" "In2.Cu")
		(hatch none 0.5)
		(connect_pads
			(clearance 0)
		)
		(min_thickness 0.25)
		(keepout
			(tracks not_allowed)
			(vias allowed)
			(pads allowed)
			(copperpour not_allowed)
			(footprints allowed)
		)
		(placement
			(enabled no)
			(sheetname "")
		)
		(fill yes
			(thermal_gap 0.5)
			(thermal_bridge_width 0.5)
			(island_removal_mode 0)
		)
		(polygon
			(pts
				(arc
					(start 447.822066 -227.271326)
					(mid 447.836945 -227.307247)
					(end 447.872866 -227.322126)
				)
				(arc
					(start 449.272406 -227.322126)
					(mid 449.308327 -227.307247)
					(end 449.323206 -227.271326)
				)
				(arc
					(start 449.323206 -226.862386)
					(mid 449.308327 -226.826465)
					(end 449.272406 -226.811586)
				)
				(arc
					(start 447.872866 -226.811586)
					(mid 447.836945 -226.826465)
					(end 447.822066 -226.862386)
				)
			)
		)
	)
	(zone
		(layers "In1.Cu" "In2.Cu")
		(hatch none 0.5)
		(connect_pads
			(clearance 0)
		)
		(min_thickness 0.25)
		(keepout
			(tracks not_allowed)
			(vias allowed)
			(pads allowed)
			(copperpour not_allowed)
			(footprints allowed)
		)
		(placement
			(enabled no)
			(sheetname "")
		)
		(fill yes
			(thermal_gap 0.5)
			(thermal_bridge_width 0.5)
			(island_removal_mode 0)
		)
		(polygon
			(pts
				(arc
					(start 462.909666 -260.421374)
					(mid 462.924545 -260.457295)
					(end 462.960466 -260.472174)
				)
				(arc
					(start 464.360006 -260.472174)
					(mid 464.395927 -260.457295)
					(end 464.410806 -260.421374)
				)
				(arc
					(start 464.410806 -260.012434)
					(mid 464.395927 -259.976513)
					(end 464.360006 -259.961634)
				)
				(arc
					(start 462.960466 -259.961634)
					(mid 462.924545 -259.976513)
					(end 462.909666 -260.012434)
				)
			)
		)
	)
	(zone
		(layers "In1.Cu" "In2.Cu")
		(hatch none 0.5)
		(connect_pads
			(clearance 0)
		)
		(min_thickness 0.25)
		(keepout
			(tracks not_allowed)
			(vias allowed)
			(pads allowed)
			(copperpour not_allowed)
			(footprints allowed)
		)
		(placement
			(enabled no)
			(sheetname "")
		)
		(fill yes
			(thermal_gap 0.5)
			(thermal_bridge_width 0.5)
			(island_removal_mode 0)
		)
		(polygon
			(pts
				(arc
					(start 34.121598 -246.821452)
					(mid 34.136477 -246.857373)
					(end 34.172398 -246.872252)
				)
				(arc
					(start 35.571938 -246.872252)
					(mid 35.607859 -246.857373)
					(end 35.622738 -246.821452)
				)
				(arc
					(start 35.622738 -246.412512)
					(mid 35.607859 -246.376591)
					(end 35.571938 -246.361712)
				)
				(arc
					(start 34.172398 -246.361712)
					(mid 34.136477 -246.376591)
					(end 34.121598 -246.412512)
				)
			)
		)
	)
	(zone
		(layers "In1.Cu" "In2.Cu")
		(hatch none 0.5)
		(connect_pads
			(clearance 0)
		)
		(min_thickness 0.25)
		(keepout
			(tracks not_allowed)
			(vias allowed)
			(pads allowed)
			(copperpour not_allowed)
			(footprints allowed)
		)
		(placement
			(enabled no)
			(sheetname "")
		)
		(fill yes
			(thermal_gap 0.5)
			(thermal_bridge_width 0.5)
			(island_removal_mode 0)
		)
		(polygon
			(pts
				(arc
					(start 49.209198 -268.921484)
					(mid 49.224077 -268.957405)
					(end 49.259998 -268.972284)
				)
				(arc
					(start 50.659538 -268.972284)
					(mid 50.695459 -268.957405)
					(end 50.710338 -268.921484)
				)
				(arc
					(start 50.710338 -268.512544)
					(mid 50.695459 -268.476623)
					(end 50.659538 -268.461744)
				)
				(arc
					(start 49.259998 -268.461744)
					(mid 49.224077 -268.476623)
					(end 49.209198 -268.512544)
				)
			)
		)
	)
	(zone
		(layers "In1.Cu" "In2.Cu")
		(hatch none 0.5)
		(connect_pads
			(clearance 0)
		)
		(min_thickness 0.25)
		(keepout
			(tracks not_allowed)
			(vias allowed)
			(pads allowed)
			(copperpour not_allowed)
			(footprints allowed)
		)
		(placement
			(enabled no)
			(sheetname "")
		)
		(fill yes
			(thermal_gap 0.5)
			(thermal_bridge_width 0.5)
			(island_removal_mode 0)
		)
		(polygon
			(pts
				(arc
					(start 203.32573 -244.271292)
					(mid 203.340609 -244.307213)
					(end 203.37653 -244.322092)
				)
				(arc
					(start 204.77607 -244.322092)
					(mid 204.811991 -244.307213)
					(end 204.82687 -244.271292)
				)
				(arc
					(start 204.82687 -243.862352)
					(mid 204.811991 -243.826431)
					(end 204.77607 -243.811552)
				)
				(arc
					(start 203.37653 -243.811552)
					(mid 203.340609 -243.826431)
					(end 203.32573 -243.862352)
				)
			)
		)
	)
	(zone
		(layers "In1.Cu" "In2.Cu")
		(hatch none 0.5)
		(connect_pads
			(clearance 0)
		)
		(min_thickness 0.25)
		(keepout
			(tracks not_allowed)
			(vias allowed)
			(pads allowed)
			(copperpour not_allowed)
			(footprints allowed)
		)
		(placement
			(enabled no)
			(sheetname "")
		)
		(fill yes
			(thermal_gap 0.5)
			(thermal_bridge_width 0.5)
			(island_removal_mode 0)
		)
		(polygon
			(pts
				(arc
					(start 64.296798 -306.32146)
					(mid 64.311677 -306.357381)
					(end 64.347598 -306.37226)
				)
				(arc
					(start 65.747138 -306.37226)
					(mid 65.783059 -306.357381)
					(end 65.797938 -306.32146)
				)
				(arc
					(start 65.797938 -305.91252)
					(mid 65.783059 -305.876599)
					(end 65.747138 -305.86172)
				)
				(arc
					(start 64.347598 -305.86172)
					(mid 64.311677 -305.876599)
					(end 64.296798 -305.91252)
				)
			)
		)
	)
	(zone
		(layers "In1.Cu" "In2.Cu")
		(hatch none 0.5)
		(connect_pads
			(clearance 0)
		)
		(min_thickness 0.25)
		(keepout
			(tracks not_allowed)
			(vias allowed)
			(pads allowed)
			(copperpour not_allowed)
			(footprints allowed)
		)
		(placement
			(enabled no)
			(sheetname "")
		)
		(fill yes
			(thermal_gap 0.5)
			(thermal_bridge_width 0.5)
			(island_removal_mode 0)
		)
		(polygon
			(pts
				(arc
					(start 406.002998 -286.771334)
					(mid 406.017877 -286.807255)
					(end 406.053798 -286.822134)
				)
				(arc
					(start 407.453338 -286.822134)
					(mid 407.489259 -286.807255)
					(end 407.504138 -286.771334)
				)
				(arc
					(start 407.504138 -286.362394)
					(mid 407.489259 -286.326473)
					(end 407.453338 -286.311594)
				)
				(arc
					(start 406.053798 -286.311594)
					(mid 406.017877 -286.326473)
					(end 406.002998 -286.362394)
				)
			)
		)
	)
	(zone
		(layers "In1.Cu" "In2.Cu")
		(hatch none 0.5)
		(connect_pads
			(clearance 0)
		)
		(min_thickness 0.25)
		(keepout
			(tracks not_allowed)
			(vias allowed)
			(pads allowed)
			(copperpour not_allowed)
			(footprints allowed)
		)
		(placement
			(enabled no)
			(sheetname "")
		)
		(fill yes
			(thermal_gap 0.5)
			(thermal_bridge_width 0.5)
			(island_removal_mode 0)
		)
		(polygon
			(pts
				(arc
					(start 64.296798 -308.021482)
					(mid 64.311677 -308.057403)
					(end 64.347598 -308.072282)
				)
				(arc
					(start 65.747138 -308.072282)
					(mid 65.783059 -308.057403)
					(end 65.797938 -308.021482)
				)
				(arc
					(start 65.797938 -307.612542)
					(mid 65.783059 -307.576621)
					(end 65.747138 -307.561742)
				)
				(arc
					(start 64.347598 -307.561742)
					(mid 64.311677 -307.576621)
					(end 64.296798 -307.612542)
				)
			)
		)
	)
	(zone
		(layers "In1.Cu" "In2.Cu")
		(hatch none 0.5)
		(connect_pads
			(clearance 0)
		)
		(min_thickness 0.25)
		(keepout
			(tracks not_allowed)
			(vias allowed)
			(pads allowed)
			(copperpour not_allowed)
			(footprints allowed)
		)
		(placement
			(enabled no)
			(sheetname "")
		)
		(fill yes
			(thermal_gap 0.5)
			(thermal_bridge_width 0.5)
			(island_removal_mode 0)
		)
		(polygon
			(pts
				(arc
					(start 312.236866 -302.921416)
					(mid 312.251745 -302.957337)
					(end 312.287666 -302.972216)
				)
				(arc
					(start 313.687206 -302.972216)
					(mid 313.723127 -302.957337)
					(end 313.738006 -302.921416)
				)
				(arc
					(start 313.738006 -302.512476)
					(mid 313.723127 -302.476555)
					(end 313.687206 -302.461676)
				)
				(arc
					(start 312.287666 -302.461676)
					(mid 312.251745 -302.476555)
					(end 312.236866 -302.512476)
				)
			)
		)
	)
	(zone
		(layers "In1.Cu" "In2.Cu")
		(hatch none 0.5)
		(connect_pads
			(clearance 0)
		)
		(min_thickness 0.25)
		(keepout
			(tracks not_allowed)
			(vias allowed)
			(pads allowed)
			(copperpour not_allowed)
			(footprints allowed)
		)
		(placement
			(enabled no)
			(sheetname "")
		)
		(fill yes
			(thermal_gap 0.5)
			(thermal_bridge_width 0.5)
			(island_removal_mode 0)
		)
		(polygon
			(pts
				(arc
					(start 289.605466 -284.221428)
					(mid 289.620345 -284.257349)
					(end 289.656266 -284.272228)
				)
				(arc
					(start 291.055806 -284.272228)
					(mid 291.091727 -284.257349)
					(end 291.106606 -284.221428)
				)
				(arc
					(start 291.106606 -283.812488)
					(mid 291.091727 -283.776567)
					(end 291.055806 -283.761688)
				)
				(arc
					(start 289.656266 -283.761688)
					(mid 289.620345 -283.776567)
					(end 289.605466 -283.812488)
				)
			)
		)
	)
	(zone
		(layers "In1.Cu" "In2.Cu")
		(hatch none 0.5)
		(connect_pads
			(clearance 0)
		)
		(min_thickness 0.25)
		(keepout
			(tracks not_allowed)
			(vias allowed)
			(pads allowed)
			(copperpour not_allowed)
			(footprints allowed)
		)
		(placement
			(enabled no)
			(sheetname "")
		)
		(fill yes
			(thermal_gap 0.5)
			(thermal_bridge_width 0.5)
			(island_removal_mode 0)
		)
		(polygon
			(pts
				(arc
					(start 259.430266 -233.22153)
					(mid 259.445145 -233.257451)
					(end 259.481066 -233.27233)
				)
				(arc
					(start 260.880606 -233.27233)
					(mid 260.916527 -233.257451)
					(end 260.931406 -233.22153)
				)
				(arc
					(start 260.931406 -232.81259)
					(mid 260.916527 -232.776669)
					(end 260.880606 -232.76179)
				)
				(arc
					(start 259.481066 -232.76179)
					(mid 259.445145 -232.776669)
					(end 259.430266 -232.81259)
				)
			)
		)
	)
	(zone
		(layers "In1.Cu" "In2.Cu")
		(hatch none 0.5)
		(connect_pads
			(clearance 0)
		)
		(min_thickness 0.25)
		(keepout
			(tracks not_allowed)
			(vias allowed)
			(pads allowed)
			(copperpour not_allowed)
			(footprints allowed)
		)
		(placement
			(enabled no)
			(sheetname "")
		)
		(fill yes
			(thermal_gap 0.5)
			(thermal_bridge_width 0.5)
			(island_removal_mode 0)
		)
		(polygon
			(pts
				(arc
					(start 289.605466 -237.471458)
					(mid 289.620345 -237.507379)
					(end 289.656266 -237.522258)
				)
				(arc
					(start 291.055806 -237.522258)
					(mid 291.091727 -237.507379)
					(end 291.106606 -237.471458)
				)
				(arc
					(start 291.106606 -237.062518)
					(mid 291.091727 -237.026597)
					(end 291.055806 -237.011718)
				)
				(arc
					(start 289.656266 -237.011718)
					(mid 289.620345 -237.026597)
					(end 289.605466 -237.062518)
				)
			)
		)
	)
	(zone
		(layers "In1.Cu" "In2.Cu")
		(hatch none 0.5)
		(connect_pads
			(clearance 0)
		)
		(min_thickness 0.25)
		(keepout
			(tracks not_allowed)
			(vias allowed)
			(pads allowed)
			(copperpour not_allowed)
			(footprints allowed)
		)
		(placement
			(enabled no)
			(sheetname "")
		)
		(fill yes
			(thermal_gap 0.5)
			(thermal_bridge_width 0.5)
			(island_removal_mode 0)
		)
		(polygon
			(pts
				(arc
					(start 169.706798 -206.871316)
					(mid 169.721677 -206.907237)
					(end 169.757598 -206.922116)
				)
				(arc
					(start 171.157138 -206.922116)
					(mid 171.193059 -206.907237)
					(end 171.207938 -206.871316)
				)
				(arc
					(start 171.207938 -206.462376)
					(mid 171.193059 -206.426455)
					(end 171.157138 -206.411576)
				)
				(arc
					(start 169.757598 -206.411576)
					(mid 169.721677 -206.426455)
					(end 169.706798 -206.462376)
				)
			)
		)
	)
	(zone
		(layers "In1.Cu" "In2.Cu")
		(hatch none 0.5)
		(connect_pads
			(clearance 0)
		)
		(min_thickness 0.25)
		(keepout
			(tracks not_allowed)
			(vias allowed)
			(pads allowed)
			(copperpour not_allowed)
			(footprints allowed)
		)
		(placement
			(enabled no)
			(sheetname "")
		)
		(fill yes
			(thermal_gap 0.5)
			(thermal_bridge_width 0.5)
			(island_removal_mode 0)
		)
		(polygon
			(pts
				(arc
					(start 289.605466 -250.221496)
					(mid 289.620345 -250.257417)
					(end 289.656266 -250.272296)
				)
				(arc
					(start 291.055806 -250.272296)
					(mid 291.091727 -250.257417)
					(end 291.106606 -250.221496)
				)
				(arc
					(start 291.106606 -249.812556)
					(mid 291.091727 -249.776635)
					(end 291.055806 -249.761756)
				)
				(arc
					(start 289.656266 -249.761756)
					(mid 289.620345 -249.776635)
					(end 289.605466 -249.812556)
				)
			)
		)
	)
	(zone
		(layers "In1.Cu" "In2.Cu")
		(hatch none 0.5)
		(connect_pads
			(clearance 0)
		)
		(min_thickness 0.25)
		(keepout
			(tracks not_allowed)
			(vias allowed)
			(pads allowed)
			(copperpour not_allowed)
			(footprints allowed)
		)
		(placement
			(enabled no)
			(sheetname "")
		)
		(fill yes
			(thermal_gap 0.5)
			(thermal_bridge_width 0.5)
			(island_removal_mode 0)
		)
		(polygon
			(pts
				(arc
					(start 37.56533 -224.72142)
					(mid 37.580209 -224.757341)
					(end 37.61613 -224.77222)
				)
				(arc
					(start 39.01567 -224.77222)
					(mid 39.051591 -224.757341)
					(end 39.06647 -224.72142)
				)
				(arc
					(start 39.06647 -224.31248)
					(mid 39.051591 -224.276559)
					(end 39.01567 -224.26168)
				)
				(arc
					(start 37.61613 -224.26168)
					(mid 37.580209 -224.276559)
					(end 37.56533 -224.31248)
				)
			)
		)
	)
	(zone
		(layers "In1.Cu" "In2.Cu")
		(hatch none 0.5)
		(connect_pads
			(clearance 0)
		)
		(min_thickness 0.25)
		(keepout
			(tracks not_allowed)
			(vias allowed)
			(pads allowed)
			(copperpour not_allowed)
			(footprints allowed)
		)
		(placement
			(enabled no)
			(sheetname "")
		)
		(fill yes
			(thermal_gap 0.5)
			(thermal_bridge_width 0.5)
			(island_removal_mode 0)
		)
		(polygon
			(pts
				(arc
					(start 64.296798 -285.92145)
					(mid 64.311677 -285.957371)
					(end 64.347598 -285.97225)
				)
				(arc
					(start 65.747138 -285.97225)
					(mid 65.783059 -285.957371)
					(end 65.797938 -285.92145)
				)
				(arc
					(start 65.797938 -285.51251)
					(mid 65.783059 -285.476589)
					(end 65.747138 -285.46171)
				)
				(arc
					(start 64.347598 -285.46171)
					(mid 64.311677 -285.476589)
					(end 64.296798 -285.51251)
				)
			)
		)
	)
	(zone
		(layers "In1.Cu" "In2.Cu")
		(hatch none 0.5)
		(connect_pads
			(clearance 0)
		)
		(min_thickness 0.25)
		(keepout
			(tracks not_allowed)
			(vias allowed)
			(pads allowed)
			(copperpour not_allowed)
			(footprints allowed)
		)
		(placement
			(enabled no)
			(sheetname "")
		)
		(fill yes
			(thermal_gap 0.5)
			(thermal_bridge_width 0.5)
			(island_removal_mode 0)
		)
		(polygon
			(pts
				(arc
					(start 192.338198 -296.971466)
					(mid 192.353077 -297.007387)
					(end 192.388998 -297.022266)
				)
				(arc
					(start 193.788538 -297.022266)
					(mid 193.824459 -297.007387)
					(end 193.839338 -296.971466)
				)
				(arc
					(start 193.839338 -296.562526)
					(mid 193.824459 -296.526605)
					(end 193.788538 -296.511726)
				)
				(arc
					(start 192.388998 -296.511726)
					(mid 192.353077 -296.526605)
					(end 192.338198 -296.562526)
				)
			)
		)
	)
	(zone
		(layers "In1.Cu" "In2.Cu")
		(hatch none 0.5)
		(connect_pads
			(clearance 0)
		)
		(min_thickness 0.25)
		(keepout
			(tracks not_allowed)
			(vias allowed)
			(pads allowed)
			(copperpour not_allowed)
			(footprints allowed)
		)
		(placement
			(enabled no)
			(sheetname "")
		)
		(fill yes
			(thermal_gap 0.5)
			(thermal_bridge_width 0.5)
			(island_removal_mode 0)
		)
		(polygon
			(pts
				(arc
					(start 289.605466 -311.421526)
					(mid 289.620345 -311.457447)
					(end 289.656266 -311.472326)
				)
				(arc
					(start 291.055806 -311.472326)
					(mid 291.091727 -311.457447)
					(end 291.106606 -311.421526)
				)
				(arc
					(start 291.106606 -311.012586)
					(mid 291.091727 -310.976665)
					(end 291.055806 -310.961786)
				)
				(arc
					(start 289.656266 -310.961786)
					(mid 289.620345 -310.976665)
					(end 289.605466 -311.012586)
				)
			)
		)
	)
	(zone
		(layers "In1.Cu" "In2.Cu")
		(hatch none 0.5)
		(connect_pads
			(clearance 0)
		)
		(min_thickness 0.25)
		(keepout
			(tracks not_allowed)
			(vias allowed)
			(pads allowed)
			(copperpour not_allowed)
			(footprints allowed)
		)
		(placement
			(enabled no)
			(sheetname "")
		)
		(fill yes
			(thermal_gap 0.5)
			(thermal_bridge_width 0.5)
			(island_removal_mode 0)
		)
		(polygon
			(pts
				(arc
					(start 195.78193 -310.571388)
					(mid 195.796809 -310.607309)
					(end 195.83273 -310.622188)
				)
				(arc
					(start 197.23227 -310.622188)
					(mid 197.268191 -310.607309)
					(end 197.28307 -310.571388)
				)
				(arc
					(start 197.28307 -310.162448)
					(mid 197.268191 -310.126527)
					(end 197.23227 -310.111648)
				)
				(arc
					(start 195.83273 -310.111648)
					(mid 195.796809 -310.126527)
					(end 195.78193 -310.162448)
				)
			)
		)
	)
	(zone
		(layers "In1.Cu" "In2.Cu")
		(hatch none 0.5)
		(connect_pads
			(clearance 0)
		)
		(min_thickness 0.25)
		(keepout
			(tracks not_allowed)
			(vias allowed)
			(pads allowed)
			(copperpour not_allowed)
			(footprints allowed)
		)
		(placement
			(enabled no)
			(sheetname "")
		)
		(fill yes
			(thermal_gap 0.5)
			(thermal_bridge_width 0.5)
			(island_removal_mode 0)
		)
		(polygon
			(pts
				(arc
					(start 19.033998 -262.121396)
					(mid 19.048877 -262.157317)
					(end 19.084798 -262.172196)
				)
				(arc
					(start 20.484338 -262.172196)
					(mid 20.520259 -262.157317)
					(end 20.535138 -262.121396)
				)
				(arc
					(start 20.535138 -261.712456)
					(mid 20.520259 -261.676535)
					(end 20.484338 -261.661656)
				)
				(arc
					(start 19.084798 -261.661656)
					(mid 19.048877 -261.676535)
					(end 19.033998 -261.712456)
				)
			)
		)
	)
	(zone
		(layers "In1.Cu" "In2.Cu")
		(hatch none 0.5)
		(connect_pads
			(clearance 0)
		)
		(min_thickness 0.25)
		(keepout
			(tracks not_allowed)
			(vias allowed)
			(pads allowed)
			(copperpour not_allowed)
			(footprints allowed)
		)
		(placement
			(enabled no)
			(sheetname "")
		)
		(fill yes
			(thermal_gap 0.5)
			(thermal_bridge_width 0.5)
			(island_removal_mode 0)
		)
		(polygon
			(pts
				(arc
					(start 37.56533 -196.671438)
					(mid 37.580209 -196.707359)
					(end 37.61613 -196.722238)
				)
				(arc
					(start 39.01567 -196.722238)
					(mid 39.051591 -196.707359)
					(end 39.06647 -196.671438)
				)
				(arc
					(start 39.06647 -196.262498)
					(mid 39.051591 -196.226577)
					(end 39.01567 -196.211698)
				)
				(arc
					(start 37.61613 -196.211698)
					(mid 37.580209 -196.226577)
					(end 37.56533 -196.262498)
				)
			)
		)
	)
	(zone
		(layers "In1.Cu" "In2.Cu")
		(hatch none 0.5)
		(connect_pads
			(clearance 0)
		)
		(min_thickness 0.25)
		(keepout
			(tracks not_allowed)
			(vias allowed)
			(pads allowed)
			(copperpour not_allowed)
			(footprints allowed)
		)
		(placement
			(enabled no)
			(sheetname "")
		)
		(fill yes
			(thermal_gap 0.5)
			(thermal_bridge_width 0.5)
			(island_removal_mode 0)
		)
		(polygon
			(pts
				(arc
					(start 300.592998 -204.32141)
					(mid 300.607877 -204.357331)
					(end 300.643798 -204.37221)
				)
				(arc
					(start 302.043338 -204.37221)
					(mid 302.079259 -204.357331)
					(end 302.094138 -204.32141)
				)
				(arc
					(start 302.094138 -203.91247)
					(mid 302.079259 -203.876549)
					(end 302.043338 -203.86167)
				)
				(arc
					(start 300.643798 -203.86167)
					(mid 300.607877 -203.876549)
					(end 300.592998 -203.91247)
				)
			)
		)
	)
	(zone
		(layers "In1.Cu" "In2.Cu")
		(hatch none 0.5)
		(connect_pads
			(clearance 0)
		)
		(min_thickness 0.25)
		(keepout
			(tracks not_allowed)
			(vias allowed)
			(pads allowed)
			(copperpour not_allowed)
			(footprints allowed)
		)
		(placement
			(enabled no)
			(sheetname "")
		)
		(fill yes
			(thermal_gap 0.5)
			(thermal_bridge_width 0.5)
			(island_removal_mode 0)
		)
		(polygon
			(pts
				(arc
					(start 300.592998 -221.321376)
					(mid 300.607877 -221.357297)
					(end 300.643798 -221.372176)
				)
				(arc
					(start 302.043338 -221.372176)
					(mid 302.079259 -221.357297)
					(end 302.094138 -221.321376)
				)
				(arc
					(start 302.094138 -220.912436)
					(mid 302.079259 -220.876515)
					(end 302.043338 -220.861636)
				)
				(arc
					(start 300.643798 -220.861636)
					(mid 300.607877 -220.876515)
					(end 300.592998 -220.912436)
				)
			)
		)
	)
	(zone
		(layers "In1.Cu" "In2.Cu")
		(hatch none 0.5)
		(connect_pads
			(clearance 0)
		)
		(min_thickness 0.25)
		(keepout
			(tracks not_allowed)
			(vias allowed)
			(pads allowed)
			(copperpour not_allowed)
			(footprints allowed)
		)
		(placement
			(enabled no)
			(sheetname "")
		)
		(fill yes
			(thermal_gap 0.5)
			(thermal_bridge_width 0.5)
			(island_removal_mode 0)
		)
		(polygon
			(pts
				(arc
					(start 270.417798 -218.77147)
					(mid 270.432677 -218.807391)
					(end 270.468598 -218.82227)
				)
				(arc
					(start 271.868138 -218.82227)
					(mid 271.904059 -218.807391)
					(end 271.918938 -218.77147)
				)
				(arc
					(start 271.918938 -218.36253)
					(mid 271.904059 -218.326609)
					(end 271.868138 -218.31173)
				)
				(arc
					(start 270.468598 -218.31173)
					(mid 270.432677 -218.326609)
					(end 270.417798 -218.36253)
				)
			)
		)
	)
	(zone
		(layers "In1.Cu" "In2.Cu")
		(hatch none 0.5)
		(connect_pads
			(clearance 0)
		)
		(min_thickness 0.25)
		(keepout
			(tracks not_allowed)
			(vias allowed)
			(pads allowed)
			(copperpour not_allowed)
			(footprints allowed)
		)
		(placement
			(enabled no)
			(sheetname "")
		)
		(fill yes
			(thermal_gap 0.5)
			(thermal_bridge_width 0.5)
			(island_removal_mode 0)
		)
		(polygon
			(pts
				(arc
					(start 270.417798 -223.021398)
					(mid 270.432677 -223.057319)
					(end 270.468598 -223.072198)
				)
				(arc
					(start 271.868138 -223.072198)
					(mid 271.904059 -223.057319)
					(end 271.918938 -223.021398)
				)
				(arc
					(start 271.918938 -222.612458)
					(mid 271.904059 -222.576537)
					(end 271.868138 -222.561658)
				)
				(arc
					(start 270.468598 -222.561658)
					(mid 270.432677 -222.576537)
					(end 270.417798 -222.612458)
				)
			)
		)
	)
	(zone
		(layers "In1.Cu" "In2.Cu")
		(hatch none 0.5)
		(connect_pads
			(clearance 0)
		)
		(min_thickness 0.25)
		(keepout
			(tracks not_allowed)
			(vias allowed)
			(pads allowed)
			(copperpour not_allowed)
			(footprints allowed)
		)
		(placement
			(enabled no)
			(sheetname "")
		)
		(fill yes
			(thermal_gap 0.5)
			(thermal_bridge_width 0.5)
			(island_removal_mode 0)
		)
		(polygon
			(pts
				(arc
					(start 199.881998 -293.571422)
					(mid 199.896877 -293.607343)
					(end 199.932798 -293.622222)
				)
				(arc
					(start 201.332338 -293.622222)
					(mid 201.368259 -293.607343)
					(end 201.383138 -293.571422)
				)
				(arc
					(start 201.383138 -293.162482)
					(mid 201.368259 -293.126561)
					(end 201.332338 -293.111682)
				)
				(arc
					(start 199.932798 -293.111682)
					(mid 199.896877 -293.126561)
					(end 199.881998 -293.162482)
				)
			)
		)
	)
	(zone
		(layers "In1.Cu" "In2.Cu")
		(hatch none 0.5)
		(connect_pads
			(clearance 0)
		)
		(min_thickness 0.25)
		(keepout
			(tracks not_allowed)
			(vias allowed)
			(pads allowed)
			(copperpour not_allowed)
			(footprints allowed)
		)
		(placement
			(enabled no)
			(sheetname "")
		)
		(fill yes
			(thermal_gap 0.5)
			(thermal_bridge_width 0.5)
			(island_removal_mode 0)
		)
		(polygon
			(pts
				(arc
					(start 7.39013 -302.921416)
					(mid 7.405009 -302.957337)
					(end 7.44093 -302.972216)
				)
				(arc
					(start 8.84047 -302.972216)
					(mid 8.876391 -302.957337)
					(end 8.89127 -302.921416)
				)
				(arc
					(start 8.89127 -302.512476)
					(mid 8.876391 -302.476555)
					(end 8.84047 -302.461676)
				)
				(arc
					(start 7.44093 -302.461676)
					(mid 7.405009 -302.476555)
					(end 7.39013 -302.512476)
				)
			)
		)
	)
	(zone
		(layers "In1.Cu" "In2.Cu")
		(hatch none 0.5)
		(connect_pads
			(clearance 0)
		)
		(min_thickness 0.25)
		(keepout
			(tracks not_allowed)
			(vias allowed)
			(pads allowed)
			(copperpour not_allowed)
			(footprints allowed)
		)
		(placement
			(enabled no)
			(sheetname "")
		)
		(fill yes
			(thermal_gap 0.5)
			(thermal_bridge_width 0.5)
			(island_removal_mode 0)
		)
		(polygon
			(pts
				(arc
					(start 425.190666 -295.271444)
					(mid 425.205545 -295.307365)
					(end 425.241466 -295.322244)
				)
				(arc
					(start 426.641006 -295.322244)
					(mid 426.676927 -295.307365)
					(end 426.691806 -295.271444)
				)
				(arc
					(start 426.691806 -294.862504)
					(mid 426.676927 -294.826583)
					(end 426.641006 -294.811704)
				)
				(arc
					(start 425.241466 -294.811704)
					(mid 425.205545 -294.826583)
					(end 425.190666 -294.862504)
				)
			)
		)
	)
	(zone
		(layers "In1.Cu" "In2.Cu")
		(hatch none 0.5)
		(connect_pads
			(clearance 0)
		)
		(min_thickness 0.25)
		(keepout
			(tracks not_allowed)
			(vias allowed)
			(pads allowed)
			(copperpour not_allowed)
			(footprints allowed)
		)
		(placement
			(enabled no)
			(sheetname "")
		)
		(fill yes
			(thermal_gap 0.5)
			(thermal_bridge_width 0.5)
			(island_removal_mode 0)
		)
		(polygon
			(pts
				(arc
					(start 210.86953 -230.67137)
					(mid 210.884409 -230.707291)
					(end 210.92033 -230.72217)
				)
				(arc
					(start 212.31987 -230.72217)
					(mid 212.355791 -230.707291)
					(end 212.37067 -230.67137)
				)
				(arc
					(start 212.37067 -230.26243)
					(mid 212.355791 -230.226509)
					(end 212.31987 -230.21163)
				)
				(arc
					(start 210.92033 -230.21163)
					(mid 210.884409 -230.226509)
					(end 210.86953 -230.26243)
				)
			)
		)
	)
	(zone
		(layers "In1.Cu" "In2.Cu")
		(hatch none 0.5)
		(connect_pads
			(clearance 0)
		)
		(min_thickness 0.25)
		(keepout
			(tracks not_allowed)
			(vias allowed)
			(pads allowed)
			(copperpour not_allowed)
			(footprints allowed)
		)
		(placement
			(enabled no)
			(sheetname "")
		)
		(fill yes
			(thermal_gap 0.5)
			(thermal_bridge_width 0.5)
			(island_removal_mode 0)
		)
		(polygon
			(pts
				(arc
					(start 255.330198 -217.071448)
					(mid 255.345077 -217.107369)
					(end 255.380998 -217.122248)
				)
				(arc
					(start 256.780538 -217.122248)
					(mid 256.816459 -217.107369)
					(end 256.831338 -217.071448)
				)
				(arc
					(start 256.831338 -216.662508)
					(mid 256.816459 -216.626587)
					(end 256.780538 -216.611708)
				)
				(arc
					(start 255.380998 -216.611708)
					(mid 255.345077 -216.626587)
					(end 255.330198 -216.662508)
				)
			)
		)
	)
	(zone
		(layers "In1.Cu" "In2.Cu")
		(hatch none 0.5)
		(connect_pads
			(clearance 0)
		)
		(min_thickness 0.25)
		(keepout
			(tracks not_allowed)
			(vias allowed)
			(pads allowed)
			(copperpour not_allowed)
			(footprints allowed)
		)
		(placement
			(enabled no)
			(sheetname "")
		)
		(fill yes
			(thermal_gap 0.5)
			(thermal_bridge_width 0.5)
			(island_removal_mode 0)
		)
		(polygon
			(pts
				(arc
					(start 417.646866 -233.22153)
					(mid 417.661745 -233.257451)
					(end 417.697666 -233.27233)
				)
				(arc
					(start 419.097206 -233.27233)
					(mid 419.133127 -233.257451)
					(end 419.148006 -233.22153)
				)
				(arc
					(start 419.148006 -232.81259)
					(mid 419.133127 -232.776669)
					(end 419.097206 -232.76179)
				)
				(arc
					(start 417.697666 -232.76179)
					(mid 417.661745 -232.776669)
					(end 417.646866 -232.81259)
				)
			)
		)
	)
	(zone
		(layers "In1.Cu" "In2.Cu")
		(hatch none 0.5)
		(connect_pads
			(clearance 0)
		)
		(min_thickness 0.25)
		(keepout
			(tracks not_allowed)
			(vias allowed)
			(pads allowed)
			(copperpour not_allowed)
			(footprints allowed)
		)
		(placement
			(enabled no)
			(sheetname "")
		)
		(fill yes
			(thermal_gap 0.5)
			(thermal_bridge_width 0.5)
			(island_removal_mode 0)
		)
		(polygon
			(pts
				(arc
					(start 410.103066 -308.021482)
					(mid 410.117945 -308.057403)
					(end 410.153866 -308.072282)
				)
				(arc
					(start 411.553406 -308.072282)
					(mid 411.589327 -308.057403)
					(end 411.604206 -308.021482)
				)
				(arc
					(start 411.604206 -307.612542)
					(mid 411.589327 -307.576621)
					(end 411.553406 -307.561742)
				)
				(arc
					(start 410.153866 -307.561742)
					(mid 410.117945 -307.576621)
					(end 410.103066 -307.612542)
				)
			)
		)
	)
	(zone
		(layers "In1.Cu" "In2.Cu")
		(hatch none 0.5)
		(connect_pads
			(clearance 0)
		)
		(min_thickness 0.25)
		(keepout
			(tracks not_allowed)
			(vias allowed)
			(pads allowed)
			(copperpour not_allowed)
			(footprints allowed)
		)
		(placement
			(enabled no)
			(sheetname "")
		)
		(fill yes
			(thermal_gap 0.5)
			(thermal_bridge_width 0.5)
			(island_removal_mode 0)
		)
		(polygon
			(pts
				(arc
					(start 165.60673 -310.571388)
					(mid 165.621609 -310.607309)
					(end 165.65753 -310.622188)
				)
				(arc
					(start 167.05707 -310.622188)
					(mid 167.092991 -310.607309)
					(end 167.10787 -310.571388)
				)
				(arc
					(start 167.10787 -310.162448)
					(mid 167.092991 -310.126527)
					(end 167.05707 -310.111648)
				)
				(arc
					(start 165.65753 -310.111648)
					(mid 165.621609 -310.126527)
					(end 165.60673 -310.162448)
				)
			)
		)
	)
	(zone
		(layers "In1.Cu" "In2.Cu")
		(hatch none 0.5)
		(connect_pads
			(clearance 0)
		)
		(min_thickness 0.25)
		(keepout
			(tracks not_allowed)
			(vias allowed)
			(pads allowed)
			(copperpour not_allowed)
			(footprints allowed)
		)
		(placement
			(enabled no)
			(sheetname "")
		)
		(fill yes
			(thermal_gap 0.5)
			(thermal_bridge_width 0.5)
			(island_removal_mode 0)
		)
		(polygon
			(pts
				(arc
					(start 410.103066 -284.221428)
					(mid 410.117945 -284.257349)
					(end 410.153866 -284.272228)
				)
				(arc
					(start 411.553406 -284.272228)
					(mid 411.589327 -284.257349)
					(end 411.604206 -284.221428)
				)
				(arc
					(start 411.604206 -283.812488)
					(mid 411.589327 -283.776567)
					(end 411.553406 -283.761688)
				)
				(arc
					(start 410.153866 -283.761688)
					(mid 410.117945 -283.776567)
					(end 410.103066 -283.812488)
				)
			)
		)
	)
	(zone
		(layers "In1.Cu" "In2.Cu")
		(hatch none 0.5)
		(connect_pads
			(clearance 0)
		)
		(min_thickness 0.25)
		(keepout
			(tracks not_allowed)
			(vias allowed)
			(pads allowed)
			(copperpour not_allowed)
			(footprints allowed)
		)
		(placement
			(enabled no)
			(sheetname "")
		)
		(fill yes
			(thermal_gap 0.5)
			(thermal_bridge_width 0.5)
			(island_removal_mode 0)
		)
		(polygon
			(pts
				(arc
					(start 451.265798 -221.321376)
					(mid 451.280677 -221.357297)
					(end 451.316598 -221.372176)
				)
				(arc
					(start 452.716138 -221.372176)
					(mid 452.752059 -221.357297)
					(end 452.766938 -221.321376)
				)
				(arc
					(start 452.766938 -220.912436)
					(mid 452.752059 -220.876515)
					(end 452.716138 -220.861636)
				)
				(arc
					(start 451.316598 -220.861636)
					(mid 451.280677 -220.876515)
					(end 451.265798 -220.912436)
				)
			)
		)
	)
	(zone
		(layers "In1.Cu" "In2.Cu")
		(hatch none 0.5)
		(connect_pads
			(clearance 0)
		)
		(min_thickness 0.25)
		(keepout
			(tracks not_allowed)
			(vias allowed)
			(pads allowed)
			(copperpour not_allowed)
			(footprints allowed)
		)
		(placement
			(enabled no)
			(sheetname "")
		)
		(fill yes
			(thermal_gap 0.5)
			(thermal_bridge_width 0.5)
			(island_removal_mode 0)
		)
		(polygon
			(pts
				(arc
					(start 293.049198 -288.471356)
					(mid 293.064077 -288.507277)
					(end 293.099998 -288.522156)
				)
				(arc
					(start 294.499538 -288.522156)
					(mid 294.535459 -288.507277)
					(end 294.550338 -288.471356)
				)
				(arc
					(start 294.550338 -288.062416)
					(mid 294.535459 -288.026495)
					(end 294.499538 -288.011616)
				)
				(arc
					(start 293.099998 -288.011616)
					(mid 293.064077 -288.026495)
					(end 293.049198 -288.062416)
				)
			)
		)
	)
	(zone
		(layers "In1.Cu" "In2.Cu")
		(hatch none 0.5)
		(connect_pads
			(clearance 0)
		)
		(min_thickness 0.25)
		(keepout
			(tracks not_allowed)
			(vias allowed)
			(pads allowed)
			(copperpour not_allowed)
			(footprints allowed)
		)
		(placement
			(enabled no)
			(sheetname "")
		)
		(fill yes
			(thermal_gap 0.5)
			(thermal_bridge_width 0.5)
			(island_removal_mode 0)
		)
		(polygon
			(pts
				(arc
					(start 289.605466 -201.771504)
					(mid 289.620345 -201.807425)
					(end 289.656266 -201.822304)
				)
				(arc
					(start 291.055806 -201.822304)
					(mid 291.091727 -201.807425)
					(end 291.106606 -201.771504)
				)
				(arc
					(start 291.106606 -201.362564)
					(mid 291.091727 -201.326643)
					(end 291.055806 -201.311764)
				)
				(arc
					(start 289.656266 -201.311764)
					(mid 289.620345 -201.326643)
					(end 289.605466 -201.362564)
				)
			)
		)
	)
	(zone
		(layers "In1.Cu" "In2.Cu")
		(hatch none 0.5)
		(connect_pads
			(clearance 0)
		)
		(min_thickness 0.25)
		(keepout
			(tracks not_allowed)
			(vias allowed)
			(pads allowed)
			(copperpour not_allowed)
			(footprints allowed)
		)
		(placement
			(enabled no)
			(sheetname "")
		)
		(fill yes
			(thermal_gap 0.5)
			(thermal_bridge_width 0.5)
			(island_removal_mode 0)
		)
		(polygon
			(pts
				(arc
					(start 56.752998 -250.221496)
					(mid 56.767877 -250.257417)
					(end 56.803798 -250.272296)
				)
				(arc
					(start 58.203338 -250.272296)
					(mid 58.239259 -250.257417)
					(end 58.254138 -250.221496)
				)
				(arc
					(start 58.254138 -249.812556)
					(mid 58.239259 -249.776635)
					(end 58.203338 -249.761756)
				)
				(arc
					(start 56.803798 -249.761756)
					(mid 56.767877 -249.776635)
					(end 56.752998 -249.812556)
				)
			)
		)
	)
	(zone
		(layers "In1.Cu" "In2.Cu")
		(hatch none 0.5)
		(connect_pads
			(clearance 0)
		)
		(min_thickness 0.25)
		(keepout
			(tracks not_allowed)
			(vias allowed)
			(pads allowed)
			(copperpour not_allowed)
			(footprints allowed)
		)
		(placement
			(enabled no)
			(sheetname "")
		)
		(fill yes
			(thermal_gap 0.5)
			(thermal_bridge_width 0.5)
			(island_removal_mode 0)
		)
		(polygon
			(pts
				(arc
					(start 293.049198 -198.37146)
					(mid 293.064077 -198.407381)
					(end 293.099998 -198.42226)
				)
				(arc
					(start 294.499538 -198.42226)
					(mid 294.535459 -198.407381)
					(end 294.550338 -198.37146)
				)
				(arc
					(start 294.550338 -197.96252)
					(mid 294.535459 -197.926599)
					(end 294.499538 -197.91172)
				)
				(arc
					(start 293.099998 -197.91172)
					(mid 293.064077 -197.926599)
					(end 293.049198 -197.96252)
				)
			)
		)
	)
	(zone
		(layers "In1.Cu" "In2.Cu")
		(hatch none 0.5)
		(connect_pads
			(clearance 0)
		)
		(min_thickness 0.25)
		(keepout
			(tracks not_allowed)
			(vias allowed)
			(pads allowed)
			(copperpour not_allowed)
			(footprints allowed)
		)
		(placement
			(enabled no)
			(sheetname "")
		)
		(fill yes
			(thermal_gap 0.5)
			(thermal_bridge_width 0.5)
			(island_removal_mode 0)
		)
		(polygon
			(pts
				(arc
					(start 60.19673 -312.27141)
					(mid 60.211609 -312.307331)
					(end 60.24753 -312.32221)
				)
				(arc
					(start 61.64707 -312.32221)
					(mid 61.682991 -312.307331)
					(end 61.69787 -312.27141)
				)
				(arc
					(start 61.69787 -311.86247)
					(mid 61.682991 -311.826549)
					(end 61.64707 -311.81167)
				)
				(arc
					(start 60.24753 -311.81167)
					(mid 60.211609 -311.826549)
					(end 60.19673 -311.86247)
				)
			)
		)
	)
	(zone
		(layers "In1.Cu" "In2.Cu")
		(hatch none 0.5)
		(connect_pads
			(clearance 0)
		)
		(min_thickness 0.25)
		(keepout
			(tracks not_allowed)
			(vias allowed)
			(pads allowed)
			(copperpour not_allowed)
			(footprints allowed)
		)
		(placement
			(enabled no)
			(sheetname "")
		)
		(fill yes
			(thermal_gap 0.5)
			(thermal_bridge_width 0.5)
			(island_removal_mode 0)
		)
		(polygon
			(pts
				(arc
					(start 458.809598 -244.271292)
					(mid 458.824477 -244.307213)
					(end 458.860398 -244.322092)
				)
				(arc
					(start 460.259938 -244.322092)
					(mid 460.295859 -244.307213)
					(end 460.310738 -244.271292)
				)
				(arc
					(start 460.310738 -243.862352)
					(mid 460.295859 -243.826431)
					(end 460.259938 -243.811552)
				)
				(arc
					(start 458.860398 -243.811552)
					(mid 458.824477 -243.826431)
					(end 458.809598 -243.862352)
				)
			)
		)
	)
	(zone
		(layers "In1.Cu" "In2.Cu")
		(hatch none 0.5)
		(connect_pads
			(clearance 0)
		)
		(min_thickness 0.25)
		(keepout
			(tracks not_allowed)
			(vias allowed)
			(pads allowed)
			(copperpour not_allowed)
			(footprints allowed)
		)
		(placement
			(enabled no)
			(sheetname "")
		)
		(fill yes
			(thermal_gap 0.5)
			(thermal_bridge_width 0.5)
			(island_removal_mode 0)
		)
		(polygon
			(pts
				(arc
					(start 30.02153 -221.321376)
					(mid 30.036409 -221.357297)
					(end 30.07233 -221.372176)
				)
				(arc
					(start 31.47187 -221.372176)
					(mid 31.507791 -221.357297)
					(end 31.52267 -221.321376)
				)
				(arc
					(start 31.52267 -220.912436)
					(mid 31.507791 -220.876515)
					(end 31.47187 -220.861636)
				)
				(arc
					(start 30.07233 -220.861636)
					(mid 30.036409 -220.876515)
					(end 30.02153 -220.912436)
				)
			)
		)
	)
	(zone
		(layers "In1.Cu" "In2.Cu")
		(hatch none 0.5)
		(connect_pads
			(clearance 0)
		)
		(min_thickness 0.25)
		(keepout
			(tracks not_allowed)
			(vias allowed)
			(pads allowed)
			(copperpour not_allowed)
			(footprints allowed)
		)
		(placement
			(enabled no)
			(sheetname "")
		)
		(fill yes
			(thermal_gap 0.5)
			(thermal_bridge_width 0.5)
			(island_removal_mode 0)
		)
		(polygon
			(pts
				(arc
					(start 451.265798 -299.521372)
					(mid 451.280677 -299.557293)
					(end 451.316598 -299.572172)
				)
				(arc
					(start 452.716138 -299.572172)
					(mid 452.752059 -299.557293)
					(end 452.766938 -299.521372)
				)
				(arc
					(start 452.766938 -299.112432)
					(mid 452.752059 -299.076511)
					(end 452.716138 -299.061632)
				)
				(arc
					(start 451.316598 -299.061632)
					(mid 451.280677 -299.076511)
					(end 451.265798 -299.112432)
				)
			)
		)
	)
	(zone
		(layers "In1.Cu" "In2.Cu")
		(hatch none 0.5)
		(connect_pads
			(clearance 0)
		)
		(min_thickness 0.25)
		(keepout
			(tracks not_allowed)
			(vias allowed)
			(pads allowed)
			(copperpour not_allowed)
			(footprints allowed)
		)
		(placement
			(enabled no)
			(sheetname "")
		)
		(fill yes
			(thermal_gap 0.5)
			(thermal_bridge_width 0.5)
			(island_removal_mode 0)
		)
		(polygon
			(pts
				(arc
					(start 195.78193 -291.8714)
					(mid 195.796809 -291.907321)
					(end 195.83273 -291.9222)
				)
				(arc
					(start 197.23227 -291.9222)
					(mid 197.268191 -291.907321)
					(end 197.28307 -291.8714)
				)
				(arc
					(start 197.28307 -291.46246)
					(mid 197.268191 -291.426539)
					(end 197.23227 -291.41166)
				)
				(arc
					(start 195.83273 -291.41166)
					(mid 195.796809 -291.426539)
					(end 195.78193 -291.46246)
				)
			)
		)
	)
	(zone
		(layers "In1.Cu" "In2.Cu")
		(hatch none 0.5)
		(connect_pads
			(clearance 0)
		)
		(min_thickness 0.25)
		(keepout
			(tracks not_allowed)
			(vias allowed)
			(pads allowed)
			(copperpour not_allowed)
			(footprints allowed)
		)
		(placement
			(enabled no)
			(sheetname "")
		)
		(fill yes
			(thermal_gap 0.5)
			(thermal_bridge_width 0.5)
			(island_removal_mode 0)
		)
		(polygon
			(pts
				(arc
					(start 266.974066 -222.171514)
					(mid 266.988945 -222.207435)
					(end 267.024866 -222.222314)
				)
				(arc
					(start 268.424406 -222.222314)
					(mid 268.460327 -222.207435)
					(end 268.475206 -222.171514)
				)
				(arc
					(start 268.475206 -221.762574)
					(mid 268.460327 -221.726653)
					(end 268.424406 -221.711774)
				)
				(arc
					(start 267.024866 -221.711774)
					(mid 266.988945 -221.726653)
					(end 266.974066 -221.762574)
				)
			)
		)
	)
	(zone
		(layers "In1.Cu" "In2.Cu")
		(hatch none 0.5)
		(connect_pads
			(clearance 0)
		)
		(min_thickness 0.25)
		(keepout
			(tracks not_allowed)
			(vias allowed)
			(pads allowed)
			(copperpour not_allowed)
			(footprints allowed)
		)
		(placement
			(enabled no)
			(sheetname "")
		)
		(fill yes
			(thermal_gap 0.5)
			(thermal_bridge_width 0.5)
			(island_removal_mode 0)
		)
		(polygon
			(pts
				(arc
					(start 274.517866 -284.221428)
					(mid 274.532745 -284.257349)
					(end 274.568666 -284.272228)
				)
				(arc
					(start 275.968206 -284.272228)
					(mid 276.004127 -284.257349)
					(end 276.019006 -284.221428)
				)
				(arc
					(start 276.019006 -283.812488)
					(mid 276.004127 -283.776567)
					(end 275.968206 -283.761688)
				)
				(arc
					(start 274.568666 -283.761688)
					(mid 274.532745 -283.776567)
					(end 274.517866 -283.812488)
				)
			)
		)
	)
	(zone
		(layers "In1.Cu" "In2.Cu")
		(hatch none 0.5)
		(connect_pads
			(clearance 0)
		)
		(min_thickness 0.25)
		(keepout
			(tracks not_allowed)
			(vias allowed)
			(pads allowed)
			(copperpour not_allowed)
			(footprints allowed)
		)
		(placement
			(enabled no)
			(sheetname "")
		)
		(fill yes
			(thermal_gap 0.5)
			(thermal_bridge_width 0.5)
			(island_removal_mode 0)
		)
		(polygon
			(pts
				(arc
					(start 425.190666 -272.321528)
					(mid 425.205545 -272.357449)
					(end 425.241466 -272.372328)
				)
				(arc
					(start 426.641006 -272.372328)
					(mid 426.676927 -272.357449)
					(end 426.691806 -272.321528)
				)
				(arc
					(start 426.691806 -271.912588)
					(mid 426.676927 -271.876667)
					(end 426.641006 -271.861788)
				)
				(arc
					(start 425.241466 -271.861788)
					(mid 425.205545 -271.876667)
					(end 425.190666 -271.912588)
				)
			)
		)
	)
	(zone
		(layers "In1.Cu" "In2.Cu")
		(hatch none 0.5)
		(connect_pads
			(clearance 0)
		)
		(min_thickness 0.25)
		(keepout
			(tracks not_allowed)
			(vias allowed)
			(pads allowed)
			(copperpour not_allowed)
			(footprints allowed)
		)
		(placement
			(enabled no)
			(sheetname "")
		)
		(fill yes
			(thermal_gap 0.5)
			(thermal_bridge_width 0.5)
			(island_removal_mode 0)
		)
		(polygon
			(pts
				(arc
					(start 440.278266 -220.471492)
					(mid 440.293145 -220.507413)
					(end 440.329066 -220.522292)
				)
				(arc
					(start 441.728606 -220.522292)
					(mid 441.764527 -220.507413)
					(end 441.779406 -220.471492)
				)
				(arc
					(start 441.779406 -220.062552)
					(mid 441.764527 -220.026631)
					(end 441.728606 -220.011752)
				)
				(arc
					(start 440.329066 -220.011752)
					(mid 440.293145 -220.026631)
					(end 440.278266 -220.062552)
				)
			)
		)
	)
	(zone
		(layers "In1.Cu" "In2.Cu")
		(hatch none 0.5)
		(connect_pads
			(clearance 0)
		)
		(min_thickness 0.25)
		(keepout
			(tracks not_allowed)
			(vias allowed)
			(pads allowed)
			(copperpour not_allowed)
			(footprints allowed)
		)
		(placement
			(enabled no)
			(sheetname "")
		)
		(fill yes
			(thermal_gap 0.5)
			(thermal_bridge_width 0.5)
			(island_removal_mode 0)
		)
		(polygon
			(pts
				(arc
					(start 52.65293 -290.171378)
					(mid 52.667809 -290.207299)
					(end 52.70373 -290.222178)
				)
				(arc
					(start 54.10327 -290.222178)
					(mid 54.139191 -290.207299)
					(end 54.15407 -290.171378)
				)
				(arc
					(start 54.15407 -289.762438)
					(mid 54.139191 -289.726517)
					(end 54.10327 -289.711638)
				)
				(arc
					(start 52.70373 -289.711638)
					(mid 52.667809 -289.726517)
					(end 52.65293 -289.762438)
				)
			)
		)
	)
	(zone
		(layers "In1.Cu" "In2.Cu")
		(hatch none 0.5)
		(connect_pads
			(clearance 0)
		)
		(min_thickness 0.25)
		(keepout
			(tracks not_allowed)
			(vias allowed)
			(pads allowed)
			(copperpour not_allowed)
			(footprints allowed)
		)
		(placement
			(enabled no)
			(sheetname "")
		)
		(fill yes
			(thermal_gap 0.5)
			(thermal_bridge_width 0.5)
			(island_removal_mode 0)
		)
		(polygon
			(pts
				(arc
					(start 462.909666 -281.671522)
					(mid 462.924545 -281.707443)
					(end 462.960466 -281.722322)
				)
				(arc
					(start 464.360006 -281.722322)
					(mid 464.395927 -281.707443)
					(end 464.410806 -281.671522)
				)
				(arc
					(start 464.410806 -281.262582)
					(mid 464.395927 -281.226661)
					(end 464.360006 -281.211782)
				)
				(arc
					(start 462.960466 -281.211782)
					(mid 462.924545 -281.226661)
					(end 462.909666 -281.262582)
				)
			)
		)
	)
	(zone
		(layers "In1.Cu" "In2.Cu")
		(hatch none 0.5)
		(connect_pads
			(clearance 0)
		)
		(min_thickness 0.25)
		(keepout
			(tracks not_allowed)
			(vias allowed)
			(pads allowed)
			(copperpour not_allowed)
			(footprints allowed)
		)
		(placement
			(enabled no)
			(sheetname "")
		)
		(fill yes
			(thermal_gap 0.5)
			(thermal_bridge_width 0.5)
			(island_removal_mode 0)
		)
		(polygon
			(pts
				(arc
					(start 195.78193 -288.471356)
					(mid 195.796809 -288.507277)
					(end 195.83273 -288.522156)
				)
				(arc
					(start 197.23227 -288.522156)
					(mid 197.268191 -288.507277)
					(end 197.28307 -288.471356)
				)
				(arc
					(start 197.28307 -288.062416)
					(mid 197.268191 -288.026495)
					(end 197.23227 -288.011616)
				)
				(arc
					(start 195.83273 -288.011616)
					(mid 195.796809 -288.026495)
					(end 195.78193 -288.062416)
				)
			)
		)
	)
	(zone
		(layers "In1.Cu" "In2.Cu")
		(hatch none 0.5)
		(connect_pads
			(clearance 0)
		)
		(min_thickness 0.25)
		(keepout
			(tracks not_allowed)
			(vias allowed)
			(pads allowed)
			(copperpour not_allowed)
			(footprints allowed)
		)
		(placement
			(enabled no)
			(sheetname "")
		)
		(fill yes
			(thermal_gap 0.5)
			(thermal_bridge_width 0.5)
			(island_removal_mode 0)
		)
		(polygon
			(pts
				(arc
					(start 30.02153 -286.771334)
					(mid 30.036409 -286.807255)
					(end 30.07233 -286.822134)
				)
				(arc
					(start 31.47187 -286.822134)
					(mid 31.507791 -286.807255)
					(end 31.52267 -286.771334)
				)
				(arc
					(start 31.52267 -286.362394)
					(mid 31.507791 -286.326473)
					(end 31.47187 -286.311594)
				)
				(arc
					(start 30.07233 -286.311594)
					(mid 30.036409 -286.326473)
					(end 30.02153 -286.362394)
				)
			)
		)
	)
	(zone
		(layers "In1.Cu" "In2.Cu")
		(hatch none 0.5)
		(connect_pads
			(clearance 0)
		)
		(min_thickness 0.25)
		(keepout
			(tracks not_allowed)
			(vias allowed)
			(pads allowed)
			(copperpour not_allowed)
			(footprints allowed)
		)
		(placement
			(enabled no)
			(sheetname "")
		)
		(fill yes
			(thermal_gap 0.5)
			(thermal_bridge_width 0.5)
			(island_removal_mode 0)
		)
		(polygon
			(pts
				(arc
					(start 169.706798 -283.371544)
					(mid 169.721677 -283.407465)
					(end 169.757598 -283.422344)
				)
				(arc
					(start 171.157138 -283.422344)
					(mid 171.193059 -283.407465)
					(end 171.207938 -283.371544)
				)
				(arc
					(start 171.207938 -282.962604)
					(mid 171.193059 -282.926683)
					(end 171.157138 -282.911804)
				)
				(arc
					(start 169.757598 -282.911804)
					(mid 169.721677 -282.926683)
					(end 169.706798 -282.962604)
				)
			)
		)
	)
	(zone
		(layers "In1.Cu" "In2.Cu")
		(hatch none 0.5)
		(connect_pads
			(clearance 0)
		)
		(min_thickness 0.25)
		(keepout
			(tracks not_allowed)
			(vias allowed)
			(pads allowed)
			(copperpour not_allowed)
			(footprints allowed)
		)
		(placement
			(enabled no)
			(sheetname "")
		)
		(fill yes
			(thermal_gap 0.5)
			(thermal_bridge_width 0.5)
			(island_removal_mode 0)
		)
		(polygon
			(pts
				(arc
					(start 203.32573 -275.721318)
					(mid 203.340609 -275.757239)
					(end 203.37653 -275.772118)
				)
				(arc
					(start 204.77607 -275.772118)
					(mid 204.811991 -275.757239)
					(end 204.82687 -275.721318)
				)
				(arc
					(start 204.82687 -275.312378)
					(mid 204.811991 -275.276457)
					(end 204.77607 -275.261578)
				)
				(arc
					(start 203.37653 -275.261578)
					(mid 203.340609 -275.276457)
					(end 203.32573 -275.312378)
				)
			)
		)
	)
	(zone
		(layers "In1.Cu" "In2.Cu")
		(hatch none 0.5)
		(connect_pads
			(clearance 0)
		)
		(min_thickness 0.25)
		(keepout
			(tracks not_allowed)
			(vias allowed)
			(pads allowed)
			(copperpour not_allowed)
			(footprints allowed)
		)
		(placement
			(enabled no)
			(sheetname "")
		)
		(fill yes
			(thermal_gap 0.5)
			(thermal_bridge_width 0.5)
			(island_removal_mode 0)
		)
		(polygon
			(pts
				(arc
					(start 413.546798 -273.171412)
					(mid 413.561677 -273.207333)
					(end 413.597598 -273.222212)
				)
				(arc
					(start 414.997138 -273.222212)
					(mid 415.033059 -273.207333)
					(end 415.047938 -273.171412)
				)
				(arc
					(start 415.047938 -272.762472)
					(mid 415.033059 -272.726551)
					(end 414.997138 -272.711672)
				)
				(arc
					(start 413.597598 -272.711672)
					(mid 413.561677 -272.726551)
					(end 413.546798 -272.762472)
				)
			)
		)
	)
	(zone
		(layers "In1.Cu" "In2.Cu")
		(hatch none 0.5)
		(connect_pads
			(clearance 0)
		)
		(min_thickness 0.25)
		(keepout
			(tracks not_allowed)
			(vias allowed)
			(pads allowed)
			(copperpour not_allowed)
			(footprints allowed)
		)
		(placement
			(enabled no)
			(sheetname "")
		)
		(fill yes
			(thermal_gap 0.5)
			(thermal_bridge_width 0.5)
			(island_removal_mode 0)
		)
		(polygon
			(pts
				(arc
					(start 173.15053 -217.071448)
					(mid 173.165409 -217.107369)
					(end 173.20133 -217.122248)
				)
				(arc
					(start 174.60087 -217.122248)
					(mid 174.636791 -217.107369)
					(end 174.65167 -217.071448)
				)
				(arc
					(start 174.65167 -216.662508)
					(mid 174.636791 -216.626587)
					(end 174.60087 -216.611708)
				)
				(arc
					(start 173.20133 -216.611708)
					(mid 173.165409 -216.626587)
					(end 173.15053 -216.662508)
				)
			)
		)
	)
	(zone
		(layers "In1.Cu" "In2.Cu")
		(hatch none 0.5)
		(connect_pads
			(clearance 0)
		)
		(min_thickness 0.25)
		(keepout
			(tracks not_allowed)
			(vias allowed)
			(pads allowed)
			(copperpour not_allowed)
			(footprints allowed)
		)
		(placement
			(enabled no)
			(sheetname "")
		)
		(fill yes
			(thermal_gap 0.5)
			(thermal_bridge_width 0.5)
			(island_removal_mode 0)
		)
		(polygon
			(pts
				(arc
					(start 180.69433 -240.021364)
					(mid 180.709209 -240.057285)
					(end 180.74513 -240.072164)
				)
				(arc
					(start 182.14467 -240.072164)
					(mid 182.180591 -240.057285)
					(end 182.19547 -240.021364)
				)
				(arc
					(start 182.19547 -239.612424)
					(mid 182.180591 -239.576503)
					(end 182.14467 -239.561624)
				)
				(arc
					(start 180.74513 -239.561624)
					(mid 180.709209 -239.576503)
					(end 180.69433 -239.612424)
				)
			)
		)
	)
	(zone
		(layers "In1.Cu" "In2.Cu")
		(hatch none 0.5)
		(connect_pads
			(clearance 0)
		)
		(min_thickness 0.25)
		(keepout
			(tracks not_allowed)
			(vias allowed)
			(pads allowed)
			(copperpour not_allowed)
			(footprints allowed)
		)
		(placement
			(enabled no)
			(sheetname "")
		)
		(fill yes
			(thermal_gap 0.5)
			(thermal_bridge_width 0.5)
			(island_removal_mode 0)
		)
		(polygon
			(pts
				(arc
					(start 192.338198 -237.471458)
					(mid 192.353077 -237.507379)
					(end 192.388998 -237.522258)
				)
				(arc
					(start 193.788538 -237.522258)
					(mid 193.824459 -237.507379)
					(end 193.839338 -237.471458)
				)
				(arc
					(start 193.839338 -237.062518)
					(mid 193.824459 -237.026597)
					(end 193.788538 -237.011718)
				)
				(arc
					(start 192.388998 -237.011718)
					(mid 192.353077 -237.026597)
					(end 192.338198 -237.062518)
				)
			)
		)
	)
	(zone
		(layers "In1.Cu" "In2.Cu")
		(hatch none 0.5)
		(connect_pads
			(clearance 0)
		)
		(min_thickness 0.25)
		(keepout
			(tracks not_allowed)
			(vias allowed)
			(pads allowed)
			(copperpour not_allowed)
			(footprints allowed)
		)
		(placement
			(enabled no)
			(sheetname "")
		)
		(fill yes
			(thermal_gap 0.5)
			(thermal_bridge_width 0.5)
			(island_removal_mode 0)
		)
		(polygon
			(pts
				(arc
					(start 34.121598 -302.071532)
					(mid 34.136477 -302.107453)
					(end 34.172398 -302.122332)
				)
				(arc
					(start 35.571938 -302.122332)
					(mid 35.607859 -302.107453)
					(end 35.622738 -302.071532)
				)
				(arc
					(start 35.622738 -301.662592)
					(mid 35.607859 -301.626671)
					(end 35.571938 -301.611792)
				)
				(arc
					(start 34.172398 -301.611792)
					(mid 34.136477 -301.626671)
					(end 34.121598 -301.662592)
				)
			)
		)
	)
	(zone
		(layers "In1.Cu" "In2.Cu")
		(hatch none 0.5)
		(connect_pads
			(clearance 0)
		)
		(min_thickness 0.25)
		(keepout
			(tracks not_allowed)
			(vias allowed)
			(pads allowed)
			(copperpour not_allowed)
			(footprints allowed)
		)
		(placement
			(enabled no)
			(sheetname "")
		)
		(fill yes
			(thermal_gap 0.5)
			(thermal_bridge_width 0.5)
			(island_removal_mode 0)
		)
		(polygon
			(pts
				(arc
					(start 64.296798 -260.421374)
					(mid 64.311677 -260.457295)
					(end 64.347598 -260.472174)
				)
				(arc
					(start 65.747138 -260.472174)
					(mid 65.783059 -260.457295)
					(end 65.797938 -260.421374)
				)
				(arc
					(start 65.797938 -260.012434)
					(mid 65.783059 -259.976513)
					(end 65.747138 -259.961634)
				)
				(arc
					(start 64.347598 -259.961634)
					(mid 64.311677 -259.976513)
					(end 64.296798 -260.012434)
				)
			)
		)
	)
	(zone
		(layers "In1.Cu" "In2.Cu")
		(hatch none 0.5)
		(connect_pads
			(clearance 0)
		)
		(min_thickness 0.25)
		(keepout
			(tracks not_allowed)
			(vias allowed)
			(pads allowed)
			(copperpour not_allowed)
			(footprints allowed)
		)
		(placement
			(enabled no)
			(sheetname "")
		)
		(fill yes
			(thermal_gap 0.5)
			(thermal_bridge_width 0.5)
			(island_removal_mode 0)
		)
		(polygon
			(pts
				(arc
					(start 304.693066 -259.57149)
					(mid 304.707945 -259.607411)
					(end 304.743866 -259.62229)
				)
				(arc
					(start 306.143406 -259.62229)
					(mid 306.179327 -259.607411)
					(end 306.194206 -259.57149)
				)
				(arc
					(start 306.194206 -259.16255)
					(mid 306.179327 -259.126629)
					(end 306.143406 -259.11175)
				)
				(arc
					(start 304.743866 -259.11175)
					(mid 304.707945 -259.126629)
					(end 304.693066 -259.16255)
				)
			)
		)
	)
	(zone
		(layers "In1.Cu" "In2.Cu")
		(hatch none 0.5)
		(connect_pads
			(clearance 0)
		)
		(min_thickness 0.25)
		(keepout
			(tracks not_allowed)
			(vias allowed)
			(pads allowed)
			(copperpour not_allowed)
			(footprints allowed)
		)
		(placement
			(enabled no)
			(sheetname "")
		)
		(fill yes
			(thermal_gap 0.5)
			(thermal_bridge_width 0.5)
			(island_removal_mode 0)
		)
		(polygon
			(pts
				(arc
					(start 180.69433 -200.921366)
					(mid 180.709209 -200.957287)
					(end 180.74513 -200.972166)
				)
				(arc
					(start 182.14467 -200.972166)
					(mid 182.180591 -200.957287)
					(end 182.19547 -200.921366)
				)
				(arc
					(start 182.19547 -200.512426)
					(mid 182.180591 -200.476505)
					(end 182.14467 -200.461626)
				)
				(arc
					(start 180.74513 -200.461626)
					(mid 180.709209 -200.476505)
					(end 180.69433 -200.512426)
				)
			)
		)
	)
	(zone
		(layers "In1.Cu" "In2.Cu")
		(hatch none 0.5)
		(connect_pads
			(clearance 0)
		)
		(min_thickness 0.25)
		(keepout
			(tracks not_allowed)
			(vias allowed)
			(pads allowed)
			(copperpour not_allowed)
			(footprints allowed)
		)
		(placement
			(enabled no)
			(sheetname "")
		)
		(fill yes
			(thermal_gap 0.5)
			(thermal_bridge_width 0.5)
			(island_removal_mode 0)
		)
		(polygon
			(pts
				(arc
					(start 410.103066 -315.671454)
					(mid 410.117945 -315.707375)
					(end 410.153866 -315.722254)
				)
				(arc
					(start 411.553406 -315.722254)
					(mid 411.589327 -315.707375)
					(end 411.604206 -315.671454)
				)
				(arc
					(start 411.604206 -315.262514)
					(mid 411.589327 -315.226593)
					(end 411.553406 -315.211714)
				)
				(arc
					(start 410.153866 -315.211714)
					(mid 410.117945 -315.226593)
					(end 410.103066 -315.262514)
				)
			)
		)
	)
	(zone
		(layers "In1.Cu" "In2.Cu")
		(hatch none 0.5)
		(connect_pads
			(clearance 0)
		)
		(min_thickness 0.25)
		(keepout
			(tracks not_allowed)
			(vias allowed)
			(pads allowed)
			(copperpour not_allowed)
			(footprints allowed)
		)
		(placement
			(enabled no)
			(sheetname "")
		)
		(fill yes
			(thermal_gap 0.5)
			(thermal_bridge_width 0.5)
			(island_removal_mode 0)
		)
		(polygon
			(pts
				(arc
					(start 158.06293 -228.971348)
					(mid 158.077809 -229.007269)
					(end 158.11373 -229.022148)
				)
				(arc
					(start 159.51327 -229.022148)
					(mid 159.549191 -229.007269)
					(end 159.56407 -228.971348)
				)
				(arc
					(start 159.56407 -228.562408)
					(mid 159.549191 -228.526487)
					(end 159.51327 -228.511608)
				)
				(arc
					(start 158.11373 -228.511608)
					(mid 158.077809 -228.526487)
					(end 158.06293 -228.562408)
				)
			)
		)
	)
	(zone
		(layers "In1.Cu" "In2.Cu")
		(hatch none 0.5)
		(connect_pads
			(clearance 0)
		)
		(min_thickness 0.25)
		(keepout
			(tracks not_allowed)
			(vias allowed)
			(pads allowed)
			(copperpour not_allowed)
			(footprints allowed)
		)
		(placement
			(enabled no)
			(sheetname "")
		)
		(fill yes
			(thermal_gap 0.5)
			(thermal_bridge_width 0.5)
			(island_removal_mode 0)
		)
		(polygon
			(pts
				(arc
					(start 184.794398 -295.271444)
					(mid 184.809277 -295.307365)
					(end 184.845198 -295.322244)
				)
				(arc
					(start 186.244738 -295.322244)
					(mid 186.280659 -295.307365)
					(end 186.295538 -295.271444)
				)
				(arc
					(start 186.295538 -294.862504)
					(mid 186.280659 -294.826583)
					(end 186.244738 -294.811704)
				)
				(arc
					(start 184.845198 -294.811704)
					(mid 184.809277 -294.826583)
					(end 184.794398 -294.862504)
				)
			)
		)
	)
	(zone
		(layers "In1.Cu" "In2.Cu")
		(hatch none 0.5)
		(connect_pads
			(clearance 0)
		)
		(min_thickness 0.25)
		(keepout
			(tracks not_allowed)
			(vias allowed)
			(pads allowed)
			(copperpour not_allowed)
			(footprints allowed)
		)
		(placement
			(enabled no)
			(sheetname "")
		)
		(fill yes
			(thermal_gap 0.5)
			(thermal_bridge_width 0.5)
			(island_removal_mode 0)
		)
		(polygon
			(pts
				(arc
					(start 297.149266 -279.9715)
					(mid 297.164145 -280.007421)
					(end 297.200066 -280.0223)
				)
				(arc
					(start 298.599606 -280.0223)
					(mid 298.635527 -280.007421)
					(end 298.650406 -279.9715)
				)
				(arc
					(start 298.650406 -279.56256)
					(mid 298.635527 -279.526639)
					(end 298.599606 -279.51176)
				)
				(arc
					(start 297.200066 -279.51176)
					(mid 297.164145 -279.526639)
					(end 297.149266 -279.56256)
				)
			)
		)
	)
	(zone
		(layers "In1.Cu" "In2.Cu")
		(hatch none 0.5)
		(connect_pads
			(clearance 0)
		)
		(min_thickness 0.25)
		(keepout
			(tracks not_allowed)
			(vias allowed)
			(pads allowed)
			(copperpour not_allowed)
			(footprints allowed)
		)
		(placement
			(enabled no)
			(sheetname "")
		)
		(fill yes
			(thermal_gap 0.5)
			(thermal_bridge_width 0.5)
			(island_removal_mode 0)
		)
		(polygon
			(pts
				(arc
					(start 184.794398 -296.971466)
					(mid 184.809277 -297.007387)
					(end 184.845198 -297.022266)
				)
				(arc
					(start 186.244738 -297.022266)
					(mid 186.280659 -297.007387)
					(end 186.295538 -296.971466)
				)
				(arc
					(start 186.295538 -296.562526)
					(mid 186.280659 -296.526605)
					(end 186.244738 -296.511726)
				)
				(arc
					(start 184.845198 -296.511726)
					(mid 184.809277 -296.526605)
					(end 184.794398 -296.562526)
				)
			)
		)
	)
	(zone
		(layers "In1.Cu" "In2.Cu")
		(hatch none 0.5)
		(connect_pads
			(clearance 0)
		)
		(min_thickness 0.25)
		(keepout
			(tracks not_allowed)
			(vias allowed)
			(pads allowed)
			(copperpour not_allowed)
			(footprints allowed)
		)
		(placement
			(enabled no)
			(sheetname "")
		)
		(fill yes
			(thermal_gap 0.5)
			(thermal_bridge_width 0.5)
			(island_removal_mode 0)
		)
		(polygon
			(pts
				(arc
					(start 45.10913 -291.8714)
					(mid 45.124009 -291.907321)
					(end 45.15993 -291.9222)
				)
				(arc
					(start 46.55947 -291.9222)
					(mid 46.595391 -291.907321)
					(end 46.61027 -291.8714)
				)
				(arc
					(start 46.61027 -291.46246)
					(mid 46.595391 -291.426539)
					(end 46.55947 -291.41166)
				)
				(arc
					(start 45.15993 -291.41166)
					(mid 45.124009 -291.426539)
					(end 45.10913 -291.46246)
				)
			)
		)
	)
	(zone
		(layers "In1.Cu" "In2.Cu")
		(hatch none 0.5)
		(connect_pads
			(clearance 0)
		)
		(min_thickness 0.25)
		(keepout
			(tracks not_allowed)
			(vias allowed)
			(pads allowed)
			(copperpour not_allowed)
			(footprints allowed)
		)
		(placement
			(enabled no)
			(sheetname "")
		)
		(fill yes
			(thermal_gap 0.5)
			(thermal_bridge_width 0.5)
			(island_removal_mode 0)
		)
		(polygon
			(pts
				(arc
					(start 443.721998 -264.671302)
					(mid 443.736877 -264.707223)
					(end 443.772798 -264.722102)
				)
				(arc
					(start 445.172338 -264.722102)
					(mid 445.208259 -264.707223)
					(end 445.223138 -264.671302)
				)
				(arc
					(start 445.223138 -264.262362)
					(mid 445.208259 -264.226441)
					(end 445.172338 -264.211562)
				)
				(arc
					(start 443.772798 -264.211562)
					(mid 443.736877 -264.226441)
					(end 443.721998 -264.262362)
				)
			)
		)
	)
	(zone
		(layers "In1.Cu" "In2.Cu")
		(hatch none 0.5)
		(connect_pads
			(clearance 0)
		)
		(min_thickness 0.25)
		(keepout
			(tracks not_allowed)
			(vias allowed)
			(pads allowed)
			(copperpour not_allowed)
			(footprints allowed)
		)
		(placement
			(enabled no)
			(sheetname "")
		)
		(fill yes
			(thermal_gap 0.5)
			(thermal_bridge_width 0.5)
			(island_removal_mode 0)
		)
		(polygon
			(pts
				(arc
					(start 312.236866 -228.121464)
					(mid 312.251745 -228.157385)
					(end 312.287666 -228.172264)
				)
				(arc
					(start 313.687206 -228.172264)
					(mid 313.723127 -228.157385)
					(end 313.738006 -228.121464)
				)
				(arc
					(start 313.738006 -227.712524)
					(mid 313.723127 -227.676603)
					(end 313.687206 -227.661724)
				)
				(arc
					(start 312.287666 -227.661724)
					(mid 312.251745 -227.676603)
					(end 312.236866 -227.712524)
				)
			)
		)
	)
	(zone
		(layers "In1.Cu" "In2.Cu")
		(hatch none 0.5)
		(connect_pads
			(clearance 0)
		)
		(min_thickness 0.25)
		(keepout
			(tracks not_allowed)
			(vias allowed)
			(pads allowed)
			(copperpour not_allowed)
			(footprints allowed)
		)
		(placement
			(enabled no)
			(sheetname "")
		)
		(fill yes
			(thermal_gap 0.5)
			(thermal_bridge_width 0.5)
			(island_removal_mode 0)
		)
		(polygon
			(pts
				(arc
					(start 7.39013 -294.421306)
					(mid 7.405009 -294.457227)
					(end 7.44093 -294.472106)
				)
				(arc
					(start 8.84047 -294.472106)
					(mid 8.876391 -294.457227)
					(end 8.89127 -294.421306)
				)
				(arc
					(start 8.89127 -294.012366)
					(mid 8.876391 -293.976445)
					(end 8.84047 -293.961566)
				)
				(arc
					(start 7.44093 -293.961566)
					(mid 7.405009 -293.976445)
					(end 7.39013 -294.012366)
				)
			)
		)
	)
	(zone
		(layers "In1.Cu" "In2.Cu")
		(hatch none 0.5)
		(connect_pads
			(clearance 0)
		)
		(min_thickness 0.25)
		(keepout
			(tracks not_allowed)
			(vias allowed)
			(pads allowed)
			(copperpour not_allowed)
			(footprints allowed)
		)
		(placement
			(enabled no)
			(sheetname "")
		)
		(fill yes
			(thermal_gap 0.5)
			(thermal_bridge_width 0.5)
			(island_removal_mode 0)
		)
		(polygon
			(pts
				(arc
					(start 455.365866 -267.221462)
					(mid 455.380745 -267.257383)
					(end 455.416666 -267.272262)
				)
				(arc
					(start 456.816206 -267.272262)
					(mid 456.852127 -267.257383)
					(end 456.867006 -267.221462)
				)
				(arc
					(start 456.867006 -266.812522)
					(mid 456.852127 -266.776601)
					(end 456.816206 -266.761722)
				)
				(arc
					(start 455.416666 -266.761722)
					(mid 455.380745 -266.776601)
					(end 455.365866 -266.812522)
				)
			)
		)
	)
	(zone
		(layers "In1.Cu" "In2.Cu")
		(hatch none 0.5)
		(connect_pads
			(clearance 0)
		)
		(min_thickness 0.25)
		(keepout
			(tracks not_allowed)
			(vias allowed)
			(pads allowed)
			(copperpour not_allowed)
			(footprints allowed)
		)
		(placement
			(enabled no)
			(sheetname "")
		)
		(fill yes
			(thermal_gap 0.5)
			(thermal_bridge_width 0.5)
			(island_removal_mode 0)
		)
		(polygon
			(pts
				(arc
					(start 214.969598 -200.071482)
					(mid 214.984477 -200.107403)
					(end 215.020398 -200.122282)
				)
				(arc
					(start 216.419938 -200.122282)
					(mid 216.455859 -200.107403)
					(end 216.470738 -200.071482)
				)
				(arc
					(start 216.470738 -199.662542)
					(mid 216.455859 -199.626621)
					(end 216.419938 -199.611742)
				)
				(arc
					(start 215.020398 -199.611742)
					(mid 214.984477 -199.626621)
					(end 214.969598 -199.662542)
				)
			)
		)
	)
	(zone
		(layers "In1.Cu" "In2.Cu")
		(hatch none 0.5)
		(connect_pads
			(clearance 0)
		)
		(min_thickness 0.25)
		(keepout
			(tracks not_allowed)
			(vias allowed)
			(pads allowed)
			(copperpour not_allowed)
			(footprints allowed)
		)
		(placement
			(enabled no)
			(sheetname "")
		)
		(fill yes
			(thermal_gap 0.5)
			(thermal_bridge_width 0.5)
			(island_removal_mode 0)
		)
		(polygon
			(pts
				(arc
					(start 207.425798 -217.921332)
					(mid 207.440677 -217.957253)
					(end 207.476598 -217.972132)
				)
				(arc
					(start 208.876138 -217.972132)
					(mid 208.912059 -217.957253)
					(end 208.926938 -217.921332)
				)
				(arc
					(start 208.926938 -217.512392)
					(mid 208.912059 -217.476471)
					(end 208.876138 -217.461592)
				)
				(arc
					(start 207.476598 -217.461592)
					(mid 207.440677 -217.476471)
					(end 207.425798 -217.512392)
				)
			)
		)
	)
	(zone
		(layers "In1.Cu" "In2.Cu")
		(hatch none 0.5)
		(connect_pads
			(clearance 0)
		)
		(min_thickness 0.25)
		(keepout
			(tracks not_allowed)
			(vias allowed)
			(pads allowed)
			(copperpour not_allowed)
			(footprints allowed)
		)
		(placement
			(enabled no)
			(sheetname "")
		)
		(fill yes
			(thermal_gap 0.5)
			(thermal_bridge_width 0.5)
			(island_removal_mode 0)
		)
		(polygon
			(pts
				(arc
					(start 277.961598 -219.621354)
					(mid 277.976477 -219.657275)
					(end 278.012398 -219.672154)
				)
				(arc
					(start 279.411938 -219.672154)
					(mid 279.447859 -219.657275)
					(end 279.462738 -219.621354)
				)
				(arc
					(start 279.462738 -219.212414)
					(mid 279.447859 -219.176493)
					(end 279.411938 -219.161614)
				)
				(arc
					(start 278.012398 -219.161614)
					(mid 277.976477 -219.176493)
					(end 277.961598 -219.212414)
				)
			)
		)
	)
	(zone
		(layers "In1.Cu" "In2.Cu")
		(hatch none 0.5)
		(connect_pads
			(clearance 0)
		)
		(min_thickness 0.25)
		(keepout
			(tracks not_allowed)
			(vias allowed)
			(pads allowed)
			(copperpour not_allowed)
			(footprints allowed)
		)
		(placement
			(enabled no)
			(sheetname "")
		)
		(fill yes
			(thermal_gap 0.5)
			(thermal_bridge_width 0.5)
			(island_removal_mode 0)
		)
		(polygon
			(pts
				(arc
					(start 37.56533 -314.821316)
					(mid 37.580209 -314.857237)
					(end 37.61613 -314.872116)
				)
				(arc
					(start 39.01567 -314.872116)
					(mid 39.051591 -314.857237)
					(end 39.06647 -314.821316)
				)
				(arc
					(start 39.06647 -314.412376)
					(mid 39.051591 -314.376455)
					(end 39.01567 -314.361576)
				)
				(arc
					(start 37.61613 -314.361576)
					(mid 37.580209 -314.376455)
					(end 37.56533 -314.412376)
				)
			)
		)
	)
	(zone
		(layers "In1.Cu" "In2.Cu")
		(hatch none 0.5)
		(connect_pads
			(clearance 0)
		)
		(min_thickness 0.25)
		(keepout
			(tracks not_allowed)
			(vias allowed)
			(pads allowed)
			(copperpour not_allowed)
			(footprints allowed)
		)
		(placement
			(enabled no)
			(sheetname "")
		)
		(fill yes
			(thermal_gap 0.5)
			(thermal_bridge_width 0.5)
			(island_removal_mode 0)
		)
		(polygon
			(pts
				(arc
					(start 300.592998 -241.721386)
					(mid 300.607877 -241.757307)
					(end 300.643798 -241.772186)
				)
				(arc
					(start 302.043338 -241.772186)
					(mid 302.079259 -241.757307)
					(end 302.094138 -241.721386)
				)
				(arc
					(start 302.094138 -241.312446)
					(mid 302.079259 -241.276525)
					(end 302.043338 -241.261646)
				)
				(arc
					(start 300.643798 -241.261646)
					(mid 300.607877 -241.276525)
					(end 300.592998 -241.312446)
				)
			)
		)
	)
	(zone
		(layers "In1.Cu" "In2.Cu")
		(hatch none 0.5)
		(connect_pads
			(clearance 0)
		)
		(min_thickness 0.25)
		(keepout
			(tracks not_allowed)
			(vias allowed)
			(pads allowed)
			(copperpour not_allowed)
			(footprints allowed)
		)
		(placement
			(enabled no)
			(sheetname "")
		)
		(fill yes
			(thermal_gap 0.5)
			(thermal_bridge_width 0.5)
			(island_removal_mode 0)
		)
		(polygon
			(pts
				(arc
					(start 274.517866 -222.171514)
					(mid 274.532745 -222.207435)
					(end 274.568666 -222.222314)
				)
				(arc
					(start 275.968206 -222.222314)
					(mid 276.004127 -222.207435)
					(end 276.019006 -222.171514)
				)
				(arc
					(start 276.019006 -221.762574)
					(mid 276.004127 -221.726653)
					(end 275.968206 -221.711774)
				)
				(arc
					(start 274.568666 -221.711774)
					(mid 274.532745 -221.726653)
					(end 274.517866 -221.762574)
				)
			)
		)
	)
	(zone
		(layers "In1.Cu" "In2.Cu")
		(hatch none 0.5)
		(connect_pads
			(clearance 0)
		)
		(min_thickness 0.25)
		(keepout
			(tracks not_allowed)
			(vias allowed)
			(pads allowed)
			(copperpour not_allowed)
			(footprints allowed)
		)
		(placement
			(enabled no)
			(sheetname "")
		)
		(fill yes
			(thermal_gap 0.5)
			(thermal_bridge_width 0.5)
			(island_removal_mode 0)
		)
		(polygon
			(pts
				(arc
					(start 184.794398 -222.171514)
					(mid 184.809277 -222.207435)
					(end 184.845198 -222.222314)
				)
				(arc
					(start 186.244738 -222.222314)
					(mid 186.280659 -222.207435)
					(end 186.295538 -222.171514)
				)
				(arc
					(start 186.295538 -221.762574)
					(mid 186.280659 -221.726653)
					(end 186.244738 -221.711774)
				)
				(arc
					(start 184.845198 -221.711774)
					(mid 184.809277 -221.726653)
					(end 184.794398 -221.762574)
				)
			)
		)
	)
	(zone
		(layers "In1.Cu" "In2.Cu")
		(hatch none 0.5)
		(connect_pads
			(clearance 0)
		)
		(min_thickness 0.25)
		(keepout
			(tracks not_allowed)
			(vias allowed)
			(pads allowed)
			(copperpour not_allowed)
			(footprints allowed)
		)
		(placement
			(enabled no)
			(sheetname "")
		)
		(fill yes
			(thermal_gap 0.5)
			(thermal_bridge_width 0.5)
			(island_removal_mode 0)
		)
		(polygon
			(pts
				(arc
					(start 7.39013 -209.421476)
					(mid 7.405009 -209.457397)
					(end 7.44093 -209.472276)
				)
				(arc
					(start 8.84047 -209.472276)
					(mid 8.876391 -209.457397)
					(end 8.89127 -209.421476)
				)
				(arc
					(start 8.89127 -209.012536)
					(mid 8.876391 -208.976615)
					(end 8.84047 -208.961736)
				)
				(arc
					(start 7.44093 -208.961736)
					(mid 7.405009 -208.976615)
					(end 7.39013 -209.012536)
				)
			)
		)
	)
	(zone
		(layers "In1.Cu" "In2.Cu")
		(hatch none 0.5)
		(connect_pads
			(clearance 0)
		)
		(min_thickness 0.25)
		(keepout
			(tracks not_allowed)
			(vias allowed)
			(pads allowed)
			(copperpour not_allowed)
			(footprints allowed)
		)
		(placement
			(enabled no)
			(sheetname "")
		)
		(fill yes
			(thermal_gap 0.5)
			(thermal_bridge_width 0.5)
			(island_removal_mode 0)
		)
		(polygon
			(pts
				(arc
					(start 195.78193 -228.121464)
					(mid 195.796809 -228.157385)
					(end 195.83273 -228.172264)
				)
				(arc
					(start 197.23227 -228.172264)
					(mid 197.268191 -228.157385)
					(end 197.28307 -228.121464)
				)
				(arc
					(start 197.28307 -227.712524)
					(mid 197.268191 -227.676603)
					(end 197.23227 -227.661724)
				)
				(arc
					(start 195.83273 -227.661724)
					(mid 195.796809 -227.676603)
					(end 195.78193 -227.712524)
				)
			)
		)
	)
	(zone
		(layers "In1.Cu" "In2.Cu")
		(hatch none 0.5)
		(connect_pads
			(clearance 0)
		)
		(min_thickness 0.25)
		(keepout
			(tracks not_allowed)
			(vias allowed)
			(pads allowed)
			(copperpour not_allowed)
			(footprints allowed)
		)
		(placement
			(enabled no)
			(sheetname "")
		)
		(fill yes
			(thermal_gap 0.5)
			(thermal_bridge_width 0.5)
			(island_removal_mode 0)
		)
		(polygon
			(pts
				(arc
					(start 440.278266 -268.921484)
					(mid 440.293145 -268.957405)
					(end 440.329066 -268.972284)
				)
				(arc
					(start 441.728606 -268.972284)
					(mid 441.764527 -268.957405)
					(end 441.779406 -268.921484)
				)
				(arc
					(start 441.779406 -268.512544)
					(mid 441.764527 -268.476623)
					(end 441.728606 -268.461744)
				)
				(arc
					(start 440.329066 -268.461744)
					(mid 440.293145 -268.476623)
					(end 440.278266 -268.512544)
				)
			)
		)
	)
	(zone
		(layers "In1.Cu" "In2.Cu")
		(hatch none 0.5)
		(connect_pads
			(clearance 0)
		)
		(min_thickness 0.25)
		(keepout
			(tracks not_allowed)
			(vias allowed)
			(pads allowed)
			(copperpour not_allowed)
			(footprints allowed)
		)
		(placement
			(enabled no)
			(sheetname "")
		)
		(fill yes
			(thermal_gap 0.5)
			(thermal_bridge_width 0.5)
			(island_removal_mode 0)
		)
		(polygon
			(pts
				(arc
					(start 297.149266 -222.171514)
					(mid 297.164145 -222.207435)
					(end 297.200066 -222.222314)
				)
				(arc
					(start 298.599606 -222.222314)
					(mid 298.635527 -222.207435)
					(end 298.650406 -222.171514)
				)
				(arc
					(start 298.650406 -221.762574)
					(mid 298.635527 -221.726653)
					(end 298.599606 -221.711774)
				)
				(arc
					(start 297.200066 -221.711774)
					(mid 297.164145 -221.726653)
					(end 297.149266 -221.762574)
				)
			)
		)
	)
	(zone
		(layers "In1.Cu" "In2.Cu")
		(hatch none 0.5)
		(connect_pads
			(clearance 0)
		)
		(min_thickness 0.25)
		(keepout
			(tracks not_allowed)
			(vias allowed)
			(pads allowed)
			(copperpour not_allowed)
			(footprints allowed)
		)
		(placement
			(enabled no)
			(sheetname "")
		)
		(fill yes
			(thermal_gap 0.5)
			(thermal_bridge_width 0.5)
			(island_removal_mode 0)
		)
		(polygon
			(pts
				(arc
					(start 443.721998 -268.071346)
					(mid 443.736877 -268.107267)
					(end 443.772798 -268.122146)
				)
				(arc
					(start 445.172338 -268.122146)
					(mid 445.208259 -268.107267)
					(end 445.223138 -268.071346)
				)
				(arc
					(start 445.223138 -267.662406)
					(mid 445.208259 -267.626485)
					(end 445.172338 -267.611606)
				)
				(arc
					(start 443.772798 -267.611606)
					(mid 443.736877 -267.626485)
					(end 443.721998 -267.662406)
				)
			)
		)
	)
	(zone
		(layers "In1.Cu" "In2.Cu")
		(hatch none 0.5)
		(connect_pads
			(clearance 0)
		)
		(min_thickness 0.25)
		(keepout
			(tracks not_allowed)
			(vias allowed)
			(pads allowed)
			(copperpour not_allowed)
			(footprints allowed)
		)
		(placement
			(enabled no)
			(sheetname "")
		)
		(fill yes
			(thermal_gap 0.5)
			(thermal_bridge_width 0.5)
			(island_removal_mode 0)
		)
		(polygon
			(pts
				(arc
					(start 425.190666 -199.221344)
					(mid 425.205545 -199.257265)
					(end 425.241466 -199.272144)
				)
				(arc
					(start 426.641006 -199.272144)
					(mid 426.676927 -199.257265)
					(end 426.691806 -199.221344)
				)
				(arc
					(start 426.691806 -198.812404)
					(mid 426.676927 -198.776483)
					(end 426.641006 -198.761604)
				)
				(arc
					(start 425.241466 -198.761604)
					(mid 425.205545 -198.776483)
					(end 425.190666 -198.812404)
				)
			)
		)
	)
	(zone
		(layers "In1.Cu" "In2.Cu")
		(hatch none 0.5)
		(connect_pads
			(clearance 0)
		)
		(min_thickness 0.25)
		(keepout
			(tracks not_allowed)
			(vias allowed)
			(pads allowed)
			(copperpour not_allowed)
			(footprints allowed)
		)
		(placement
			(enabled no)
			(sheetname "")
		)
		(fill yes
			(thermal_gap 0.5)
			(thermal_bridge_width 0.5)
			(island_removal_mode 0)
		)
		(polygon
			(pts
				(arc
					(start 203.32573 -314.821316)
					(mid 203.340609 -314.857237)
					(end 203.37653 -314.872116)
				)
				(arc
					(start 204.77607 -314.872116)
					(mid 204.811991 -314.857237)
					(end 204.82687 -314.821316)
				)
				(arc
					(start 204.82687 -314.412376)
					(mid 204.811991 -314.376455)
					(end 204.77607 -314.361576)
				)
				(arc
					(start 203.37653 -314.361576)
					(mid 203.340609 -314.376455)
					(end 203.32573 -314.412376)
				)
			)
		)
	)
	(zone
		(layers "In1.Cu" "In2.Cu")
		(hatch none 0.5)
		(connect_pads
			(clearance 0)
		)
		(min_thickness 0.25)
		(keepout
			(tracks not_allowed)
			(vias allowed)
			(pads allowed)
			(copperpour not_allowed)
			(footprints allowed)
		)
		(placement
			(enabled no)
			(sheetname "")
		)
		(fill yes
			(thermal_gap 0.5)
			(thermal_bridge_width 0.5)
			(island_removal_mode 0)
		)
		(polygon
			(pts
				(arc
					(start 184.794398 -278.271478)
					(mid 184.809277 -278.307399)
					(end 184.845198 -278.322278)
				)
				(arc
					(start 186.244738 -278.322278)
					(mid 186.280659 -278.307399)
					(end 186.295538 -278.271478)
				)
				(arc
					(start 186.295538 -277.862538)
					(mid 186.280659 -277.826617)
					(end 186.244738 -277.811738)
				)
				(arc
					(start 184.845198 -277.811738)
					(mid 184.809277 -277.826617)
					(end 184.794398 -277.862538)
				)
			)
		)
	)
	(zone
		(layers "In1.Cu" "In2.Cu")
		(hatch none 0.5)
		(connect_pads
			(clearance 0)
		)
		(min_thickness 0.25)
		(keepout
			(tracks not_allowed)
			(vias allowed)
			(pads allowed)
			(copperpour not_allowed)
			(footprints allowed)
		)
		(placement
			(enabled no)
			(sheetname "")
		)
		(fill yes
			(thermal_gap 0.5)
			(thermal_bridge_width 0.5)
			(island_removal_mode 0)
		)
		(polygon
			(pts
				(arc
					(start 192.338198 -206.871316)
					(mid 192.353077 -206.907237)
					(end 192.388998 -206.922116)
				)
				(arc
					(start 193.788538 -206.922116)
					(mid 193.824459 -206.907237)
					(end 193.839338 -206.871316)
				)
				(arc
					(start 193.839338 -206.462376)
					(mid 193.824459 -206.426455)
					(end 193.788538 -206.411576)
				)
				(arc
					(start 192.388998 -206.411576)
					(mid 192.353077 -206.426455)
					(end 192.338198 -206.462376)
				)
			)
		)
	)
	(zone
		(layers "In1.Cu" "In2.Cu")
		(hatch none 0.5)
		(connect_pads
			(clearance 0)
		)
		(min_thickness 0.25)
		(keepout
			(tracks not_allowed)
			(vias allowed)
			(pads allowed)
			(copperpour not_allowed)
			(footprints allowed)
		)
		(placement
			(enabled no)
			(sheetname "")
		)
		(fill yes
			(thermal_gap 0.5)
			(thermal_bridge_width 0.5)
			(island_removal_mode 0)
		)
		(polygon
			(pts
				(arc
					(start 11.490198 -222.171514)
					(mid 11.505077 -222.207435)
					(end 11.540998 -222.222314)
				)
				(arc
					(start 12.940538 -222.222314)
					(mid 12.976459 -222.207435)
					(end 12.991338 -222.171514)
				)
				(arc
					(start 12.991338 -221.762574)
					(mid 12.976459 -221.726653)
					(end 12.940538 -221.711774)
				)
				(arc
					(start 11.540998 -221.711774)
					(mid 11.505077 -221.726653)
					(end 11.490198 -221.762574)
				)
			)
		)
	)
	(zone
		(layers "In1.Cu" "In2.Cu")
		(hatch none 0.5)
		(connect_pads
			(clearance 0)
		)
		(min_thickness 0.25)
		(keepout
			(tracks not_allowed)
			(vias allowed)
			(pads allowed)
			(copperpour not_allowed)
			(footprints allowed)
		)
		(placement
			(enabled no)
			(sheetname "")
		)
		(fill yes
			(thermal_gap 0.5)
			(thermal_bridge_width 0.5)
			(island_removal_mode 0)
		)
		(polygon
			(pts
				(arc
					(start 425.190666 -231.521508)
					(mid 425.205545 -231.557429)
					(end 425.241466 -231.572308)
				)
				(arc
					(start 426.641006 -231.572308)
					(mid 426.676927 -231.557429)
					(end 426.691806 -231.521508)
				)
				(arc
					(start 426.691806 -231.112568)
					(mid 426.676927 -231.076647)
					(end 426.641006 -231.061768)
				)
				(arc
					(start 425.241466 -231.061768)
					(mid 425.205545 -231.076647)
					(end 425.190666 -231.112568)
				)
			)
		)
	)
	(zone
		(layers "In1.Cu" "In2.Cu")
		(hatch none 0.5)
		(connect_pads
			(clearance 0)
		)
		(min_thickness 0.25)
		(keepout
			(tracks not_allowed)
			(vias allowed)
			(pads allowed)
			(copperpour not_allowed)
			(footprints allowed)
		)
		(placement
			(enabled no)
			(sheetname "")
		)
		(fill yes
			(thermal_gap 0.5)
			(thermal_bridge_width 0.5)
			(island_removal_mode 0)
		)
		(polygon
			(pts
				(arc
					(start 26.577798 -205.171548)
					(mid 26.592677 -205.207469)
					(end 26.628598 -205.222348)
				)
				(arc
					(start 28.028138 -205.222348)
					(mid 28.064059 -205.207469)
					(end 28.078938 -205.171548)
				)
				(arc
					(start 28.078938 -204.762608)
					(mid 28.064059 -204.726687)
					(end 28.028138 -204.711808)
				)
				(arc
					(start 26.628598 -204.711808)
					(mid 26.592677 -204.726687)
					(end 26.577798 -204.762608)
				)
			)
		)
	)
	(zone
		(layers "In1.Cu" "In2.Cu")
		(hatch none 0.5)
		(connect_pads
			(clearance 0)
		)
		(min_thickness 0.25)
		(keepout
			(tracks not_allowed)
			(vias allowed)
			(pads allowed)
			(copperpour not_allowed)
			(footprints allowed)
		)
		(placement
			(enabled no)
			(sheetname "")
		)
		(fill yes
			(thermal_gap 0.5)
			(thermal_bridge_width 0.5)
			(island_removal_mode 0)
		)
		(polygon
			(pts
				(arc
					(start 428.634398 -268.071346)
					(mid 428.649277 -268.107267)
					(end 428.685198 -268.122146)
				)
				(arc
					(start 430.084738 -268.122146)
					(mid 430.120659 -268.107267)
					(end 430.135538 -268.071346)
				)
				(arc
					(start 430.135538 -267.662406)
					(mid 430.120659 -267.626485)
					(end 430.084738 -267.611606)
				)
				(arc
					(start 428.685198 -267.611606)
					(mid 428.649277 -267.626485)
					(end 428.634398 -267.662406)
				)
			)
		)
	)
	(zone
		(layers "In1.Cu" "In2.Cu")
		(hatch none 0.5)
		(connect_pads
			(clearance 0)
		)
		(min_thickness 0.25)
		(keepout
			(tracks not_allowed)
			(vias allowed)
			(pads allowed)
			(copperpour not_allowed)
			(footprints allowed)
		)
		(placement
			(enabled no)
			(sheetname "")
		)
		(fill yes
			(thermal_gap 0.5)
			(thermal_bridge_width 0.5)
			(island_removal_mode 0)
		)
		(polygon
			(pts
				(arc
					(start 447.822066 -274.02155)
					(mid 447.836945 -274.057471)
					(end 447.872866 -274.07235)
				)
				(arc
					(start 449.272406 -274.07235)
					(mid 449.308327 -274.057471)
					(end 449.323206 -274.02155)
				)
				(arc
					(start 449.323206 -273.61261)
					(mid 449.308327 -273.576689)
					(end 449.272406 -273.56181)
				)
				(arc
					(start 447.872866 -273.56181)
					(mid 447.836945 -273.576689)
					(end 447.822066 -273.61261)
				)
			)
		)
	)
	(zone
		(layers "In1.Cu" "In2.Cu")
		(hatch none 0.5)
		(connect_pads
			(clearance 0)
		)
		(min_thickness 0.25)
		(keepout
			(tracks not_allowed)
			(vias allowed)
			(pads allowed)
			(copperpour not_allowed)
			(footprints allowed)
		)
		(placement
			(enabled no)
			(sheetname "")
		)
		(fill yes
			(thermal_gap 0.5)
			(thermal_bridge_width 0.5)
			(island_removal_mode 0)
		)
		(polygon
			(pts
				(arc
					(start 285.505398 -314.821316)
					(mid 285.520277 -314.857237)
					(end 285.556198 -314.872116)
				)
				(arc
					(start 286.955738 -314.872116)
					(mid 286.991659 -314.857237)
					(end 287.006538 -314.821316)
				)
				(arc
					(start 287.006538 -314.412376)
					(mid 286.991659 -314.376455)
					(end 286.955738 -314.361576)
				)
				(arc
					(start 285.556198 -314.361576)
					(mid 285.520277 -314.376455)
					(end 285.505398 -314.412376)
				)
			)
		)
	)
	(zone
		(layers "In1.Cu" "In2.Cu")
		(hatch none 0.5)
		(connect_pads
			(clearance 0)
		)
		(min_thickness 0.25)
		(keepout
			(tracks not_allowed)
			(vias allowed)
			(pads allowed)
			(copperpour not_allowed)
			(footprints allowed)
		)
		(placement
			(enabled no)
			(sheetname "")
		)
		(fill yes
			(thermal_gap 0.5)
			(thermal_bridge_width 0.5)
			(island_removal_mode 0)
		)
		(polygon
			(pts
				(arc
					(start 192.338198 -260.421374)
					(mid 192.353077 -260.457295)
					(end 192.388998 -260.472174)
				)
				(arc
					(start 193.788538 -260.472174)
					(mid 193.824459 -260.457295)
					(end 193.839338 -260.421374)
				)
				(arc
					(start 193.839338 -260.012434)
					(mid 193.824459 -259.976513)
					(end 193.788538 -259.961634)
				)
				(arc
					(start 192.388998 -259.961634)
					(mid 192.353077 -259.976513)
					(end 192.338198 -260.012434)
				)
			)
		)
	)
	(zone
		(layers "In1.Cu" "In2.Cu")
		(hatch none 0.5)
		(connect_pads
			(clearance 0)
		)
		(min_thickness 0.25)
		(keepout
			(tracks not_allowed)
			(vias allowed)
			(pads allowed)
			(copperpour not_allowed)
			(footprints allowed)
		)
		(placement
			(enabled no)
			(sheetname "")
		)
		(fill yes
			(thermal_gap 0.5)
			(thermal_bridge_width 0.5)
			(island_removal_mode 0)
		)
		(polygon
			(pts
				(arc
					(start 49.209198 -304.621438)
					(mid 49.224077 -304.657359)
					(end 49.259998 -304.672238)
				)
				(arc
					(start 50.659538 -304.672238)
					(mid 50.695459 -304.657359)
					(end 50.710338 -304.621438)
				)
				(arc
					(start 50.710338 -304.212498)
					(mid 50.695459 -304.176577)
					(end 50.659538 -304.161698)
				)
				(arc
					(start 49.259998 -304.161698)
					(mid 49.224077 -304.176577)
					(end 49.209198 -304.212498)
				)
			)
		)
	)
	(zone
		(layers "In1.Cu" "In2.Cu")
		(hatch none 0.5)
		(connect_pads
			(clearance 0)
		)
		(min_thickness 0.25)
		(keepout
			(tracks not_allowed)
			(vias allowed)
			(pads allowed)
			(copperpour not_allowed)
			(footprints allowed)
		)
		(placement
			(enabled no)
			(sheetname "")
		)
		(fill yes
			(thermal_gap 0.5)
			(thermal_bridge_width 0.5)
			(island_removal_mode 0)
		)
		(polygon
			(pts
				(arc
					(start 184.794398 -216.22131)
					(mid 184.809277 -216.257231)
					(end 184.845198 -216.27211)
				)
				(arc
					(start 186.244738 -216.27211)
					(mid 186.280659 -216.257231)
					(end 186.295538 -216.22131)
				)
				(arc
					(start 186.295538 -215.81237)
					(mid 186.280659 -215.776449)
					(end 186.244738 -215.76157)
				)
				(arc
					(start 184.845198 -215.76157)
					(mid 184.809277 -215.776449)
					(end 184.794398 -215.81237)
				)
			)
		)
	)
	(zone
		(layers "In1.Cu" "In2.Cu")
		(hatch none 0.5)
		(connect_pads
			(clearance 0)
		)
		(min_thickness 0.25)
		(keepout
			(tracks not_allowed)
			(vias allowed)
			(pads allowed)
			(copperpour not_allowed)
			(footprints allowed)
		)
		(placement
			(enabled no)
			(sheetname "")
		)
		(fill yes
			(thermal_gap 0.5)
			(thermal_bridge_width 0.5)
			(island_removal_mode 0)
		)
		(polygon
			(pts
				(arc
					(start 214.969598 -308.021482)
					(mid 214.984477 -308.057403)
					(end 215.020398 -308.072282)
				)
				(arc
					(start 216.419938 -308.072282)
					(mid 216.455859 -308.057403)
					(end 216.470738 -308.021482)
				)
				(arc
					(start 216.470738 -307.612542)
					(mid 216.455859 -307.576621)
					(end 216.419938 -307.561742)
				)
				(arc
					(start 215.020398 -307.561742)
					(mid 214.984477 -307.576621)
					(end 214.969598 -307.612542)
				)
			)
		)
	)
	(zone
		(layers "In1.Cu" "In2.Cu")
		(hatch none 0.5)
		(connect_pads
			(clearance 0)
		)
		(min_thickness 0.25)
		(keepout
			(tracks not_allowed)
			(vias allowed)
			(pads allowed)
			(copperpour not_allowed)
			(footprints allowed)
		)
		(placement
			(enabled no)
			(sheetname "")
		)
		(fill yes
			(thermal_gap 0.5)
			(thermal_bridge_width 0.5)
			(island_removal_mode 0)
		)
		(polygon
			(pts
				(arc
					(start 289.605466 -295.271444)
					(mid 289.620345 -295.307365)
					(end 289.656266 -295.322244)
				)
				(arc
					(start 291.055806 -295.322244)
					(mid 291.091727 -295.307365)
					(end 291.106606 -295.271444)
				)
				(arc
					(start 291.106606 -294.862504)
					(mid 291.091727 -294.826583)
					(end 291.055806 -294.811704)
				)
				(arc
					(start 289.656266 -294.811704)
					(mid 289.620345 -294.826583)
					(end 289.605466 -294.862504)
				)
			)
		)
	)
	(zone
		(layers "In1.Cu" "In2.Cu")
		(hatch none 0.5)
		(connect_pads
			(clearance 0)
		)
		(min_thickness 0.25)
		(keepout
			(tracks not_allowed)
			(vias allowed)
			(pads allowed)
			(copperpour not_allowed)
			(footprints allowed)
		)
		(placement
			(enabled no)
			(sheetname "")
		)
		(fill yes
			(thermal_gap 0.5)
			(thermal_bridge_width 0.5)
			(island_removal_mode 0)
		)
		(polygon
			(pts
				(arc
					(start 56.752998 -240.871502)
					(mid 56.767877 -240.907423)
					(end 56.803798 -240.922302)
				)
				(arc
					(start 58.203338 -240.922302)
					(mid 58.239259 -240.907423)
					(end 58.254138 -240.871502)
				)
				(arc
					(start 58.254138 -240.462562)
					(mid 58.239259 -240.426641)
					(end 58.203338 -240.411762)
				)
				(arc
					(start 56.803798 -240.411762)
					(mid 56.767877 -240.426641)
					(end 56.752998 -240.462562)
				)
			)
		)
	)
	(zone
		(layers "In1.Cu" "In2.Cu")
		(hatch none 0.5)
		(connect_pads
			(clearance 0)
		)
		(min_thickness 0.25)
		(keepout
			(tracks not_allowed)
			(vias allowed)
			(pads allowed)
			(copperpour not_allowed)
			(footprints allowed)
		)
		(placement
			(enabled no)
			(sheetname "")
		)
		(fill yes
			(thermal_gap 0.5)
			(thermal_bridge_width 0.5)
			(island_removal_mode 0)
		)
		(polygon
			(pts
				(arc
					(start 169.706798 -315.671454)
					(mid 169.721677 -315.707375)
					(end 169.757598 -315.722254)
				)
				(arc
					(start 171.157138 -315.722254)
					(mid 171.193059 -315.707375)
					(end 171.207938 -315.671454)
				)
				(arc
					(start 171.207938 -315.262514)
					(mid 171.193059 -315.226593)
					(end 171.157138 -315.211714)
				)
				(arc
					(start 169.757598 -315.211714)
					(mid 169.721677 -315.226593)
					(end 169.706798 -315.262514)
				)
			)
		)
	)
	(zone
		(layers "In1.Cu" "In2.Cu")
		(hatch none 0.5)
		(connect_pads
			(clearance 0)
		)
		(min_thickness 0.25)
		(keepout
			(tracks not_allowed)
			(vias allowed)
			(pads allowed)
			(copperpour not_allowed)
			(footprints allowed)
		)
		(placement
			(enabled no)
			(sheetname "")
		)
		(fill yes
			(thermal_gap 0.5)
			(thermal_bridge_width 0.5)
			(island_removal_mode 0)
		)
		(polygon
			(pts
				(arc
					(start 199.881998 -285.92145)
					(mid 199.896877 -285.957371)
					(end 199.932798 -285.97225)
				)
				(arc
					(start 201.332338 -285.97225)
					(mid 201.368259 -285.957371)
					(end 201.383138 -285.92145)
				)
				(arc
					(start 201.383138 -285.51251)
					(mid 201.368259 -285.476589)
					(end 201.332338 -285.46171)
				)
				(arc
					(start 199.932798 -285.46171)
					(mid 199.896877 -285.476589)
					(end 199.881998 -285.51251)
				)
			)
		)
	)
	(zone
		(layers "In1.Cu" "In2.Cu")
		(hatch none 0.5)
		(connect_pads
			(clearance 0)
		)
		(min_thickness 0.25)
		(keepout
			(tracks not_allowed)
			(vias allowed)
			(pads allowed)
			(copperpour not_allowed)
			(footprints allowed)
		)
		(placement
			(enabled no)
			(sheetname "")
		)
		(fill yes
			(thermal_gap 0.5)
			(thermal_bridge_width 0.5)
			(island_removal_mode 0)
		)
		(polygon
			(pts
				(arc
					(start 45.10913 -196.671438)
					(mid 45.124009 -196.707359)
					(end 45.15993 -196.722238)
				)
				(arc
					(start 46.55947 -196.722238)
					(mid 46.595391 -196.707359)
					(end 46.61027 -196.671438)
				)
				(arc
					(start 46.61027 -196.262498)
					(mid 46.595391 -196.226577)
					(end 46.55947 -196.211698)
				)
				(arc
					(start 45.15993 -196.211698)
					(mid 45.124009 -196.226577)
					(end 45.10913 -196.262498)
				)
			)
		)
	)
	(zone
		(layers "In1.Cu" "In2.Cu")
		(hatch none 0.5)
		(connect_pads
			(clearance 0)
		)
		(min_thickness 0.25)
		(keepout
			(tracks not_allowed)
			(vias allowed)
			(pads allowed)
			(copperpour not_allowed)
			(footprints allowed)
		)
		(placement
			(enabled no)
			(sheetname "")
		)
		(fill yes
			(thermal_gap 0.5)
			(thermal_bridge_width 0.5)
			(island_removal_mode 0)
		)
		(polygon
			(pts
				(arc
					(start 282.061666 -216.22131)
					(mid 282.076545 -216.257231)
					(end 282.112466 -216.27211)
				)
				(arc
					(start 283.512006 -216.27211)
					(mid 283.547927 -216.257231)
					(end 283.562806 -216.22131)
				)
				(arc
					(start 283.562806 -215.81237)
					(mid 283.547927 -215.776449)
					(end 283.512006 -215.76157)
				)
				(arc
					(start 282.112466 -215.76157)
					(mid 282.076545 -215.776449)
					(end 282.061666 -215.81237)
				)
			)
		)
	)
	(zone
		(layers "In1.Cu" "In2.Cu")
		(hatch none 0.5)
		(connect_pads
			(clearance 0)
		)
		(min_thickness 0.25)
		(keepout
			(tracks not_allowed)
			(vias allowed)
			(pads allowed)
			(copperpour not_allowed)
			(footprints allowed)
		)
		(placement
			(enabled no)
			(sheetname "")
		)
		(fill yes
			(thermal_gap 0.5)
			(thermal_bridge_width 0.5)
			(island_removal_mode 0)
		)
		(polygon
			(pts
				(arc
					(start 203.32573 -291.8714)
					(mid 203.340609 -291.907321)
					(end 203.37653 -291.9222)
				)
				(arc
					(start 204.77607 -291.9222)
					(mid 204.811991 -291.907321)
					(end 204.82687 -291.8714)
				)
				(arc
					(start 204.82687 -291.46246)
					(mid 204.811991 -291.426539)
					(end 204.77607 -291.41166)
				)
				(arc
					(start 203.37653 -291.41166)
					(mid 203.340609 -291.426539)
					(end 203.32573 -291.46246)
				)
			)
		)
	)
	(zone
		(layers "In1.Cu" "In2.Cu")
		(hatch none 0.5)
		(connect_pads
			(clearance 0)
		)
		(min_thickness 0.25)
		(keepout
			(tracks not_allowed)
			(vias allowed)
			(pads allowed)
			(copperpour not_allowed)
			(footprints allowed)
		)
		(placement
			(enabled no)
			(sheetname "")
		)
		(fill yes
			(thermal_gap 0.5)
			(thermal_bridge_width 0.5)
			(island_removal_mode 0)
		)
		(polygon
			(pts
				(arc
					(start 312.236866 -237.471458)
					(mid 312.251745 -237.507379)
					(end 312.287666 -237.522258)
				)
				(arc
					(start 313.687206 -237.522258)
					(mid 313.723127 -237.507379)
					(end 313.738006 -237.471458)
				)
				(arc
					(start 313.738006 -237.062518)
					(mid 313.723127 -237.026597)
					(end 313.687206 -237.011718)
				)
				(arc
					(start 312.287666 -237.011718)
					(mid 312.251745 -237.026597)
					(end 312.236866 -237.062518)
				)
			)
		)
	)
	(zone
		(layers "In1.Cu" "In2.Cu")
		(hatch none 0.5)
		(connect_pads
			(clearance 0)
		)
		(min_thickness 0.25)
		(keepout
			(tracks not_allowed)
			(vias allowed)
			(pads allowed)
			(copperpour not_allowed)
			(footprints allowed)
		)
		(placement
			(enabled no)
			(sheetname "")
		)
		(fill yes
			(thermal_gap 0.5)
			(thermal_bridge_width 0.5)
			(island_removal_mode 0)
		)
		(polygon
			(pts
				(arc
					(start 30.02153 -252.771402)
					(mid 30.036409 -252.807323)
					(end 30.07233 -252.822202)
				)
				(arc
					(start 31.47187 -252.822202)
					(mid 31.507791 -252.807323)
					(end 31.52267 -252.771402)
				)
				(arc
					(start 31.52267 -252.362462)
					(mid 31.507791 -252.326541)
					(end 31.47187 -252.311662)
				)
				(arc
					(start 30.07233 -252.311662)
					(mid 30.036409 -252.326541)
					(end 30.02153 -252.362462)
				)
			)
		)
	)
	(zone
		(layers "In1.Cu" "In2.Cu")
		(hatch none 0.5)
		(connect_pads
			(clearance 0)
		)
		(min_thickness 0.25)
		(keepout
			(tracks not_allowed)
			(vias allowed)
			(pads allowed)
			(copperpour not_allowed)
			(footprints allowed)
		)
		(placement
			(enabled no)
			(sheetname "")
		)
		(fill yes
			(thermal_gap 0.5)
			(thermal_bridge_width 0.5)
			(island_removal_mode 0)
		)
		(polygon
			(pts
				(arc
					(start 432.734466 -291.021516)
					(mid 432.749345 -291.057437)
					(end 432.785266 -291.072316)
				)
				(arc
					(start 434.184806 -291.072316)
					(mid 434.220727 -291.057437)
					(end 434.235606 -291.021516)
				)
				(arc
					(start 434.235606 -290.612576)
					(mid 434.220727 -290.576655)
					(end 434.184806 -290.561776)
				)
				(arc
					(start 432.785266 -290.561776)
					(mid 432.749345 -290.576655)
					(end 432.734466 -290.612576)
				)
			)
		)
	)
	(zone
		(layers "In1.Cu" "In2.Cu")
		(hatch none 0.5)
		(connect_pads
			(clearance 0)
		)
		(min_thickness 0.25)
		(keepout
			(tracks not_allowed)
			(vias allowed)
			(pads allowed)
			(copperpour not_allowed)
			(footprints allowed)
		)
		(placement
			(enabled no)
			(sheetname "")
		)
		(fill yes
			(thermal_gap 0.5)
			(thermal_bridge_width 0.5)
			(island_removal_mode 0)
		)
		(polygon
			(pts
				(arc
					(start 259.430266 -285.92145)
					(mid 259.445145 -285.957371)
					(end 259.481066 -285.97225)
				)
				(arc
					(start 260.880606 -285.97225)
					(mid 260.916527 -285.957371)
					(end 260.931406 -285.92145)
				)
				(arc
					(start 260.931406 -285.51251)
					(mid 260.916527 -285.476589)
					(end 260.880606 -285.46171)
				)
				(arc
					(start 259.481066 -285.46171)
					(mid 259.445145 -285.476589)
					(end 259.430266 -285.51251)
				)
			)
		)
	)
	(zone
		(layers "In1.Cu" "In2.Cu")
		(hatch none 0.5)
		(connect_pads
			(clearance 0)
		)
		(min_thickness 0.25)
		(keepout
			(tracks not_allowed)
			(vias allowed)
			(pads allowed)
			(copperpour not_allowed)
			(footprints allowed)
		)
		(placement
			(enabled no)
			(sheetname "")
		)
		(fill yes
			(thermal_gap 0.5)
			(thermal_bridge_width 0.5)
			(island_removal_mode 0)
		)
		(polygon
			(pts
				(arc
					(start 49.209198 -233.22153)
					(mid 49.224077 -233.257451)
					(end 49.259998 -233.27233)
				)
				(arc
					(start 50.659538 -233.27233)
					(mid 50.695459 -233.257451)
					(end 50.710338 -233.22153)
				)
				(arc
					(start 50.710338 -232.81259)
					(mid 50.695459 -232.776669)
					(end 50.659538 -232.76179)
				)
				(arc
					(start 49.259998 -232.76179)
					(mid 49.224077 -232.776669)
					(end 49.209198 -232.81259)
				)
			)
		)
	)
	(zone
		(layers "In1.Cu" "In2.Cu")
		(hatch none 0.5)
		(connect_pads
			(clearance 0)
		)
		(min_thickness 0.25)
		(keepout
			(tracks not_allowed)
			(vias allowed)
			(pads allowed)
			(copperpour not_allowed)
			(footprints allowed)
		)
		(placement
			(enabled no)
			(sheetname "")
		)
		(fill yes
			(thermal_gap 0.5)
			(thermal_bridge_width 0.5)
			(island_removal_mode 0)
		)
		(polygon
			(pts
				(arc
					(start 162.162998 -234.921298)
					(mid 162.177877 -234.957219)
					(end 162.213798 -234.972098)
				)
				(arc
					(start 163.613338 -234.972098)
					(mid 163.649259 -234.957219)
					(end 163.664138 -234.921298)
				)
				(arc
					(start 163.664138 -234.512358)
					(mid 163.649259 -234.476437)
					(end 163.613338 -234.461558)
				)
				(arc
					(start 162.213798 -234.461558)
					(mid 162.177877 -234.476437)
					(end 162.162998 -234.512358)
				)
			)
		)
	)
	(zone
		(layers "In1.Cu" "In2.Cu")
		(hatch none 0.5)
		(connect_pads
			(clearance 0)
		)
		(min_thickness 0.25)
		(keepout
			(tracks not_allowed)
			(vias allowed)
			(pads allowed)
			(copperpour not_allowed)
			(footprints allowed)
		)
		(placement
			(enabled no)
			(sheetname "")
		)
		(fill yes
			(thermal_gap 0.5)
			(thermal_bridge_width 0.5)
			(island_removal_mode 0)
		)
		(polygon
			(pts
				(arc
					(start 30.02153 -223.021398)
					(mid 30.036409 -223.057319)
					(end 30.07233 -223.072198)
				)
				(arc
					(start 31.47187 -223.072198)
					(mid 31.507791 -223.057319)
					(end 31.52267 -223.021398)
				)
				(arc
					(start 31.52267 -222.612458)
					(mid 31.507791 -222.576537)
					(end 31.47187 -222.561658)
				)
				(arc
					(start 30.07233 -222.561658)
					(mid 30.036409 -222.576537)
					(end 30.02153 -222.612458)
				)
			)
		)
	)
	(zone
		(layers "In1.Cu" "In2.Cu")
		(hatch none 0.5)
		(connect_pads
			(clearance 0)
		)
		(min_thickness 0.25)
		(keepout
			(tracks not_allowed)
			(vias allowed)
			(pads allowed)
			(copperpour not_allowed)
			(footprints allowed)
		)
		(placement
			(enabled no)
			(sheetname "")
		)
		(fill yes
			(thermal_gap 0.5)
			(thermal_bridge_width 0.5)
			(island_removal_mode 0)
		)
		(polygon
			(pts
				(arc
					(start 277.961598 -282.521406)
					(mid 277.976477 -282.557327)
					(end 278.012398 -282.572206)
				)
				(arc
					(start 279.411938 -282.572206)
					(mid 279.447859 -282.557327)
					(end 279.462738 -282.521406)
				)
				(arc
					(start 279.462738 -282.112466)
					(mid 279.447859 -282.076545)
					(end 279.411938 -282.061666)
				)
				(arc
					(start 278.012398 -282.061666)
					(mid 277.976477 -282.076545)
					(end 277.961598 -282.112466)
				)
			)
		)
	)
	(zone
		(layers "In1.Cu" "In2.Cu")
		(hatch none 0.5)
		(connect_pads
			(clearance 0)
		)
		(min_thickness 0.25)
		(keepout
			(tracks not_allowed)
			(vias allowed)
			(pads allowed)
			(copperpour not_allowed)
			(footprints allowed)
		)
		(placement
			(enabled no)
			(sheetname "")
		)
		(fill yes
			(thermal_gap 0.5)
			(thermal_bridge_width 0.5)
			(island_removal_mode 0)
		)
		(polygon
			(pts
				(arc
					(start 37.56533 -291.8714)
					(mid 37.580209 -291.907321)
					(end 37.61613 -291.9222)
				)
				(arc
					(start 39.01567 -291.9222)
					(mid 39.051591 -291.907321)
					(end 39.06647 -291.8714)
				)
				(arc
					(start 39.06647 -291.46246)
					(mid 39.051591 -291.426539)
					(end 39.01567 -291.41166)
				)
				(arc
					(start 37.61613 -291.41166)
					(mid 37.580209 -291.426539)
					(end 37.56533 -291.46246)
				)
			)
		)
	)
	(zone
		(layers "In1.Cu" "In2.Cu")
		(hatch none 0.5)
		(connect_pads
			(clearance 0)
		)
		(min_thickness 0.25)
		(keepout
			(tracks not_allowed)
			(vias allowed)
			(pads allowed)
			(copperpour not_allowed)
			(footprints allowed)
		)
		(placement
			(enabled no)
			(sheetname "")
		)
		(fill yes
			(thermal_gap 0.5)
			(thermal_bridge_width 0.5)
			(island_removal_mode 0)
		)
		(polygon
			(pts
				(arc
					(start 188.23813 -226.421442)
					(mid 188.253009 -226.457363)
					(end 188.28893 -226.472242)
				)
				(arc
					(start 189.68847 -226.472242)
					(mid 189.724391 -226.457363)
					(end 189.73927 -226.421442)
				)
				(arc
					(start 189.73927 -226.012502)
					(mid 189.724391 -225.976581)
					(end 189.68847 -225.961702)
				)
				(arc
					(start 188.28893 -225.961702)
					(mid 188.253009 -225.976581)
					(end 188.23813 -226.012502)
				)
			)
		)
	)
	(zone
		(layers "In1.Cu" "In2.Cu")
		(hatch none 0.5)
		(connect_pads
			(clearance 0)
		)
		(min_thickness 0.25)
		(keepout
			(tracks not_allowed)
			(vias allowed)
			(pads allowed)
			(copperpour not_allowed)
			(footprints allowed)
		)
		(placement
			(enabled no)
			(sheetname "")
		)
		(fill yes
			(thermal_gap 0.5)
			(thermal_bridge_width 0.5)
			(island_removal_mode 0)
		)
		(polygon
			(pts
				(arc
					(start 425.190666 -239.17148)
					(mid 425.205545 -239.207401)
					(end 425.241466 -239.22228)
				)
				(arc
					(start 426.641006 -239.22228)
					(mid 426.676927 -239.207401)
					(end 426.691806 -239.17148)
				)
				(arc
					(start 426.691806 -238.76254)
					(mid 426.676927 -238.726619)
					(end 426.641006 -238.71174)
				)
				(arc
					(start 425.241466 -238.71174)
					(mid 425.205545 -238.726619)
					(end 425.190666 -238.76254)
				)
			)
		)
	)
	(zone
		(layers "In1.Cu" "In2.Cu")
		(hatch none 0.5)
		(connect_pads
			(clearance 0)
		)
		(min_thickness 0.25)
		(keepout
			(tracks not_allowed)
			(vias allowed)
			(pads allowed)
			(copperpour not_allowed)
			(footprints allowed)
		)
		(placement
			(enabled no)
			(sheetname "")
		)
		(fill yes
			(thermal_gap 0.5)
			(thermal_bridge_width 0.5)
			(island_removal_mode 0)
		)
		(polygon
			(pts
				(arc
					(start 199.881998 -309.721504)
					(mid 199.896877 -309.757425)
					(end 199.932798 -309.772304)
				)
				(arc
					(start 201.332338 -309.772304)
					(mid 201.368259 -309.757425)
					(end 201.383138 -309.721504)
				)
				(arc
					(start 201.383138 -309.312564)
					(mid 201.368259 -309.276643)
					(end 201.332338 -309.261764)
				)
				(arc
					(start 199.932798 -309.261764)
					(mid 199.896877 -309.276643)
					(end 199.881998 -309.312564)
				)
			)
		)
	)
	(zone
		(layers "In1.Cu" "In2.Cu")
		(hatch none 0.5)
		(connect_pads
			(clearance 0)
		)
		(min_thickness 0.25)
		(keepout
			(tracks not_allowed)
			(vias allowed)
			(pads allowed)
			(copperpour not_allowed)
			(footprints allowed)
		)
		(placement
			(enabled no)
			(sheetname "")
		)
		(fill yes
			(thermal_gap 0.5)
			(thermal_bridge_width 0.5)
			(island_removal_mode 0)
		)
		(polygon
			(pts
				(arc
					(start 7.39013 -316.521338)
					(mid 7.405009 -316.557259)
					(end 7.44093 -316.572138)
				)
				(arc
					(start 8.84047 -316.572138)
					(mid 8.876391 -316.557259)
					(end 8.89127 -316.521338)
				)
				(arc
					(start 8.89127 -316.112398)
					(mid 8.876391 -316.076477)
					(end 8.84047 -316.061598)
				)
				(arc
					(start 7.44093 -316.061598)
					(mid 7.405009 -316.076477)
					(end 7.39013 -316.112398)
				)
			)
		)
	)
	(zone
		(layers "In1.Cu" "In2.Cu")
		(hatch none 0.5)
		(connect_pads
			(clearance 0)
		)
		(min_thickness 0.25)
		(keepout
			(tracks not_allowed)
			(vias allowed)
			(pads allowed)
			(copperpour not_allowed)
			(footprints allowed)
		)
		(placement
			(enabled no)
			(sheetname "")
		)
		(fill yes
			(thermal_gap 0.5)
			(thermal_bridge_width 0.5)
			(island_removal_mode 0)
		)
		(polygon
			(pts
				(arc
					(start 259.430266 -287.621472)
					(mid 259.445145 -287.657393)
					(end 259.481066 -287.672272)
				)
				(arc
					(start 260.880606 -287.672272)
					(mid 260.916527 -287.657393)
					(end 260.931406 -287.621472)
				)
				(arc
					(start 260.931406 -287.212532)
					(mid 260.916527 -287.176611)
					(end 260.880606 -287.161732)
				)
				(arc
					(start 259.481066 -287.161732)
					(mid 259.445145 -287.176611)
					(end 259.430266 -287.212532)
				)
			)
		)
	)
	(zone
		(layers "In1.Cu" "In2.Cu")
		(hatch none 0.5)
		(connect_pads
			(clearance 0)
		)
		(min_thickness 0.25)
		(keepout
			(tracks not_allowed)
			(vias allowed)
			(pads allowed)
			(copperpour not_allowed)
			(footprints allowed)
		)
		(placement
			(enabled no)
			(sheetname "")
		)
		(fill yes
			(thermal_gap 0.5)
			(thermal_bridge_width 0.5)
			(island_removal_mode 0)
		)
		(polygon
			(pts
				(arc
					(start 432.734466 -287.621472)
					(mid 432.749345 -287.657393)
					(end 432.785266 -287.672272)
				)
				(arc
					(start 434.184806 -287.672272)
					(mid 434.220727 -287.657393)
					(end 434.235606 -287.621472)
				)
				(arc
					(start 434.235606 -287.212532)
					(mid 434.220727 -287.176611)
					(end 434.184806 -287.161732)
				)
				(arc
					(start 432.785266 -287.161732)
					(mid 432.749345 -287.176611)
					(end 432.734466 -287.212532)
				)
			)
		)
	)
	(zone
		(layers "In1.Cu" "In2.Cu")
		(hatch none 0.5)
		(connect_pads
			(clearance 0)
		)
		(min_thickness 0.25)
		(keepout
			(tracks not_allowed)
			(vias allowed)
			(pads allowed)
			(copperpour not_allowed)
			(footprints allowed)
		)
		(placement
			(enabled no)
			(sheetname "")
		)
		(fill yes
			(thermal_gap 0.5)
			(thermal_bridge_width 0.5)
			(island_removal_mode 0)
		)
		(polygon
			(pts
				(arc
					(start 14.93393 -282.521406)
					(mid 14.948809 -282.557327)
					(end 14.98473 -282.572206)
				)
				(arc
					(start 16.38427 -282.572206)
					(mid 16.420191 -282.557327)
					(end 16.43507 -282.521406)
				)
				(arc
					(start 16.43507 -282.112466)
					(mid 16.420191 -282.076545)
					(end 16.38427 -282.061666)
				)
				(arc
					(start 14.98473 -282.061666)
					(mid 14.948809 -282.076545)
					(end 14.93393 -282.112466)
				)
			)
		)
	)
	(zone
		(layers "In1.Cu" "In2.Cu")
		(hatch none 0.5)
		(connect_pads
			(clearance 0)
		)
		(min_thickness 0.25)
		(keepout
			(tracks not_allowed)
			(vias allowed)
			(pads allowed)
			(copperpour not_allowed)
			(footprints allowed)
		)
		(placement
			(enabled no)
			(sheetname "")
		)
		(fill yes
			(thermal_gap 0.5)
			(thermal_bridge_width 0.5)
			(island_removal_mode 0)
		)
		(polygon
			(pts
				(arc
					(start 180.69433 -284.221428)
					(mid 180.709209 -284.257349)
					(end 180.74513 -284.272228)
				)
				(arc
					(start 182.14467 -284.272228)
					(mid 182.180591 -284.257349)
					(end 182.19547 -284.221428)
				)
				(arc
					(start 182.19547 -283.812488)
					(mid 182.180591 -283.776567)
					(end 182.14467 -283.761688)
				)
				(arc
					(start 180.74513 -283.761688)
					(mid 180.709209 -283.776567)
					(end 180.69433 -283.812488)
				)
			)
		)
	)
	(zone
		(layers "In1.Cu" "In2.Cu")
		(hatch none 0.5)
		(connect_pads
			(clearance 0)
		)
		(min_thickness 0.25)
		(keepout
			(tracks not_allowed)
			(vias allowed)
			(pads allowed)
			(copperpour not_allowed)
			(footprints allowed)
		)
		(placement
			(enabled no)
			(sheetname "")
		)
		(fill yes
			(thermal_gap 0.5)
			(thermal_bridge_width 0.5)
			(island_removal_mode 0)
		)
		(polygon
			(pts
				(arc
					(start 162.162998 -263.821418)
					(mid 162.177877 -263.857339)
					(end 162.213798 -263.872218)
				)
				(arc
					(start 163.613338 -263.872218)
					(mid 163.649259 -263.857339)
					(end 163.664138 -263.821418)
				)
				(arc
					(start 163.664138 -263.412478)
					(mid 163.649259 -263.376557)
					(end 163.613338 -263.361678)
				)
				(arc
					(start 162.213798 -263.361678)
					(mid 162.177877 -263.376557)
					(end 162.162998 -263.412478)
				)
			)
		)
	)
	(zone
		(layers "In1.Cu" "In2.Cu")
		(hatch none 0.5)
		(connect_pads
			(clearance 0)
		)
		(min_thickness 0.25)
		(keepout
			(tracks not_allowed)
			(vias allowed)
			(pads allowed)
			(copperpour not_allowed)
			(footprints allowed)
		)
		(placement
			(enabled no)
			(sheetname "")
		)
		(fill yes
			(thermal_gap 0.5)
			(thermal_bridge_width 0.5)
			(island_removal_mode 0)
		)
		(polygon
			(pts
				(arc
					(start 165.60673 -206.021432)
					(mid 165.621609 -206.057353)
					(end 165.65753 -206.072232)
				)
				(arc
					(start 167.05707 -206.072232)
					(mid 167.092991 -206.057353)
					(end 167.10787 -206.021432)
				)
				(arc
					(start 167.10787 -205.612492)
					(mid 167.092991 -205.576571)
					(end 167.05707 -205.561692)
				)
				(arc
					(start 165.65753 -205.561692)
					(mid 165.621609 -205.576571)
					(end 165.60673 -205.612492)
				)
			)
		)
	)
	(zone
		(layers "In1.Cu" "In2.Cu")
		(hatch none 0.5)
		(connect_pads
			(clearance 0)
		)
		(min_thickness 0.25)
		(keepout
			(tracks not_allowed)
			(vias allowed)
			(pads allowed)
			(copperpour not_allowed)
			(footprints allowed)
		)
		(placement
			(enabled no)
			(sheetname "")
		)
		(fill yes
			(thermal_gap 0.5)
			(thermal_bridge_width 0.5)
			(island_removal_mode 0)
		)
		(polygon
			(pts
				(arc
					(start 37.56533 -247.671336)
					(mid 37.580209 -247.707257)
					(end 37.61613 -247.722136)
				)
				(arc
					(start 39.01567 -247.722136)
					(mid 39.051591 -247.707257)
					(end 39.06647 -247.671336)
				)
				(arc
					(start 39.06647 -247.262396)
					(mid 39.051591 -247.226475)
					(end 39.01567 -247.211596)
				)
				(arc
					(start 37.61613 -247.211596)
					(mid 37.580209 -247.226475)
					(end 37.56533 -247.262396)
				)
			)
		)
	)
	(zone
		(layers "In1.Cu" "In2.Cu")
		(hatch none 0.5)
		(connect_pads
			(clearance 0)
		)
		(min_thickness 0.25)
		(keepout
			(tracks not_allowed)
			(vias allowed)
			(pads allowed)
			(copperpour not_allowed)
			(footprints allowed)
		)
		(placement
			(enabled no)
			(sheetname "")
		)
		(fill yes
			(thermal_gap 0.5)
			(thermal_bridge_width 0.5)
			(island_removal_mode 0)
		)
		(polygon
			(pts
				(arc
					(start 406.002998 -226.421442)
					(mid 406.017877 -226.457363)
					(end 406.053798 -226.472242)
				)
				(arc
					(start 407.453338 -226.472242)
					(mid 407.489259 -226.457363)
					(end 407.504138 -226.421442)
				)
				(arc
					(start 407.504138 -226.012502)
					(mid 407.489259 -225.976581)
					(end 407.453338 -225.961702)
				)
				(arc
					(start 406.053798 -225.961702)
					(mid 406.017877 -225.976581)
					(end 406.002998 -226.012502)
				)
			)
		)
	)
	(zone
		(layers "In1.Cu" "In2.Cu")
		(hatch none 0.5)
		(connect_pads
			(clearance 0)
		)
		(min_thickness 0.25)
		(keepout
			(tracks not_allowed)
			(vias allowed)
			(pads allowed)
			(copperpour not_allowed)
			(footprints allowed)
		)
		(placement
			(enabled no)
			(sheetname "")
		)
		(fill yes
			(thermal_gap 0.5)
			(thermal_bridge_width 0.5)
			(island_removal_mode 0)
		)
		(polygon
			(pts
				(arc
					(start 259.430266 -284.221428)
					(mid 259.445145 -284.257349)
					(end 259.481066 -284.272228)
				)
				(arc
					(start 260.880606 -284.272228)
					(mid 260.916527 -284.257349)
					(end 260.931406 -284.221428)
				)
				(arc
					(start 260.931406 -283.812488)
					(mid 260.916527 -283.776567)
					(end 260.880606 -283.761688)
				)
				(arc
					(start 259.481066 -283.761688)
					(mid 259.445145 -283.776567)
					(end 259.430266 -283.812488)
				)
			)
		)
	)
	(zone
		(layers "In1.Cu" "In2.Cu")
		(hatch none 0.5)
		(connect_pads
			(clearance 0)
		)
		(min_thickness 0.25)
		(keepout
			(tracks not_allowed)
			(vias allowed)
			(pads allowed)
			(copperpour not_allowed)
			(footprints allowed)
		)
		(placement
			(enabled no)
			(sheetname "")
		)
		(fill yes
			(thermal_gap 0.5)
			(thermal_bridge_width 0.5)
			(island_removal_mode 0)
		)
		(polygon
			(pts
				(arc
					(start 266.974066 -289.321494)
					(mid 266.988945 -289.357415)
					(end 267.024866 -289.372294)
				)
				(arc
					(start 268.424406 -289.372294)
					(mid 268.460327 -289.357415)
					(end 268.475206 -289.321494)
				)
				(arc
					(start 268.475206 -288.912554)
					(mid 268.460327 -288.876633)
					(end 268.424406 -288.861754)
				)
				(arc
					(start 267.024866 -288.861754)
					(mid 266.988945 -288.876633)
					(end 266.974066 -288.912554)
				)
			)
		)
	)
	(zone
		(layers "In1.Cu" "In2.Cu")
		(hatch none 0.5)
		(connect_pads
			(clearance 0)
		)
		(min_thickness 0.25)
		(keepout
			(tracks not_allowed)
			(vias allowed)
			(pads allowed)
			(copperpour not_allowed)
			(footprints allowed)
		)
		(placement
			(enabled no)
			(sheetname "")
		)
		(fill yes
			(thermal_gap 0.5)
			(thermal_bridge_width 0.5)
			(island_removal_mode 0)
		)
		(polygon
			(pts
				(arc
					(start 462.909666 -206.871316)
					(mid 462.924545 -206.907237)
					(end 462.960466 -206.922116)
				)
				(arc
					(start 464.360006 -206.922116)
					(mid 464.395927 -206.907237)
					(end 464.410806 -206.871316)
				)
				(arc
					(start 464.410806 -206.462376)
					(mid 464.395927 -206.426455)
					(end 464.360006 -206.411576)
				)
				(arc
					(start 462.960466 -206.411576)
					(mid 462.924545 -206.426455)
					(end 462.909666 -206.462376)
				)
			)
		)
	)
	(zone
		(layers "In1.Cu" "In2.Cu")
		(hatch none 0.5)
		(connect_pads
			(clearance 0)
		)
		(min_thickness 0.25)
		(keepout
			(tracks not_allowed)
			(vias allowed)
			(pads allowed)
			(copperpour not_allowed)
			(footprints allowed)
		)
		(placement
			(enabled no)
			(sheetname "")
		)
		(fill yes
			(thermal_gap 0.5)
			(thermal_bridge_width 0.5)
			(island_removal_mode 0)
		)
		(polygon
			(pts
				(arc
					(start 406.002998 -241.721386)
					(mid 406.017877 -241.757307)
					(end 406.053798 -241.772186)
				)
				(arc
					(start 407.453338 -241.772186)
					(mid 407.489259 -241.757307)
					(end 407.504138 -241.721386)
				)
				(arc
					(start 407.504138 -241.312446)
					(mid 407.489259 -241.276525)
					(end 407.453338 -241.261646)
				)
				(arc
					(start 406.053798 -241.261646)
					(mid 406.017877 -241.276525)
					(end 406.002998 -241.312446)
				)
			)
		)
	)
	(zone
		(layers "In1.Cu" "In2.Cu")
		(hatch none 0.5)
		(connect_pads
			(clearance 0)
		)
		(min_thickness 0.25)
		(keepout
			(tracks not_allowed)
			(vias allowed)
			(pads allowed)
			(copperpour not_allowed)
			(footprints allowed)
		)
		(placement
			(enabled no)
			(sheetname "")
		)
		(fill yes
			(thermal_gap 0.5)
			(thermal_bridge_width 0.5)
			(island_removal_mode 0)
		)
		(polygon
			(pts
				(arc
					(start 421.090598 -301.221394)
					(mid 421.105477 -301.257315)
					(end 421.141398 -301.272194)
				)
				(arc
					(start 422.540938 -301.272194)
					(mid 422.576859 -301.257315)
					(end 422.591738 -301.221394)
				)
				(arc
					(start 422.591738 -300.812454)
					(mid 422.576859 -300.776533)
					(end 422.540938 -300.761654)
				)
				(arc
					(start 421.141398 -300.761654)
					(mid 421.105477 -300.776533)
					(end 421.090598 -300.812454)
				)
			)
		)
	)
	(zone
		(layers "In1.Cu" "In2.Cu")
		(hatch none 0.5)
		(connect_pads
			(clearance 0)
		)
		(min_thickness 0.25)
		(keepout
			(tracks not_allowed)
			(vias allowed)
			(pads allowed)
			(copperpour not_allowed)
			(footprints allowed)
		)
		(placement
			(enabled no)
			(sheetname "")
		)
		(fill yes
			(thermal_gap 0.5)
			(thermal_bridge_width 0.5)
			(island_removal_mode 0)
		)
		(polygon
			(pts
				(arc
					(start 447.822066 -284.221428)
					(mid 447.836945 -284.257349)
					(end 447.872866 -284.272228)
				)
				(arc
					(start 449.272406 -284.272228)
					(mid 449.308327 -284.257349)
					(end 449.323206 -284.221428)
				)
				(arc
					(start 449.323206 -283.812488)
					(mid 449.308327 -283.776567)
					(end 449.272406 -283.761688)
				)
				(arc
					(start 447.872866 -283.761688)
					(mid 447.836945 -283.776567)
					(end 447.822066 -283.812488)
				)
			)
		)
	)
	(zone
		(layers "In1.Cu" "In2.Cu")
		(hatch none 0.5)
		(connect_pads
			(clearance 0)
		)
		(min_thickness 0.25)
		(keepout
			(tracks not_allowed)
			(vias allowed)
			(pads allowed)
			(copperpour not_allowed)
			(footprints allowed)
		)
		(placement
			(enabled no)
			(sheetname "")
		)
		(fill yes
			(thermal_gap 0.5)
			(thermal_bridge_width 0.5)
			(island_removal_mode 0)
		)
		(polygon
			(pts
				(arc
					(start 49.209198 -274.02155)
					(mid 49.224077 -274.057471)
					(end 49.259998 -274.07235)
				)
				(arc
					(start 50.659538 -274.07235)
					(mid 50.695459 -274.057471)
					(end 50.710338 -274.02155)
				)
				(arc
					(start 50.710338 -273.61261)
					(mid 50.695459 -273.576689)
					(end 50.659538 -273.56181)
				)
				(arc
					(start 49.259998 -273.56181)
					(mid 49.224077 -273.576689)
					(end 49.209198 -273.61261)
				)
			)
		)
	)
	(zone
		(layers "In1.Cu" "In2.Cu")
		(hatch none 0.5)
		(connect_pads
			(clearance 0)
		)
		(min_thickness 0.25)
		(keepout
			(tracks not_allowed)
			(vias allowed)
			(pads allowed)
			(copperpour not_allowed)
			(footprints allowed)
		)
		(placement
			(enabled no)
			(sheetname "")
		)
		(fill yes
			(thermal_gap 0.5)
			(thermal_bridge_width 0.5)
			(island_removal_mode 0)
		)
		(polygon
			(pts
				(arc
					(start 266.974066 -199.221344)
					(mid 266.988945 -199.257265)
					(end 267.024866 -199.272144)
				)
				(arc
					(start 268.424406 -199.272144)
					(mid 268.460327 -199.257265)
					(end 268.475206 -199.221344)
				)
				(arc
					(start 268.475206 -198.812404)
					(mid 268.460327 -198.776483)
					(end 268.424406 -198.761604)
				)
				(arc
					(start 267.024866 -198.761604)
					(mid 266.988945 -198.776483)
					(end 266.974066 -198.812404)
				)
			)
		)
	)
	(zone
		(layers "In1.Cu" "In2.Cu")
		(hatch none 0.5)
		(connect_pads
			(clearance 0)
		)
		(min_thickness 0.25)
		(keepout
			(tracks not_allowed)
			(vias allowed)
			(pads allowed)
			(copperpour not_allowed)
			(footprints allowed)
		)
		(placement
			(enabled no)
			(sheetname "")
		)
		(fill yes
			(thermal_gap 0.5)
			(thermal_bridge_width 0.5)
			(island_removal_mode 0)
		)
		(polygon
			(pts
				(arc
					(start 49.209198 -222.171514)
					(mid 49.224077 -222.207435)
					(end 49.259998 -222.222314)
				)
				(arc
					(start 50.659538 -222.222314)
					(mid 50.695459 -222.207435)
					(end 50.710338 -222.171514)
				)
				(arc
					(start 50.710338 -221.762574)
					(mid 50.695459 -221.726653)
					(end 50.659538 -221.711774)
				)
				(arc
					(start 49.259998 -221.711774)
					(mid 49.224077 -221.726653)
					(end 49.209198 -221.762574)
				)
			)
		)
	)
	(zone
		(layers "In1.Cu" "In2.Cu")
		(hatch none 0.5)
		(connect_pads
			(clearance 0)
		)
		(min_thickness 0.25)
		(keepout
			(tracks not_allowed)
			(vias allowed)
			(pads allowed)
			(copperpour not_allowed)
			(footprints allowed)
		)
		(placement
			(enabled no)
			(sheetname "")
		)
		(fill yes
			(thermal_gap 0.5)
			(thermal_bridge_width 0.5)
			(island_removal_mode 0)
		)
		(polygon
			(pts
				(arc
					(start 413.546798 -213.671404)
					(mid 413.561677 -213.707325)
					(end 413.597598 -213.722204)
				)
				(arc
					(start 414.997138 -213.722204)
					(mid 415.033059 -213.707325)
					(end 415.047938 -213.671404)
				)
				(arc
					(start 415.047938 -213.262464)
					(mid 415.033059 -213.226543)
					(end 414.997138 -213.211664)
				)
				(arc
					(start 413.597598 -213.211664)
					(mid 413.561677 -213.226543)
					(end 413.546798 -213.262464)
				)
			)
		)
	)
	(zone
		(layers "In1.Cu" "In2.Cu")
		(hatch none 0.5)
		(connect_pads
			(clearance 0)
		)
		(min_thickness 0.25)
		(keepout
			(tracks not_allowed)
			(vias allowed)
			(pads allowed)
			(copperpour not_allowed)
			(footprints allowed)
		)
		(placement
			(enabled no)
			(sheetname "")
		)
		(fill yes
			(thermal_gap 0.5)
			(thermal_bridge_width 0.5)
			(island_removal_mode 0)
		)
		(polygon
			(pts
				(arc
					(start 406.002998 -314.821316)
					(mid 406.017877 -314.857237)
					(end 406.053798 -314.872116)
				)
				(arc
					(start 407.453338 -314.872116)
					(mid 407.489259 -314.857237)
					(end 407.504138 -314.821316)
				)
				(arc
					(start 407.504138 -314.412376)
					(mid 407.489259 -314.376455)
					(end 407.453338 -314.361576)
				)
				(arc
					(start 406.053798 -314.361576)
					(mid 406.017877 -314.376455)
					(end 406.002998 -314.412376)
				)
			)
		)
	)
	(zone
		(layers "In1.Cu" "In2.Cu")
		(hatch none 0.5)
		(connect_pads
			(clearance 0)
		)
		(min_thickness 0.25)
		(keepout
			(tracks not_allowed)
			(vias allowed)
			(pads allowed)
			(copperpour not_allowed)
			(footprints allowed)
		)
		(placement
			(enabled no)
			(sheetname "")
		)
		(fill yes
			(thermal_gap 0.5)
			(thermal_bridge_width 0.5)
			(island_removal_mode 0)
		)
		(polygon
			(pts
				(arc
					(start 210.86953 -251.07138)
					(mid 210.884409 -251.107301)
					(end 210.92033 -251.12218)
				)
				(arc
					(start 212.31987 -251.12218)
					(mid 212.355791 -251.107301)
					(end 212.37067 -251.07138)
				)
				(arc
					(start 212.37067 -250.66244)
					(mid 212.355791 -250.626519)
					(end 212.31987 -250.61164)
				)
				(arc
					(start 210.92033 -250.61164)
					(mid 210.884409 -250.626519)
					(end 210.86953 -250.66244)
				)
			)
		)
	)
	(zone
		(layers "In1.Cu" "In2.Cu")
		(hatch none 0.5)
		(connect_pads
			(clearance 0)
		)
		(min_thickness 0.25)
		(keepout
			(tracks not_allowed)
			(vias allowed)
			(pads allowed)
			(copperpour not_allowed)
			(footprints allowed)
		)
		(placement
			(enabled no)
			(sheetname "")
		)
		(fill yes
			(thermal_gap 0.5)
			(thermal_bridge_width 0.5)
			(island_removal_mode 0)
		)
		(polygon
			(pts
				(arc
					(start 19.033998 -285.92145)
					(mid 19.048877 -285.957371)
					(end 19.084798 -285.97225)
				)
				(arc
					(start 20.484338 -285.97225)
					(mid 20.520259 -285.957371)
					(end 20.535138 -285.92145)
				)
				(arc
					(start 20.535138 -285.51251)
					(mid 20.520259 -285.476589)
					(end 20.484338 -285.46171)
				)
				(arc
					(start 19.084798 -285.46171)
					(mid 19.048877 -285.476589)
					(end 19.033998 -285.51251)
				)
			)
		)
	)
	(zone
		(layers "In1.Cu" "In2.Cu")
		(hatch none 0.5)
		(connect_pads
			(clearance 0)
		)
		(min_thickness 0.25)
		(keepout
			(tracks not_allowed)
			(vias allowed)
			(pads allowed)
			(copperpour not_allowed)
			(footprints allowed)
		)
		(placement
			(enabled no)
			(sheetname "")
		)
		(fill yes
			(thermal_gap 0.5)
			(thermal_bridge_width 0.5)
			(island_removal_mode 0)
		)
		(polygon
			(pts
				(arc
					(start 203.32573 -294.421306)
					(mid 203.340609 -294.457227)
					(end 203.37653 -294.472106)
				)
				(arc
					(start 204.77607 -294.472106)
					(mid 204.811991 -294.457227)
					(end 204.82687 -294.421306)
				)
				(arc
					(start 204.82687 -294.012366)
					(mid 204.811991 -293.976445)
					(end 204.77607 -293.961566)
				)
				(arc
					(start 203.37653 -293.961566)
					(mid 203.340609 -293.976445)
					(end 203.32573 -294.012366)
				)
			)
		)
	)
	(zone
		(layers "In1.Cu" "In2.Cu")
		(hatch none 0.5)
		(connect_pads
			(clearance 0)
		)
		(min_thickness 0.25)
		(keepout
			(tracks not_allowed)
			(vias allowed)
			(pads allowed)
			(copperpour not_allowed)
			(footprints allowed)
		)
		(placement
			(enabled no)
			(sheetname "")
		)
		(fill yes
			(thermal_gap 0.5)
			(thermal_bridge_width 0.5)
			(island_removal_mode 0)
		)
		(polygon
			(pts
				(arc
					(start 432.734466 -205.171548)
					(mid 432.749345 -205.207469)
					(end 432.785266 -205.222348)
				)
				(arc
					(start 434.184806 -205.222348)
					(mid 434.220727 -205.207469)
					(end 434.235606 -205.171548)
				)
				(arc
					(start 434.235606 -204.762608)
					(mid 434.220727 -204.726687)
					(end 434.184806 -204.711808)
				)
				(arc
					(start 432.785266 -204.711808)
					(mid 432.749345 -204.726687)
					(end 432.734466 -204.762608)
				)
			)
		)
	)
	(zone
		(layers "In1.Cu" "In2.Cu")
		(hatch none 0.5)
		(connect_pads
			(clearance 0)
		)
		(min_thickness 0.25)
		(keepout
			(tracks not_allowed)
			(vias allowed)
			(pads allowed)
			(copperpour not_allowed)
			(footprints allowed)
		)
		(placement
			(enabled no)
			(sheetname "")
		)
		(fill yes
			(thermal_gap 0.5)
			(thermal_bridge_width 0.5)
			(island_removal_mode 0)
		)
		(polygon
			(pts
				(arc
					(start 162.162998 -205.171548)
					(mid 162.177877 -205.207469)
					(end 162.213798 -205.222348)
				)
				(arc
					(start 163.613338 -205.222348)
					(mid 163.649259 -205.207469)
					(end 163.664138 -205.171548)
				)
				(arc
					(start 163.664138 -204.762608)
					(mid 163.649259 -204.726687)
					(end 163.613338 -204.711808)
				)
				(arc
					(start 162.213798 -204.711808)
					(mid 162.177877 -204.726687)
					(end 162.162998 -204.762608)
				)
			)
		)
	)
	(zone
		(layers "In1.Cu" "In2.Cu")
		(hatch none 0.5)
		(connect_pads
			(clearance 0)
		)
		(min_thickness 0.25)
		(keepout
			(tracks not_allowed)
			(vias allowed)
			(pads allowed)
			(copperpour not_allowed)
			(footprints allowed)
		)
		(placement
			(enabled no)
			(sheetname "")
		)
		(fill yes
			(thermal_gap 0.5)
			(thermal_bridge_width 0.5)
			(island_removal_mode 0)
		)
		(polygon
			(pts
				(arc
					(start 214.969598 -222.171514)
					(mid 214.984477 -222.207435)
					(end 215.020398 -222.222314)
				)
				(arc
					(start 216.419938 -222.222314)
					(mid 216.455859 -222.207435)
					(end 216.470738 -222.171514)
				)
				(arc
					(start 216.470738 -221.762574)
					(mid 216.455859 -221.726653)
					(end 216.419938 -221.711774)
				)
				(arc
					(start 215.020398 -221.711774)
					(mid 214.984477 -221.726653)
					(end 214.969598 -221.762574)
				)
			)
		)
	)
	(zone
		(layers "In1.Cu" "In2.Cu")
		(hatch none 0.5)
		(connect_pads
			(clearance 0)
		)
		(min_thickness 0.25)
		(keepout
			(tracks not_allowed)
			(vias allowed)
			(pads allowed)
			(copperpour not_allowed)
			(footprints allowed)
		)
		(placement
			(enabled no)
			(sheetname "")
		)
		(fill yes
			(thermal_gap 0.5)
			(thermal_bridge_width 0.5)
			(island_removal_mode 0)
		)
		(polygon
			(pts
				(arc
					(start 199.881998 -308.021482)
					(mid 199.896877 -308.057403)
					(end 199.932798 -308.072282)
				)
				(arc
					(start 201.332338 -308.072282)
					(mid 201.368259 -308.057403)
					(end 201.383138 -308.021482)
				)
				(arc
					(start 201.383138 -307.612542)
					(mid 201.368259 -307.576621)
					(end 201.332338 -307.561742)
				)
				(arc
					(start 199.932798 -307.561742)
					(mid 199.896877 -307.576621)
					(end 199.881998 -307.612542)
				)
			)
		)
	)
	(zone
		(layers "In1.Cu" "In2.Cu")
		(hatch none 0.5)
		(connect_pads
			(clearance 0)
		)
		(min_thickness 0.25)
		(keepout
			(tracks not_allowed)
			(vias allowed)
			(pads allowed)
			(copperpour not_allowed)
			(footprints allowed)
		)
		(placement
			(enabled no)
			(sheetname "")
		)
		(fill yes
			(thermal_gap 0.5)
			(thermal_bridge_width 0.5)
			(island_removal_mode 0)
		)
		(polygon
			(pts
				(arc
					(start 165.60673 -215.371426)
					(mid 165.621609 -215.407347)
					(end 165.65753 -215.422226)
				)
				(arc
					(start 167.05707 -215.422226)
					(mid 167.092991 -215.407347)
					(end 167.10787 -215.371426)
				)
				(arc
					(start 167.10787 -214.962486)
					(mid 167.092991 -214.926565)
					(end 167.05707 -214.911686)
				)
				(arc
					(start 165.65753 -214.911686)
					(mid 165.621609 -214.926565)
					(end 165.60673 -214.962486)
				)
			)
		)
	)
	(zone
		(layers "In1.Cu" "In2.Cu")
		(hatch none 0.5)
		(connect_pads
			(clearance 0)
		)
		(min_thickness 0.25)
		(keepout
			(tracks not_allowed)
			(vias allowed)
			(pads allowed)
			(copperpour not_allowed)
			(footprints allowed)
		)
		(placement
			(enabled no)
			(sheetname "")
		)
		(fill yes
			(thermal_gap 0.5)
			(thermal_bridge_width 0.5)
			(island_removal_mode 0)
		)
		(polygon
			(pts
				(arc
					(start 451.265798 -198.37146)
					(mid 451.280677 -198.407381)
					(end 451.316598 -198.42226)
				)
				(arc
					(start 452.716138 -198.42226)
					(mid 452.752059 -198.407381)
					(end 452.766938 -198.37146)
				)
				(arc
					(start 452.766938 -197.96252)
					(mid 452.752059 -197.926599)
					(end 452.716138 -197.91172)
				)
				(arc
					(start 451.316598 -197.91172)
					(mid 451.280677 -197.926599)
					(end 451.265798 -197.96252)
				)
			)
		)
	)
	(zone
		(layers "In1.Cu" "In2.Cu")
		(hatch none 0.5)
		(connect_pads
			(clearance 0)
		)
		(min_thickness 0.25)
		(keepout
			(tracks not_allowed)
			(vias allowed)
			(pads allowed)
			(copperpour not_allowed)
			(footprints allowed)
		)
		(placement
			(enabled no)
			(sheetname "")
		)
		(fill yes
			(thermal_gap 0.5)
			(thermal_bridge_width 0.5)
			(island_removal_mode 0)
		)
		(polygon
			(pts
				(arc
					(start 259.430266 -274.02155)
					(mid 259.445145 -274.057471)
					(end 259.481066 -274.07235)
				)
				(arc
					(start 260.880606 -274.07235)
					(mid 260.916527 -274.057471)
					(end 260.931406 -274.02155)
				)
				(arc
					(start 260.931406 -273.61261)
					(mid 260.916527 -273.576689)
					(end 260.880606 -273.56181)
				)
				(arc
					(start 259.481066 -273.56181)
					(mid 259.445145 -273.576689)
					(end 259.430266 -273.61261)
				)
			)
		)
	)
	(zone
		(layers "In1.Cu" "In2.Cu")
		(hatch none 0.5)
		(connect_pads
			(clearance 0)
		)
		(min_thickness 0.25)
		(keepout
			(tracks not_allowed)
			(vias allowed)
			(pads allowed)
			(copperpour not_allowed)
			(footprints allowed)
		)
		(placement
			(enabled no)
			(sheetname "")
		)
		(fill yes
			(thermal_gap 0.5)
			(thermal_bridge_width 0.5)
			(island_removal_mode 0)
		)
		(polygon
			(pts
				(arc
					(start 458.809598 -235.771436)
					(mid 458.824477 -235.807357)
					(end 458.860398 -235.822236)
				)
				(arc
					(start 460.259938 -235.822236)
					(mid 460.295859 -235.807357)
					(end 460.310738 -235.771436)
				)
				(arc
					(start 460.310738 -235.362496)
					(mid 460.295859 -235.326575)
					(end 460.259938 -235.311696)
				)
				(arc
					(start 458.860398 -235.311696)
					(mid 458.824477 -235.326575)
					(end 458.809598 -235.362496)
				)
			)
		)
	)
	(zone
		(layers "In1.Cu" "In2.Cu")
		(hatch none 0.5)
		(connect_pads
			(clearance 0)
		)
		(min_thickness 0.25)
		(keepout
			(tracks not_allowed)
			(vias allowed)
			(pads allowed)
			(copperpour not_allowed)
			(footprints allowed)
		)
		(placement
			(enabled no)
			(sheetname "")
		)
		(fill yes
			(thermal_gap 0.5)
			(thermal_bridge_width 0.5)
			(island_removal_mode 0)
		)
		(polygon
			(pts
				(arc
					(start 262.873998 -218.77147)
					(mid 262.888877 -218.807391)
					(end 262.924798 -218.82227)
				)
				(arc
					(start 264.324338 -218.82227)
					(mid 264.360259 -218.807391)
					(end 264.375138 -218.77147)
				)
				(arc
					(start 264.375138 -218.36253)
					(mid 264.360259 -218.326609)
					(end 264.324338 -218.31173)
				)
				(arc
					(start 262.924798 -218.31173)
					(mid 262.888877 -218.326609)
					(end 262.873998 -218.36253)
				)
			)
		)
	)
	(zone
		(layers "In1.Cu" "In2.Cu")
		(hatch none 0.5)
		(connect_pads
			(clearance 0)
		)
		(min_thickness 0.25)
		(keepout
			(tracks not_allowed)
			(vias allowed)
			(pads allowed)
			(copperpour not_allowed)
			(footprints allowed)
		)
		(placement
			(enabled no)
			(sheetname "")
		)
		(fill yes
			(thermal_gap 0.5)
			(thermal_bridge_width 0.5)
			(island_removal_mode 0)
		)
		(polygon
			(pts
				(arc
					(start 297.149266 -199.221344)
					(mid 297.164145 -199.257265)
					(end 297.200066 -199.272144)
				)
				(arc
					(start 298.599606 -199.272144)
					(mid 298.635527 -199.257265)
					(end 298.650406 -199.221344)
				)
				(arc
					(start 298.650406 -198.812404)
					(mid 298.635527 -198.776483)
					(end 298.599606 -198.761604)
				)
				(arc
					(start 297.200066 -198.761604)
					(mid 297.164145 -198.776483)
					(end 297.149266 -198.812404)
				)
			)
		)
	)
	(zone
		(layers "In1.Cu" "In2.Cu")
		(hatch none 0.5)
		(connect_pads
			(clearance 0)
		)
		(min_thickness 0.25)
		(keepout
			(tracks not_allowed)
			(vias allowed)
			(pads allowed)
			(copperpour not_allowed)
			(footprints allowed)
		)
		(placement
			(enabled no)
			(sheetname "")
		)
		(fill yes
			(thermal_gap 0.5)
			(thermal_bridge_width 0.5)
			(island_removal_mode 0)
		)
		(polygon
			(pts
				(arc
					(start 432.734466 -211.121498)
					(mid 432.749345 -211.157419)
					(end 432.785266 -211.172298)
				)
				(arc
					(start 434.184806 -211.172298)
					(mid 434.220727 -211.157419)
					(end 434.235606 -211.121498)
				)
				(arc
					(start 434.235606 -210.712558)
					(mid 434.220727 -210.676637)
					(end 434.184806 -210.661758)
				)
				(arc
					(start 432.785266 -210.661758)
					(mid 432.749345 -210.676637)
					(end 432.734466 -210.712558)
				)
			)
		)
	)
	(zone
		(layers "In1.Cu" "In2.Cu")
		(hatch none 0.5)
		(connect_pads
			(clearance 0)
		)
		(min_thickness 0.25)
		(keepout
			(tracks not_allowed)
			(vias allowed)
			(pads allowed)
			(copperpour not_allowed)
			(footprints allowed)
		)
		(placement
			(enabled no)
			(sheetname "")
		)
		(fill yes
			(thermal_gap 0.5)
			(thermal_bridge_width 0.5)
			(island_removal_mode 0)
		)
		(polygon
			(pts
				(arc
					(start 184.794398 -272.321528)
					(mid 184.809277 -272.357449)
					(end 184.845198 -272.372328)
				)
				(arc
					(start 186.244738 -272.372328)
					(mid 186.280659 -272.357449)
					(end 186.295538 -272.321528)
				)
				(arc
					(start 186.295538 -271.912588)
					(mid 186.280659 -271.876667)
					(end 186.244738 -271.861788)
				)
				(arc
					(start 184.845198 -271.861788)
					(mid 184.809277 -271.876667)
					(end 184.794398 -271.912588)
				)
			)
		)
	)
	(zone
		(layers "In1.Cu" "In2.Cu")
		(hatch none 0.5)
		(connect_pads
			(clearance 0)
		)
		(min_thickness 0.25)
		(keepout
			(tracks not_allowed)
			(vias allowed)
			(pads allowed)
			(copperpour not_allowed)
			(footprints allowed)
		)
		(placement
			(enabled no)
			(sheetname "")
		)
		(fill yes
			(thermal_gap 0.5)
			(thermal_bridge_width 0.5)
			(island_removal_mode 0)
		)
		(polygon
			(pts
				(arc
					(start 64.296798 -279.9715)
					(mid 64.311677 -280.007421)
					(end 64.347598 -280.0223)
				)
				(arc
					(start 65.747138 -280.0223)
					(mid 65.783059 -280.007421)
					(end 65.797938 -279.9715)
				)
				(arc
					(start 65.797938 -279.56256)
					(mid 65.783059 -279.526639)
					(end 65.747138 -279.51176)
				)
				(arc
					(start 64.347598 -279.51176)
					(mid 64.311677 -279.526639)
					(end 64.296798 -279.56256)
				)
			)
		)
	)
	(zone
		(layers "In1.Cu" "In2.Cu")
		(hatch none 0.5)
		(connect_pads
			(clearance 0)
		)
		(min_thickness 0.25)
		(keepout
			(tracks not_allowed)
			(vias allowed)
			(pads allowed)
			(copperpour not_allowed)
			(footprints allowed)
		)
		(placement
			(enabled no)
			(sheetname "")
		)
		(fill yes
			(thermal_gap 0.5)
			(thermal_bridge_width 0.5)
			(island_removal_mode 0)
		)
		(polygon
			(pts
				(arc
					(start 52.65293 -249.371358)
					(mid 52.667809 -249.407279)
					(end 52.70373 -249.422158)
				)
				(arc
					(start 54.10327 -249.422158)
					(mid 54.139191 -249.407279)
					(end 54.15407 -249.371358)
				)
				(arc
					(start 54.15407 -248.962418)
					(mid 54.139191 -248.926497)
					(end 54.10327 -248.911618)
				)
				(arc
					(start 52.70373 -248.911618)
					(mid 52.667809 -248.926497)
					(end 52.65293 -248.962418)
				)
			)
		)
	)
	(zone
		(layers "In1.Cu" "In2.Cu")
		(hatch none 0.5)
		(connect_pads
			(clearance 0)
		)
		(min_thickness 0.25)
		(keepout
			(tracks not_allowed)
			(vias allowed)
			(pads allowed)
			(copperpour not_allowed)
			(footprints allowed)
		)
		(placement
			(enabled no)
			(sheetname "")
		)
		(fill yes
			(thermal_gap 0.5)
			(thermal_bridge_width 0.5)
			(island_removal_mode 0)
		)
		(polygon
			(pts
				(arc
					(start 297.149266 -263.821418)
					(mid 297.164145 -263.857339)
					(end 297.200066 -263.872218)
				)
				(arc
					(start 298.599606 -263.872218)
					(mid 298.635527 -263.857339)
					(end 298.650406 -263.821418)
				)
				(arc
					(start 298.650406 -263.412478)
					(mid 298.635527 -263.376557)
					(end 298.599606 -263.361678)
				)
				(arc
					(start 297.200066 -263.361678)
					(mid 297.164145 -263.376557)
					(end 297.149266 -263.412478)
				)
			)
		)
	)
	(zone
		(layers "In1.Cu" "In2.Cu")
		(hatch none 0.5)
		(connect_pads
			(clearance 0)
		)
		(min_thickness 0.25)
		(keepout
			(tracks not_allowed)
			(vias allowed)
			(pads allowed)
			(copperpour not_allowed)
			(footprints allowed)
		)
		(placement
			(enabled no)
			(sheetname "")
		)
		(fill yes
			(thermal_gap 0.5)
			(thermal_bridge_width 0.5)
			(island_removal_mode 0)
		)
		(polygon
			(pts
				(arc
					(start 30.02153 -218.77147)
					(mid 30.036409 -218.807391)
					(end 30.07233 -218.82227)
				)
				(arc
					(start 31.47187 -218.82227)
					(mid 31.507791 -218.807391)
					(end 31.52267 -218.77147)
				)
				(arc
					(start 31.52267 -218.36253)
					(mid 31.507791 -218.326609)
					(end 31.47187 -218.31173)
				)
				(arc
					(start 30.07233 -218.31173)
					(mid 30.036409 -218.326609)
					(end 30.02153 -218.36253)
				)
			)
		)
	)
	(zone
		(layers "In1.Cu" "In2.Cu")
		(hatch none 0.5)
		(connect_pads
			(clearance 0)
		)
		(min_thickness 0.25)
		(keepout
			(tracks not_allowed)
			(vias allowed)
			(pads allowed)
			(copperpour not_allowed)
			(footprints allowed)
		)
		(placement
			(enabled no)
			(sheetname "")
		)
		(fill yes
			(thermal_gap 0.5)
			(thermal_bridge_width 0.5)
			(island_removal_mode 0)
		)
		(polygon
			(pts
				(arc
					(start 300.592998 -218.77147)
					(mid 300.607877 -218.807391)
					(end 300.643798 -218.82227)
				)
				(arc
					(start 302.043338 -218.82227)
					(mid 302.079259 -218.807391)
					(end 302.094138 -218.77147)
				)
				(arc
					(start 302.094138 -218.36253)
					(mid 302.079259 -218.326609)
					(end 302.043338 -218.31173)
				)
				(arc
					(start 300.643798 -218.31173)
					(mid 300.607877 -218.326609)
					(end 300.592998 -218.36253)
				)
			)
		)
	)
	(zone
		(layers "In1.Cu" "In2.Cu")
		(hatch none 0.5)
		(connect_pads
			(clearance 0)
		)
		(min_thickness 0.25)
		(keepout
			(tracks not_allowed)
			(vias allowed)
			(pads allowed)
			(copperpour not_allowed)
			(footprints allowed)
		)
		(placement
			(enabled no)
			(sheetname "")
		)
		(fill yes
			(thermal_gap 0.5)
			(thermal_bridge_width 0.5)
			(island_removal_mode 0)
		)
		(polygon
			(pts
				(arc
					(start 458.809598 -238.321342)
					(mid 458.824477 -238.357263)
					(end 458.860398 -238.372142)
				)
				(arc
					(start 460.259938 -238.372142)
					(mid 460.295859 -238.357263)
					(end 460.310738 -238.321342)
				)
				(arc
					(start 460.310738 -237.912402)
					(mid 460.295859 -237.876481)
					(end 460.259938 -237.861602)
				)
				(arc
					(start 458.860398 -237.861602)
					(mid 458.824477 -237.876481)
					(end 458.809598 -237.912402)
				)
			)
		)
	)
	(zone
		(layers "In1.Cu" "In2.Cu")
		(hatch none 0.5)
		(connect_pads
			(clearance 0)
		)
		(min_thickness 0.25)
		(keepout
			(tracks not_allowed)
			(vias allowed)
			(pads allowed)
			(copperpour not_allowed)
			(footprints allowed)
		)
		(placement
			(enabled no)
			(sheetname "")
		)
		(fill yes
			(thermal_gap 0.5)
			(thermal_bridge_width 0.5)
			(island_removal_mode 0)
		)
		(polygon
			(pts
				(arc
					(start 410.103066 -208.571338)
					(mid 410.117945 -208.607259)
					(end 410.153866 -208.622138)
				)
				(arc
					(start 411.553406 -208.622138)
					(mid 411.589327 -208.607259)
					(end 411.604206 -208.571338)
				)
				(arc
					(start 411.604206 -208.162398)
					(mid 411.589327 -208.126477)
					(end 411.553406 -208.111598)
				)
				(arc
					(start 410.153866 -208.111598)
					(mid 410.117945 -208.126477)
					(end 410.103066 -208.162398)
				)
			)
		)
	)
	(zone
		(layers "In1.Cu" "In2.Cu")
		(hatch none 0.5)
		(connect_pads
			(clearance 0)
		)
		(min_thickness 0.25)
		(keepout
			(tracks not_allowed)
			(vias allowed)
			(pads allowed)
			(copperpour not_allowed)
			(footprints allowed)
		)
		(placement
			(enabled no)
			(sheetname "")
		)
		(fill yes
			(thermal_gap 0.5)
			(thermal_bridge_width 0.5)
			(island_removal_mode 0)
		)
		(polygon
			(pts
				(arc
					(start 312.236866 -205.171548)
					(mid 312.251745 -205.207469)
					(end 312.287666 -205.222348)
				)
				(arc
					(start 313.687206 -205.222348)
					(mid 313.723127 -205.207469)
					(end 313.738006 -205.171548)
				)
				(arc
					(start 313.738006 -204.762608)
					(mid 313.723127 -204.726687)
					(end 313.687206 -204.711808)
				)
				(arc
					(start 312.287666 -204.711808)
					(mid 312.251745 -204.726687)
					(end 312.236866 -204.762608)
				)
			)
		)
	)
	(zone
		(layers "In1.Cu" "In2.Cu")
		(hatch none 0.5)
		(connect_pads
			(clearance 0)
		)
		(min_thickness 0.25)
		(keepout
			(tracks not_allowed)
			(vias allowed)
			(pads allowed)
			(copperpour not_allowed)
			(footprints allowed)
		)
		(placement
			(enabled no)
			(sheetname "")
		)
		(fill yes
			(thermal_gap 0.5)
			(thermal_bridge_width 0.5)
			(island_removal_mode 0)
		)
		(polygon
			(pts
				(arc
					(start 447.822066 -272.321528)
					(mid 447.836945 -272.357449)
					(end 447.872866 -272.372328)
				)
				(arc
					(start 449.272406 -272.372328)
					(mid 449.308327 -272.357449)
					(end 449.323206 -272.321528)
				)
				(arc
					(start 449.323206 -271.912588)
					(mid 449.308327 -271.876667)
					(end 449.272406 -271.861788)
				)
				(arc
					(start 447.872866 -271.861788)
					(mid 447.836945 -271.876667)
					(end 447.822066 -271.912588)
				)
			)
		)
	)
	(zone
		(layers "In1.Cu" "In2.Cu")
		(hatch none 0.5)
		(connect_pads
			(clearance 0)
		)
		(min_thickness 0.25)
		(keepout
			(tracks not_allowed)
			(vias allowed)
			(pads allowed)
			(copperpour not_allowed)
			(footprints allowed)
		)
		(placement
			(enabled no)
			(sheetname "")
		)
		(fill yes
			(thermal_gap 0.5)
			(thermal_bridge_width 0.5)
			(island_removal_mode 0)
		)
		(polygon
			(pts
				(arc
					(start 195.78193 -262.971534)
					(mid 195.796809 -263.007455)
					(end 195.83273 -263.022334)
				)
				(arc
					(start 197.23227 -263.022334)
					(mid 197.268191 -263.007455)
					(end 197.28307 -262.971534)
				)
				(arc
					(start 197.28307 -262.562594)
					(mid 197.268191 -262.526673)
					(end 197.23227 -262.511794)
				)
				(arc
					(start 195.83273 -262.511794)
					(mid 195.796809 -262.526673)
					(end 195.78193 -262.562594)
				)
			)
		)
	)
	(zone
		(layers "In1.Cu" "In2.Cu")
		(hatch none 0.5)
		(connect_pads
			(clearance 0)
		)
		(min_thickness 0.25)
		(keepout
			(tracks not_allowed)
			(vias allowed)
			(pads allowed)
			(copperpour not_allowed)
			(footprints allowed)
		)
		(placement
			(enabled no)
			(sheetname "")
		)
		(fill yes
			(thermal_gap 0.5)
			(thermal_bridge_width 0.5)
			(island_removal_mode 0)
		)
		(polygon
			(pts
				(arc
					(start 14.93393 -275.721318)
					(mid 14.948809 -275.757239)
					(end 14.98473 -275.772118)
				)
				(arc
					(start 16.38427 -275.772118)
					(mid 16.420191 -275.757239)
					(end 16.43507 -275.721318)
				)
				(arc
					(start 16.43507 -275.312378)
					(mid 16.420191 -275.276457)
					(end 16.38427 -275.261578)
				)
				(arc
					(start 14.98473 -275.261578)
					(mid 14.948809 -275.276457)
					(end 14.93393 -275.312378)
				)
			)
		)
	)
	(zone
		(layers "In1.Cu" "In2.Cu")
		(hatch none 0.5)
		(connect_pads
			(clearance 0)
		)
		(min_thickness 0.25)
		(keepout
			(tracks not_allowed)
			(vias allowed)
			(pads allowed)
			(copperpour not_allowed)
			(footprints allowed)
		)
		(placement
			(enabled no)
			(sheetname "")
		)
		(fill yes
			(thermal_gap 0.5)
			(thermal_bridge_width 0.5)
			(island_removal_mode 0)
		)
		(polygon
			(pts
				(arc
					(start 162.162998 -292.721538)
					(mid 162.177877 -292.757459)
					(end 162.213798 -292.772338)
				)
				(arc
					(start 163.613338 -292.772338)
					(mid 163.649259 -292.757459)
					(end 163.664138 -292.721538)
				)
				(arc
					(start 163.664138 -292.312598)
					(mid 163.649259 -292.276677)
					(end 163.613338 -292.261798)
				)
				(arc
					(start 162.213798 -292.261798)
					(mid 162.177877 -292.276677)
					(end 162.162998 -292.312598)
				)
			)
		)
	)
	(zone
		(layers "In1.Cu" "In2.Cu")
		(hatch none 0.5)
		(connect_pads
			(clearance 0)
		)
		(min_thickness 0.25)
		(keepout
			(tracks not_allowed)
			(vias allowed)
			(pads allowed)
			(copperpour not_allowed)
			(footprints allowed)
		)
		(placement
			(enabled no)
			(sheetname "")
		)
		(fill yes
			(thermal_gap 0.5)
			(thermal_bridge_width 0.5)
			(island_removal_mode 0)
		)
		(polygon
			(pts
				(arc
					(start 297.149266 -265.52144)
					(mid 297.164145 -265.557361)
					(end 297.200066 -265.57224)
				)
				(arc
					(start 298.599606 -265.57224)
					(mid 298.635527 -265.557361)
					(end 298.650406 -265.52144)
				)
				(arc
					(start 298.650406 -265.1125)
					(mid 298.635527 -265.076579)
					(end 298.599606 -265.0617)
				)
				(arc
					(start 297.200066 -265.0617)
					(mid 297.164145 -265.076579)
					(end 297.149266 -265.1125)
				)
			)
		)
	)
	(zone
		(layers "In1.Cu" "In2.Cu")
		(hatch none 0.5)
		(connect_pads
			(clearance 0)
		)
		(min_thickness 0.25)
		(keepout
			(tracks not_allowed)
			(vias allowed)
			(pads allowed)
			(copperpour not_allowed)
			(footprints allowed)
		)
		(placement
			(enabled no)
			(sheetname "")
		)
		(fill yes
			(thermal_gap 0.5)
			(thermal_bridge_width 0.5)
			(island_removal_mode 0)
		)
		(polygon
			(pts
				(arc
					(start 188.23813 -210.27136)
					(mid 188.253009 -210.307281)
					(end 188.28893 -210.32216)
				)
				(arc
					(start 189.68847 -210.32216)
					(mid 189.724391 -210.307281)
					(end 189.73927 -210.27136)
				)
				(arc
					(start 189.73927 -209.86242)
					(mid 189.724391 -209.826499)
					(end 189.68847 -209.81162)
				)
				(arc
					(start 188.28893 -209.81162)
					(mid 188.253009 -209.826499)
					(end 188.23813 -209.86242)
				)
			)
		)
	)
	(zone
		(layers "In1.Cu" "In2.Cu")
		(hatch none 0.5)
		(connect_pads
			(clearance 0)
		)
		(min_thickness 0.25)
		(keepout
			(tracks not_allowed)
			(vias allowed)
			(pads allowed)
			(copperpour not_allowed)
			(footprints allowed)
		)
		(placement
			(enabled no)
			(sheetname "")
		)
		(fill yes
			(thermal_gap 0.5)
			(thermal_bridge_width 0.5)
			(island_removal_mode 0)
		)
		(polygon
			(pts
				(arc
					(start 210.86953 -279.121362)
					(mid 210.884409 -279.157283)
					(end 210.92033 -279.172162)
				)
				(arc
					(start 212.31987 -279.172162)
					(mid 212.355791 -279.157283)
					(end 212.37067 -279.121362)
				)
				(arc
					(start 212.37067 -278.712422)
					(mid 212.355791 -278.676501)
					(end 212.31987 -278.661622)
				)
				(arc
					(start 210.92033 -278.661622)
					(mid 210.884409 -278.676501)
					(end 210.86953 -278.712422)
				)
			)
		)
	)
	(zone
		(layers "In1.Cu" "In2.Cu")
		(hatch none 0.5)
		(connect_pads
			(clearance 0)
		)
		(min_thickness 0.25)
		(keepout
			(tracks not_allowed)
			(vias allowed)
			(pads allowed)
			(copperpour not_allowed)
			(footprints allowed)
		)
		(placement
			(enabled no)
			(sheetname "")
		)
		(fill yes
			(thermal_gap 0.5)
			(thermal_bridge_width 0.5)
			(island_removal_mode 0)
		)
		(polygon
			(pts
				(arc
					(start 432.734466 -295.271444)
					(mid 432.749345 -295.307365)
					(end 432.785266 -295.322244)
				)
				(arc
					(start 434.184806 -295.322244)
					(mid 434.220727 -295.307365)
					(end 434.235606 -295.271444)
				)
				(arc
					(start 434.235606 -294.862504)
					(mid 434.220727 -294.826583)
					(end 434.184806 -294.811704)
				)
				(arc
					(start 432.785266 -294.811704)
					(mid 432.749345 -294.826583)
					(end 432.734466 -294.862504)
				)
			)
		)
	)
	(zone
		(layers "In1.Cu" "In2.Cu")
		(hatch none 0.5)
		(connect_pads
			(clearance 0)
		)
		(min_thickness 0.25)
		(keepout
			(tracks not_allowed)
			(vias allowed)
			(pads allowed)
			(copperpour not_allowed)
			(footprints allowed)
		)
		(placement
			(enabled no)
			(sheetname "")
		)
		(fill yes
			(thermal_gap 0.5)
			(thermal_bridge_width 0.5)
			(island_removal_mode 0)
		)
		(polygon
			(pts
				(arc
					(start 462.909666 -218.77147)
					(mid 462.924545 -218.807391)
					(end 462.960466 -218.82227)
				)
				(arc
					(start 464.360006 -218.82227)
					(mid 464.395927 -218.807391)
					(end 464.410806 -218.77147)
				)
				(arc
					(start 464.410806 -218.36253)
					(mid 464.395927 -218.326609)
					(end 464.360006 -218.31173)
				)
				(arc
					(start 462.960466 -218.31173)
					(mid 462.924545 -218.326609)
					(end 462.909666 -218.36253)
				)
			)
		)
	)
	(zone
		(layers "In1.Cu" "In2.Cu")
		(hatch none 0.5)
		(connect_pads
			(clearance 0)
		)
		(min_thickness 0.25)
		(keepout
			(tracks not_allowed)
			(vias allowed)
			(pads allowed)
			(copperpour not_allowed)
			(footprints allowed)
		)
		(placement
			(enabled no)
			(sheetname "")
		)
		(fill yes
			(thermal_gap 0.5)
			(thermal_bridge_width 0.5)
			(island_removal_mode 0)
		)
		(polygon
			(pts
				(arc
					(start 413.546798 -288.471356)
					(mid 413.561677 -288.507277)
					(end 413.597598 -288.522156)
				)
				(arc
					(start 414.997138 -288.522156)
					(mid 415.033059 -288.507277)
					(end 415.047938 -288.471356)
				)
				(arc
					(start 415.047938 -288.062416)
					(mid 415.033059 -288.026495)
					(end 414.997138 -288.011616)
				)
				(arc
					(start 413.597598 -288.011616)
					(mid 413.561677 -288.026495)
					(end 413.546798 -288.062416)
				)
			)
		)
	)
	(zone
		(layers "In1.Cu" "In2.Cu")
		(hatch none 0.5)
		(connect_pads
			(clearance 0)
		)
		(min_thickness 0.25)
		(keepout
			(tracks not_allowed)
			(vias allowed)
			(pads allowed)
			(copperpour not_allowed)
			(footprints allowed)
		)
		(placement
			(enabled no)
			(sheetname "")
		)
		(fill yes
			(thermal_gap 0.5)
			(thermal_bridge_width 0.5)
			(island_removal_mode 0)
		)
		(polygon
			(pts
				(arc
					(start 277.961598 -211.971382)
					(mid 277.976477 -212.007303)
					(end 278.012398 -212.022182)
				)
				(arc
					(start 279.411938 -212.022182)
					(mid 279.447859 -212.007303)
					(end 279.462738 -211.971382)
				)
				(arc
					(start 279.462738 -211.562442)
					(mid 279.447859 -211.526521)
					(end 279.411938 -211.511642)
				)
				(arc
					(start 278.012398 -211.511642)
					(mid 277.976477 -211.526521)
					(end 277.961598 -211.562442)
				)
			)
		)
	)
	(zone
		(layers "In1.Cu" "In2.Cu")
		(hatch none 0.5)
		(connect_pads
			(clearance 0)
		)
		(min_thickness 0.25)
		(keepout
			(tracks not_allowed)
			(vias allowed)
			(pads allowed)
			(copperpour not_allowed)
			(footprints allowed)
		)
		(placement
			(enabled no)
			(sheetname "")
		)
		(fill yes
			(thermal_gap 0.5)
			(thermal_bridge_width 0.5)
			(island_removal_mode 0)
		)
		(polygon
			(pts
				(arc
					(start 45.10913 -288.471356)
					(mid 45.124009 -288.507277)
					(end 45.15993 -288.522156)
				)
				(arc
					(start 46.55947 -288.522156)
					(mid 46.595391 -288.507277)
					(end 46.61027 -288.471356)
				)
				(arc
					(start 46.61027 -288.062416)
					(mid 46.595391 -288.026495)
					(end 46.55947 -288.011616)
				)
				(arc
					(start 45.15993 -288.011616)
					(mid 45.124009 -288.026495)
					(end 45.10913 -288.062416)
				)
			)
		)
	)
	(zone
		(layers "In1.Cu" "In2.Cu")
		(hatch none 0.5)
		(connect_pads
			(clearance 0)
		)
		(min_thickness 0.25)
		(keepout
			(tracks not_allowed)
			(vias allowed)
			(pads allowed)
			(copperpour not_allowed)
			(footprints allowed)
		)
		(placement
			(enabled no)
			(sheetname "")
		)
		(fill yes
			(thermal_gap 0.5)
			(thermal_bridge_width 0.5)
			(island_removal_mode 0)
		)
		(polygon
			(pts
				(arc
					(start 428.634398 -240.021364)
					(mid 428.649277 -240.057285)
					(end 428.685198 -240.072164)
				)
				(arc
					(start 430.084738 -240.072164)
					(mid 430.120659 -240.057285)
					(end 430.135538 -240.021364)
				)
				(arc
					(start 430.135538 -239.612424)
					(mid 430.120659 -239.576503)
					(end 430.084738 -239.561624)
				)
				(arc
					(start 428.685198 -239.561624)
					(mid 428.649277 -239.576503)
					(end 428.634398 -239.612424)
				)
			)
		)
	)
	(zone
		(layers "In1.Cu" "In2.Cu")
		(hatch none 0.5)
		(connect_pads
			(clearance 0)
		)
		(min_thickness 0.25)
		(keepout
			(tracks not_allowed)
			(vias allowed)
			(pads allowed)
			(copperpour not_allowed)
			(footprints allowed)
		)
		(placement
			(enabled no)
			(sheetname "")
		)
		(fill yes
			(thermal_gap 0.5)
			(thermal_bridge_width 0.5)
			(island_removal_mode 0)
		)
		(polygon
			(pts
				(arc
					(start 56.752998 -216.22131)
					(mid 56.767877 -216.257231)
					(end 56.803798 -216.27211)
				)
				(arc
					(start 58.203338 -216.27211)
					(mid 58.239259 -216.257231)
					(end 58.254138 -216.22131)
				)
				(arc
					(start 58.254138 -215.81237)
					(mid 58.239259 -215.776449)
					(end 58.203338 -215.76157)
				)
				(arc
					(start 56.803798 -215.76157)
					(mid 56.767877 -215.776449)
					(end 56.752998 -215.81237)
				)
			)
		)
	)
	(zone
		(layers "In1.Cu" "In2.Cu")
		(hatch none 0.5)
		(connect_pads
			(clearance 0)
		)
		(min_thickness 0.25)
		(keepout
			(tracks not_allowed)
			(vias allowed)
			(pads allowed)
			(copperpour not_allowed)
			(footprints allowed)
		)
		(placement
			(enabled no)
			(sheetname "")
		)
		(fill yes
			(thermal_gap 0.5)
			(thermal_bridge_width 0.5)
			(island_removal_mode 0)
		)
		(polygon
			(pts
				(arc
					(start 447.822066 -205.171548)
					(mid 447.836945 -205.207469)
					(end 447.872866 -205.222348)
				)
				(arc
					(start 449.272406 -205.222348)
					(mid 449.308327 -205.207469)
					(end 449.323206 -205.171548)
				)
				(arc
					(start 449.323206 -204.762608)
					(mid 449.308327 -204.726687)
					(end 449.272406 -204.711808)
				)
				(arc
					(start 447.872866 -204.711808)
					(mid 447.836945 -204.726687)
					(end 447.822066 -204.762608)
				)
			)
		)
	)
	(zone
		(layers "In1.Cu" "In2.Cu")
		(hatch none 0.5)
		(connect_pads
			(clearance 0)
		)
		(min_thickness 0.25)
		(keepout
			(tracks not_allowed)
			(vias allowed)
			(pads allowed)
			(copperpour not_allowed)
			(footprints allowed)
		)
		(placement
			(enabled no)
			(sheetname "")
		)
		(fill yes
			(thermal_gap 0.5)
			(thermal_bridge_width 0.5)
			(island_removal_mode 0)
		)
		(polygon
			(pts
				(arc
					(start 49.209198 -287.621472)
					(mid 49.224077 -287.657393)
					(end 49.259998 -287.672272)
				)
				(arc
					(start 50.659538 -287.672272)
					(mid 50.695459 -287.657393)
					(end 50.710338 -287.621472)
				)
				(arc
					(start 50.710338 -287.212532)
					(mid 50.695459 -287.176611)
					(end 50.659538 -287.161732)
				)
				(arc
					(start 49.259998 -287.161732)
					(mid 49.224077 -287.176611)
					(end 49.209198 -287.212532)
				)
			)
		)
	)
	(zone
		(layers "In1.Cu" "In2.Cu")
		(hatch none 0.5)
		(connect_pads
			(clearance 0)
		)
		(min_thickness 0.25)
		(keepout
			(tracks not_allowed)
			(vias allowed)
			(pads allowed)
			(copperpour not_allowed)
			(footprints allowed)
		)
		(placement
			(enabled no)
			(sheetname "")
		)
		(fill yes
			(thermal_gap 0.5)
			(thermal_bridge_width 0.5)
			(island_removal_mode 0)
		)
		(polygon
			(pts
				(arc
					(start 34.121598 -209.421476)
					(mid 34.136477 -209.457397)
					(end 34.172398 -209.472276)
				)
				(arc
					(start 35.571938 -209.472276)
					(mid 35.607859 -209.457397)
					(end 35.622738 -209.421476)
				)
				(arc
					(start 35.622738 -209.012536)
					(mid 35.607859 -208.976615)
					(end 35.571938 -208.961736)
				)
				(arc
					(start 34.172398 -208.961736)
					(mid 34.136477 -208.976615)
					(end 34.121598 -209.012536)
				)
			)
		)
	)
	(zone
		(layers "In1.Cu" "In2.Cu")
		(hatch none 0.5)
		(connect_pads
			(clearance 0)
		)
		(min_thickness 0.25)
		(keepout
			(tracks not_allowed)
			(vias allowed)
			(pads allowed)
			(copperpour not_allowed)
			(footprints allowed)
		)
		(placement
			(enabled no)
			(sheetname "")
		)
		(fill yes
			(thermal_gap 0.5)
			(thermal_bridge_width 0.5)
			(island_removal_mode 0)
		)
		(polygon
			(pts
				(arc
					(start 436.178198 -210.27136)
					(mid 436.193077 -210.307281)
					(end 436.228998 -210.32216)
				)
				(arc
					(start 437.628538 -210.32216)
					(mid 437.664459 -210.307281)
					(end 437.679338 -210.27136)
				)
				(arc
					(start 437.679338 -209.86242)
					(mid 437.664459 -209.826499)
					(end 437.628538 -209.81162)
				)
				(arc
					(start 436.228998 -209.81162)
					(mid 436.193077 -209.826499)
					(end 436.178198 -209.86242)
				)
			)
		)
	)
	(zone
		(layers "In1.Cu" "In2.Cu")
		(hatch none 0.5)
		(connect_pads
			(clearance 0)
		)
		(min_thickness 0.25)
		(keepout
			(tracks not_allowed)
			(vias allowed)
			(pads allowed)
			(copperpour not_allowed)
			(footprints allowed)
		)
		(placement
			(enabled no)
			(sheetname "")
		)
		(fill yes
			(thermal_gap 0.5)
			(thermal_bridge_width 0.5)
			(island_removal_mode 0)
		)
		(polygon
			(pts
				(arc
					(start 428.634398 -224.72142)
					(mid 428.649277 -224.757341)
					(end 428.685198 -224.77222)
				)
				(arc
					(start 430.084738 -224.77222)
					(mid 430.120659 -224.757341)
					(end 430.135538 -224.72142)
				)
				(arc
					(start 430.135538 -224.31248)
					(mid 430.120659 -224.276559)
					(end 430.084738 -224.26168)
				)
				(arc
					(start 428.685198 -224.26168)
					(mid 428.649277 -224.276559)
					(end 428.634398 -224.31248)
				)
			)
		)
	)
	(zone
		(layers "In1.Cu" "In2.Cu")
		(hatch none 0.5)
		(connect_pads
			(clearance 0)
		)
		(min_thickness 0.25)
		(keepout
			(tracks not_allowed)
			(vias allowed)
			(pads allowed)
			(copperpour not_allowed)
			(footprints allowed)
		)
		(placement
			(enabled no)
			(sheetname "")
		)
		(fill yes
			(thermal_gap 0.5)
			(thermal_bridge_width 0.5)
			(island_removal_mode 0)
		)
		(polygon
			(pts
				(arc
					(start 255.330198 -198.37146)
					(mid 255.345077 -198.407381)
					(end 255.380998 -198.42226)
				)
				(arc
					(start 256.780538 -198.42226)
					(mid 256.816459 -198.407381)
					(end 256.831338 -198.37146)
				)
				(arc
					(start 256.831338 -197.96252)
					(mid 256.816459 -197.926599)
					(end 256.780538 -197.91172)
				)
				(arc
					(start 255.380998 -197.91172)
					(mid 255.345077 -197.926599)
					(end 255.330198 -197.96252)
				)
			)
		)
	)
	(zone
		(layers "In1.Cu" "In2.Cu")
		(hatch none 0.5)
		(connect_pads
			(clearance 0)
		)
		(min_thickness 0.25)
		(keepout
			(tracks not_allowed)
			(vias allowed)
			(pads allowed)
			(copperpour not_allowed)
			(footprints allowed)
		)
		(placement
			(enabled no)
			(sheetname "")
		)
		(fill yes
			(thermal_gap 0.5)
			(thermal_bridge_width 0.5)
			(island_removal_mode 0)
		)
		(polygon
			(pts
				(arc
					(start 7.39013 -280.821384)
					(mid 7.405009 -280.857305)
					(end 7.44093 -280.872184)
				)
				(arc
					(start 8.84047 -280.872184)
					(mid 8.876391 -280.857305)
					(end 8.89127 -280.821384)
				)
				(arc
					(start 8.89127 -280.412444)
					(mid 8.876391 -280.376523)
					(end 8.84047 -280.361644)
				)
				(arc
					(start 7.44093 -280.361644)
					(mid 7.405009 -280.376523)
					(end 7.39013 -280.412444)
				)
			)
		)
	)
	(zone
		(layers "In1.Cu" "In2.Cu")
		(hatch none 0.5)
		(connect_pads
			(clearance 0)
		)
		(min_thickness 0.25)
		(keepout
			(tracks not_allowed)
			(vias allowed)
			(pads allowed)
			(copperpour not_allowed)
			(footprints allowed)
		)
		(placement
			(enabled no)
			(sheetname "")
		)
		(fill yes
			(thermal_gap 0.5)
			(thermal_bridge_width 0.5)
			(island_removal_mode 0)
		)
		(polygon
			(pts
				(arc
					(start 270.417798 -299.521372)
					(mid 270.432677 -299.557293)
					(end 270.468598 -299.572172)
				)
				(arc
					(start 271.868138 -299.572172)
					(mid 271.904059 -299.557293)
					(end 271.918938 -299.521372)
				)
				(arc
					(start 271.918938 -299.112432)
					(mid 271.904059 -299.076511)
					(end 271.868138 -299.061632)
				)
				(arc
					(start 270.468598 -299.061632)
					(mid 270.432677 -299.076511)
					(end 270.417798 -299.112432)
				)
			)
		)
	)
	(zone
		(layers "In1.Cu" "In2.Cu")
		(hatch none 0.5)
		(connect_pads
			(clearance 0)
		)
		(min_thickness 0.25)
		(keepout
			(tracks not_allowed)
			(vias allowed)
			(pads allowed)
			(copperpour not_allowed)
			(footprints allowed)
		)
		(placement
			(enabled no)
			(sheetname "")
		)
		(fill yes
			(thermal_gap 0.5)
			(thermal_bridge_width 0.5)
			(island_removal_mode 0)
		)
		(polygon
			(pts
				(arc
					(start 169.706798 -225.571304)
					(mid 169.721677 -225.607225)
					(end 169.757598 -225.622104)
				)
				(arc
					(start 171.157138 -225.622104)
					(mid 171.193059 -225.607225)
					(end 171.207938 -225.571304)
				)
				(arc
					(start 171.207938 -225.162364)
					(mid 171.193059 -225.126443)
					(end 171.157138 -225.111564)
				)
				(arc
					(start 169.757598 -225.111564)
					(mid 169.721677 -225.126443)
					(end 169.706798 -225.162364)
				)
			)
		)
	)
	(zone
		(layers "In1.Cu" "In2.Cu")
		(hatch none 0.5)
		(connect_pads
			(clearance 0)
		)
		(min_thickness 0.25)
		(keepout
			(tracks not_allowed)
			(vias allowed)
			(pads allowed)
			(copperpour not_allowed)
			(footprints allowed)
		)
		(placement
			(enabled no)
			(sheetname "")
		)
		(fill yes
			(thermal_gap 0.5)
			(thermal_bridge_width 0.5)
			(island_removal_mode 0)
		)
		(polygon
			(pts
				(arc
					(start 34.121598 -287.621472)
					(mid 34.136477 -287.657393)
					(end 34.172398 -287.672272)
				)
				(arc
					(start 35.571938 -287.672272)
					(mid 35.607859 -287.657393)
					(end 35.622738 -287.621472)
				)
				(arc
					(start 35.622738 -287.212532)
					(mid 35.607859 -287.176611)
					(end 35.571938 -287.161732)
				)
				(arc
					(start 34.172398 -287.161732)
					(mid 34.136477 -287.176611)
					(end 34.121598 -287.212532)
				)
			)
		)
	)
	(zone
		(layers "In1.Cu" "In2.Cu")
		(hatch none 0.5)
		(connect_pads
			(clearance 0)
		)
		(min_thickness 0.25)
		(keepout
			(tracks not_allowed)
			(vias allowed)
			(pads allowed)
			(copperpour not_allowed)
			(footprints allowed)
		)
		(placement
			(enabled no)
			(sheetname "")
		)
		(fill yes
			(thermal_gap 0.5)
			(thermal_bridge_width 0.5)
			(island_removal_mode 0)
		)
		(polygon
			(pts
				(arc
					(start 30.02153 -198.37146)
					(mid 30.036409 -198.407381)
					(end 30.07233 -198.42226)
				)
				(arc
					(start 31.47187 -198.42226)
					(mid 31.507791 -198.407381)
					(end 31.52267 -198.37146)
				)
				(arc
					(start 31.52267 -197.96252)
					(mid 31.507791 -197.926599)
					(end 31.47187 -197.91172)
				)
				(arc
					(start 30.07233 -197.91172)
					(mid 30.036409 -197.926599)
					(end 30.02153 -197.96252)
				)
			)
		)
	)
	(zone
		(layers "In1.Cu" "In2.Cu")
		(hatch none 0.5)
		(connect_pads
			(clearance 0)
		)
		(min_thickness 0.25)
		(keepout
			(tracks not_allowed)
			(vias allowed)
			(pads allowed)
			(copperpour not_allowed)
			(footprints allowed)
		)
		(placement
			(enabled no)
			(sheetname "")
		)
		(fill yes
			(thermal_gap 0.5)
			(thermal_bridge_width 0.5)
			(island_removal_mode 0)
		)
		(polygon
			(pts
				(arc
					(start 11.490198 -270.621506)
					(mid 11.505077 -270.657427)
					(end 11.540998 -270.672306)
				)
				(arc
					(start 12.940538 -270.672306)
					(mid 12.976459 -270.657427)
					(end 12.991338 -270.621506)
				)
				(arc
					(start 12.991338 -270.212566)
					(mid 12.976459 -270.176645)
					(end 12.940538 -270.161766)
				)
				(arc
					(start 11.540998 -270.161766)
					(mid 11.505077 -270.176645)
					(end 11.490198 -270.212566)
				)
			)
		)
	)
	(zone
		(layers "In1.Cu" "In2.Cu")
		(hatch none 0.5)
		(connect_pads
			(clearance 0)
		)
		(min_thickness 0.25)
		(keepout
			(tracks not_allowed)
			(vias allowed)
			(pads allowed)
			(copperpour not_allowed)
			(footprints allowed)
		)
		(placement
			(enabled no)
			(sheetname "")
		)
		(fill yes
			(thermal_gap 0.5)
			(thermal_bridge_width 0.5)
			(island_removal_mode 0)
		)
		(polygon
			(pts
				(arc
					(start 425.190666 -296.971466)
					(mid 425.205545 -297.007387)
					(end 425.241466 -297.022266)
				)
				(arc
					(start 426.641006 -297.022266)
					(mid 426.676927 -297.007387)
					(end 426.691806 -296.971466)
				)
				(arc
					(start 426.691806 -296.562526)
					(mid 426.676927 -296.526605)
					(end 426.641006 -296.511726)
				)
				(arc
					(start 425.241466 -296.511726)
					(mid 425.205545 -296.526605)
					(end 425.190666 -296.562526)
				)
			)
		)
	)
	(zone
		(layers "In1.Cu" "In2.Cu")
		(hatch none 0.5)
		(connect_pads
			(clearance 0)
		)
		(min_thickness 0.25)
		(keepout
			(tracks not_allowed)
			(vias allowed)
			(pads allowed)
			(copperpour not_allowed)
			(footprints allowed)
		)
		(placement
			(enabled no)
			(sheetname "")
		)
		(fill yes
			(thermal_gap 0.5)
			(thermal_bridge_width 0.5)
			(island_removal_mode 0)
		)
		(polygon
			(pts
				(arc
					(start 22.47773 -244.271292)
					(mid 22.492609 -244.307213)
					(end 22.52853 -244.322092)
				)
				(arc
					(start 23.92807 -244.322092)
					(mid 23.963991 -244.307213)
					(end 23.97887 -244.271292)
				)
				(arc
					(start 23.97887 -243.862352)
					(mid 23.963991 -243.826431)
					(end 23.92807 -243.811552)
				)
				(arc
					(start 22.52853 -243.811552)
					(mid 22.492609 -243.826431)
					(end 22.47773 -243.862352)
				)
			)
		)
	)
	(zone
		(layers "In1.Cu" "In2.Cu")
		(hatch none 0.5)
		(connect_pads
			(clearance 0)
		)
		(min_thickness 0.25)
		(keepout
			(tracks not_allowed)
			(vias allowed)
			(pads allowed)
			(copperpour not_allowed)
			(footprints allowed)
		)
		(placement
			(enabled no)
			(sheetname "")
		)
		(fill yes
			(thermal_gap 0.5)
			(thermal_bridge_width 0.5)
			(island_removal_mode 0)
		)
		(polygon
			(pts
				(arc
					(start 274.517866 -212.82152)
					(mid 274.532745 -212.857441)
					(end 274.568666 -212.87232)
				)
				(arc
					(start 275.968206 -212.87232)
					(mid 276.004127 -212.857441)
					(end 276.019006 -212.82152)
				)
				(arc
					(start 276.019006 -212.41258)
					(mid 276.004127 -212.376659)
					(end 275.968206 -212.36178)
				)
				(arc
					(start 274.568666 -212.36178)
					(mid 274.532745 -212.376659)
					(end 274.517866 -212.41258)
				)
			)
		)
	)
	(zone
		(layers "In1.Cu" "In2.Cu")
		(hatch none 0.5)
		(connect_pads
			(clearance 0)
		)
		(min_thickness 0.25)
		(keepout
			(tracks not_allowed)
			(vias allowed)
			(pads allowed)
			(copperpour not_allowed)
			(footprints allowed)
		)
		(placement
			(enabled no)
			(sheetname "")
		)
		(fill yes
			(thermal_gap 0.5)
			(thermal_bridge_width 0.5)
			(island_removal_mode 0)
		)
		(polygon
			(pts
				(arc
					(start 413.546798 -303.7713)
					(mid 413.561677 -303.807221)
					(end 413.597598 -303.8221)
				)
				(arc
					(start 414.997138 -303.8221)
					(mid 415.033059 -303.807221)
					(end 415.047938 -303.7713)
				)
				(arc
					(start 415.047938 -303.36236)
					(mid 415.033059 -303.326439)
					(end 414.997138 -303.31156)
				)
				(arc
					(start 413.597598 -303.31156)
					(mid 413.561677 -303.326439)
					(end 413.546798 -303.36236)
				)
			)
		)
	)
	(zone
		(layers "In1.Cu" "In2.Cu")
		(hatch none 0.5)
		(connect_pads
			(clearance 0)
		)
		(min_thickness 0.25)
		(keepout
			(tracks not_allowed)
			(vias allowed)
			(pads allowed)
			(copperpour not_allowed)
			(footprints allowed)
		)
		(placement
			(enabled no)
			(sheetname "")
		)
		(fill yes
			(thermal_gap 0.5)
			(thermal_bridge_width 0.5)
			(island_removal_mode 0)
		)
		(polygon
			(pts
				(arc
					(start 41.665398 -263.821418)
					(mid 41.680277 -263.857339)
					(end 41.716198 -263.872218)
				)
				(arc
					(start 43.115738 -263.872218)
					(mid 43.151659 -263.857339)
					(end 43.166538 -263.821418)
				)
				(arc
					(start 43.166538 -263.412478)
					(mid 43.151659 -263.376557)
					(end 43.115738 -263.361678)
				)
				(arc
					(start 41.716198 -263.361678)
					(mid 41.680277 -263.376557)
					(end 41.665398 -263.412478)
				)
			)
		)
	)
	(zone
		(layers "In1.Cu" "In2.Cu")
		(hatch none 0.5)
		(connect_pads
			(clearance 0)
		)
		(min_thickness 0.25)
		(keepout
			(tracks not_allowed)
			(vias allowed)
			(pads allowed)
			(copperpour not_allowed)
			(footprints allowed)
		)
		(placement
			(enabled no)
			(sheetname "")
		)
		(fill yes
			(thermal_gap 0.5)
			(thermal_bridge_width 0.5)
			(island_removal_mode 0)
		)
		(polygon
			(pts
				(arc
					(start 455.365866 -250.221496)
					(mid 455.380745 -250.257417)
					(end 455.416666 -250.272296)
				)
				(arc
					(start 456.816206 -250.272296)
					(mid 456.852127 -250.257417)
					(end 456.867006 -250.221496)
				)
				(arc
					(start 456.867006 -249.812556)
					(mid 456.852127 -249.776635)
					(end 456.816206 -249.761756)
				)
				(arc
					(start 455.416666 -249.761756)
					(mid 455.380745 -249.776635)
					(end 455.365866 -249.812556)
				)
			)
		)
	)
	(zone
		(layers "In1.Cu" "In2.Cu")
		(hatch none 0.5)
		(connect_pads
			(clearance 0)
		)
		(min_thickness 0.25)
		(keepout
			(tracks not_allowed)
			(vias allowed)
			(pads allowed)
			(copperpour not_allowed)
			(footprints allowed)
		)
		(placement
			(enabled no)
			(sheetname "")
		)
		(fill yes
			(thermal_gap 0.5)
			(thermal_bridge_width 0.5)
			(island_removal_mode 0)
		)
		(polygon
			(pts
				(arc
					(start 312.236866 -308.021482)
					(mid 312.251745 -308.057403)
					(end 312.287666 -308.072282)
				)
				(arc
					(start 313.687206 -308.072282)
					(mid 313.723127 -308.057403)
					(end 313.738006 -308.021482)
				)
				(arc
					(start 313.738006 -307.612542)
					(mid 313.723127 -307.576621)
					(end 313.687206 -307.561742)
				)
				(arc
					(start 312.287666 -307.561742)
					(mid 312.251745 -307.576621)
					(end 312.236866 -307.612542)
				)
			)
		)
	)
	(zone
		(layers "In1.Cu" "In2.Cu")
		(hatch none 0.5)
		(connect_pads
			(clearance 0)
		)
		(min_thickness 0.25)
		(keepout
			(tracks not_allowed)
			(vias allowed)
			(pads allowed)
			(copperpour not_allowed)
			(footprints allowed)
		)
		(placement
			(enabled no)
			(sheetname "")
		)
		(fill yes
			(thermal_gap 0.5)
			(thermal_bridge_width 0.5)
			(island_removal_mode 0)
		)
		(polygon
			(pts
				(arc
					(start 180.69433 -297.82135)
					(mid 180.709209 -297.857271)
					(end 180.74513 -297.87215)
				)
				(arc
					(start 182.14467 -297.87215)
					(mid 182.180591 -297.857271)
					(end 182.19547 -297.82135)
				)
				(arc
					(start 182.19547 -297.41241)
					(mid 182.180591 -297.376489)
					(end 182.14467 -297.36161)
				)
				(arc
					(start 180.74513 -297.36161)
					(mid 180.709209 -297.376489)
					(end 180.69433 -297.41241)
				)
			)
		)
	)
	(zone
		(layers "In1.Cu" "In2.Cu")
		(hatch none 0.5)
		(connect_pads
			(clearance 0)
		)
		(min_thickness 0.25)
		(keepout
			(tracks not_allowed)
			(vias allowed)
			(pads allowed)
			(copperpour not_allowed)
			(footprints allowed)
		)
		(placement
			(enabled no)
			(sheetname "")
		)
		(fill yes
			(thermal_gap 0.5)
			(thermal_bridge_width 0.5)
			(island_removal_mode 0)
		)
		(polygon
			(pts
				(arc
					(start 52.65293 -218.77147)
					(mid 52.667809 -218.807391)
					(end 52.70373 -218.82227)
				)
				(arc
					(start 54.10327 -218.82227)
					(mid 54.139191 -218.807391)
					(end 54.15407 -218.77147)
				)
				(arc
					(start 54.15407 -218.36253)
					(mid 54.139191 -218.326609)
					(end 54.10327 -218.31173)
				)
				(arc
					(start 52.70373 -218.31173)
					(mid 52.667809 -218.326609)
					(end 52.65293 -218.36253)
				)
			)
		)
	)
	(zone
		(layers "In1.Cu" "In2.Cu")
		(hatch none 0.5)
		(connect_pads
			(clearance 0)
		)
		(min_thickness 0.25)
		(keepout
			(tracks not_allowed)
			(vias allowed)
			(pads allowed)
			(copperpour not_allowed)
			(footprints allowed)
		)
		(placement
			(enabled no)
			(sheetname "")
		)
		(fill yes
			(thermal_gap 0.5)
			(thermal_bridge_width 0.5)
			(island_removal_mode 0)
		)
		(polygon
			(pts
				(arc
					(start 266.974066 -245.12143)
					(mid 266.988945 -245.157351)
					(end 267.024866 -245.17223)
				)
				(arc
					(start 268.424406 -245.17223)
					(mid 268.460327 -245.157351)
					(end 268.475206 -245.12143)
				)
				(arc
					(start 268.475206 -244.71249)
					(mid 268.460327 -244.676569)
					(end 268.424406 -244.66169)
				)
				(arc
					(start 267.024866 -244.66169)
					(mid 266.988945 -244.676569)
					(end 266.974066 -244.71249)
				)
			)
		)
	)
	(zone
		(layers "In1.Cu" "In2.Cu")
		(hatch none 0.5)
		(connect_pads
			(clearance 0)
		)
		(min_thickness 0.25)
		(keepout
			(tracks not_allowed)
			(vias allowed)
			(pads allowed)
			(copperpour not_allowed)
			(footprints allowed)
		)
		(placement
			(enabled no)
			(sheetname "")
		)
		(fill yes
			(thermal_gap 0.5)
			(thermal_bridge_width 0.5)
			(island_removal_mode 0)
		)
		(polygon
			(pts
				(arc
					(start 282.061666 -313.971432)
					(mid 282.076545 -314.007353)
					(end 282.112466 -314.022232)
				)
				(arc
					(start 283.512006 -314.022232)
					(mid 283.547927 -314.007353)
					(end 283.562806 -313.971432)
				)
				(arc
					(start 283.562806 -313.562492)
					(mid 283.547927 -313.526571)
					(end 283.512006 -313.511692)
				)
				(arc
					(start 282.112466 -313.511692)
					(mid 282.076545 -313.526571)
					(end 282.061666 -313.562492)
				)
			)
		)
	)
	(zone
		(layers "In1.Cu" "In2.Cu")
		(hatch none 0.5)
		(connect_pads
			(clearance 0)
		)
		(min_thickness 0.25)
		(keepout
			(tracks not_allowed)
			(vias allowed)
			(pads allowed)
			(copperpour not_allowed)
			(footprints allowed)
		)
		(placement
			(enabled no)
			(sheetname "")
		)
		(fill yes
			(thermal_gap 0.5)
			(thermal_bridge_width 0.5)
			(island_removal_mode 0)
		)
		(polygon
			(pts
				(arc
					(start 312.236866 -201.771504)
					(mid 312.251745 -201.807425)
					(end 312.287666 -201.822304)
				)
				(arc
					(start 313.687206 -201.822304)
					(mid 313.723127 -201.807425)
					(end 313.738006 -201.771504)
				)
				(arc
					(start 313.738006 -201.362564)
					(mid 313.723127 -201.326643)
					(end 313.687206 -201.311764)
				)
				(arc
					(start 312.287666 -201.311764)
					(mid 312.251745 -201.326643)
					(end 312.236866 -201.362564)
				)
			)
		)
	)
	(zone
		(layers "In1.Cu" "In2.Cu")
		(hatch none 0.5)
		(connect_pads
			(clearance 0)
		)
		(min_thickness 0.25)
		(keepout
			(tracks not_allowed)
			(vias allowed)
			(pads allowed)
			(copperpour not_allowed)
			(footprints allowed)
		)
		(placement
			(enabled no)
			(sheetname "")
		)
		(fill yes
			(thermal_gap 0.5)
			(thermal_bridge_width 0.5)
			(island_removal_mode 0)
		)
		(polygon
			(pts
				(arc
					(start 447.822066 -223.871536)
					(mid 447.836945 -223.907457)
					(end 447.872866 -223.922336)
				)
				(arc
					(start 449.272406 -223.922336)
					(mid 449.308327 -223.907457)
					(end 449.323206 -223.871536)
				)
				(arc
					(start 449.323206 -223.462596)
					(mid 449.308327 -223.426675)
					(end 449.272406 -223.411796)
				)
				(arc
					(start 447.872866 -223.411796)
					(mid 447.836945 -223.426675)
					(end 447.822066 -223.462596)
				)
			)
		)
	)
	(zone
		(layers "In1.Cu" "In2.Cu")
		(hatch none 0.5)
		(connect_pads
			(clearance 0)
		)
		(min_thickness 0.25)
		(keepout
			(tracks not_allowed)
			(vias allowed)
			(pads allowed)
			(copperpour not_allowed)
			(footprints allowed)
		)
		(placement
			(enabled no)
			(sheetname "")
		)
		(fill yes
			(thermal_gap 0.5)
			(thermal_bridge_width 0.5)
			(island_removal_mode 0)
		)
		(polygon
			(pts
				(arc
					(start 277.961598 -314.821316)
					(mid 277.976477 -314.857237)
					(end 278.012398 -314.872116)
				)
				(arc
					(start 279.411938 -314.872116)
					(mid 279.447859 -314.857237)
					(end 279.462738 -314.821316)
				)
				(arc
					(start 279.462738 -314.412376)
					(mid 279.447859 -314.376455)
					(end 279.411938 -314.361576)
				)
				(arc
					(start 278.012398 -314.361576)
					(mid 277.976477 -314.376455)
					(end 277.961598 -314.412376)
				)
			)
		)
	)
	(zone
		(layers "In1.Cu" "In2.Cu")
		(hatch none 0.5)
		(connect_pads
			(clearance 0)
		)
		(min_thickness 0.25)
		(keepout
			(tracks not_allowed)
			(vias allowed)
			(pads allowed)
			(copperpour not_allowed)
			(footprints allowed)
		)
		(placement
			(enabled no)
			(sheetname "")
		)
		(fill yes
			(thermal_gap 0.5)
			(thermal_bridge_width 0.5)
			(island_removal_mode 0)
		)
		(polygon
			(pts
				(arc
					(start 413.546798 -280.821384)
					(mid 413.561677 -280.857305)
					(end 413.597598 -280.872184)
				)
				(arc
					(start 414.997138 -280.872184)
					(mid 415.033059 -280.857305)
					(end 415.047938 -280.821384)
				)
				(arc
					(start 415.047938 -280.412444)
					(mid 415.033059 -280.376523)
					(end 414.997138 -280.361644)
				)
				(arc
					(start 413.597598 -280.361644)
					(mid 413.561677 -280.376523)
					(end 413.546798 -280.412444)
				)
			)
		)
	)
	(zone
		(layers "In1.Cu" "In2.Cu")
		(hatch none 0.5)
		(connect_pads
			(clearance 0)
		)
		(min_thickness 0.25)
		(keepout
			(tracks not_allowed)
			(vias allowed)
			(pads allowed)
			(copperpour not_allowed)
			(footprints allowed)
		)
		(placement
			(enabled no)
			(sheetname "")
		)
		(fill yes
			(thermal_gap 0.5)
			(thermal_bridge_width 0.5)
			(island_removal_mode 0)
		)
		(polygon
			(pts
				(arc
					(start 443.721998 -196.671438)
					(mid 443.736877 -196.707359)
					(end 443.772798 -196.722238)
				)
				(arc
					(start 445.172338 -196.722238)
					(mid 445.208259 -196.707359)
					(end 445.223138 -196.671438)
				)
				(arc
					(start 445.223138 -196.262498)
					(mid 445.208259 -196.226577)
					(end 445.172338 -196.211698)
				)
				(arc
					(start 443.772798 -196.211698)
					(mid 443.736877 -196.226577)
					(end 443.721998 -196.262498)
				)
			)
		)
	)
	(zone
		(layers "In1.Cu" "In2.Cu")
		(hatch none 0.5)
		(connect_pads
			(clearance 0)
		)
		(min_thickness 0.25)
		(keepout
			(tracks not_allowed)
			(vias allowed)
			(pads allowed)
			(copperpour not_allowed)
			(footprints allowed)
		)
		(placement
			(enabled no)
			(sheetname "")
		)
		(fill yes
			(thermal_gap 0.5)
			(thermal_bridge_width 0.5)
			(island_removal_mode 0)
		)
		(polygon
			(pts
				(arc
					(start 417.646866 -309.721504)
					(mid 417.661745 -309.757425)
					(end 417.697666 -309.772304)
				)
				(arc
					(start 419.097206 -309.772304)
					(mid 419.133127 -309.757425)
					(end 419.148006 -309.721504)
				)
				(arc
					(start 419.148006 -309.312564)
					(mid 419.133127 -309.276643)
					(end 419.097206 -309.261764)
				)
				(arc
					(start 417.697666 -309.261764)
					(mid 417.661745 -309.276643)
					(end 417.646866 -309.312564)
				)
			)
		)
	)
	(zone
		(layers "In1.Cu" "In2.Cu")
		(hatch none 0.5)
		(connect_pads
			(clearance 0)
		)
		(min_thickness 0.25)
		(keepout
			(tracks not_allowed)
			(vias allowed)
			(pads allowed)
			(copperpour not_allowed)
			(footprints allowed)
		)
		(placement
			(enabled no)
			(sheetname "")
		)
		(fill yes
			(thermal_gap 0.5)
			(thermal_bridge_width 0.5)
			(island_removal_mode 0)
		)
		(polygon
			(pts
				(arc
					(start 300.592998 -206.021432)
					(mid 300.607877 -206.057353)
					(end 300.643798 -206.072232)
				)
				(arc
					(start 302.043338 -206.072232)
					(mid 302.079259 -206.057353)
					(end 302.094138 -206.021432)
				)
				(arc
					(start 302.094138 -205.612492)
					(mid 302.079259 -205.576571)
					(end 302.043338 -205.561692)
				)
				(arc
					(start 300.643798 -205.561692)
					(mid 300.607877 -205.576571)
					(end 300.592998 -205.612492)
				)
			)
		)
	)
	(zone
		(layers "In1.Cu" "In2.Cu")
		(hatch none 0.5)
		(connect_pads
			(clearance 0)
		)
		(min_thickness 0.25)
		(keepout
			(tracks not_allowed)
			(vias allowed)
			(pads allowed)
			(copperpour not_allowed)
			(footprints allowed)
		)
		(placement
			(enabled no)
			(sheetname "")
		)
		(fill yes
			(thermal_gap 0.5)
			(thermal_bridge_width 0.5)
			(island_removal_mode 0)
		)
		(polygon
			(pts
				(arc
					(start 169.706798 -197.521322)
					(mid 169.721677 -197.557243)
					(end 169.757598 -197.572122)
				)
				(arc
					(start 171.157138 -197.572122)
					(mid 171.193059 -197.557243)
					(end 171.207938 -197.521322)
				)
				(arc
					(start 171.207938 -197.112382)
					(mid 171.193059 -197.076461)
					(end 171.157138 -197.061582)
				)
				(arc
					(start 169.757598 -197.061582)
					(mid 169.721677 -197.076461)
					(end 169.706798 -197.112382)
				)
			)
		)
	)
	(zone
		(layers "In1.Cu" "In2.Cu")
		(hatch none 0.5)
		(connect_pads
			(clearance 0)
		)
		(min_thickness 0.25)
		(keepout
			(tracks not_allowed)
			(vias allowed)
			(pads allowed)
			(copperpour not_allowed)
			(footprints allowed)
		)
		(placement
			(enabled no)
			(sheetname "")
		)
		(fill yes
			(thermal_gap 0.5)
			(thermal_bridge_width 0.5)
			(island_removal_mode 0)
		)
		(polygon
			(pts
				(arc
					(start 180.69433 -286.771334)
					(mid 180.709209 -286.807255)
					(end 180.74513 -286.822134)
				)
				(arc
					(start 182.14467 -286.822134)
					(mid 182.180591 -286.807255)
					(end 182.19547 -286.771334)
				)
				(arc
					(start 182.19547 -286.362394)
					(mid 182.180591 -286.326473)
					(end 182.14467 -286.311594)
				)
				(arc
					(start 180.74513 -286.311594)
					(mid 180.709209 -286.326473)
					(end 180.69433 -286.362394)
				)
			)
		)
	)
	(zone
		(layers "In1.Cu" "In2.Cu")
		(hatch none 0.5)
		(connect_pads
			(clearance 0)
		)
		(min_thickness 0.25)
		(keepout
			(tracks not_allowed)
			(vias allowed)
			(pads allowed)
			(copperpour not_allowed)
			(footprints allowed)
		)
		(placement
			(enabled no)
			(sheetname "")
		)
		(fill yes
			(thermal_gap 0.5)
			(thermal_bridge_width 0.5)
			(island_removal_mode 0)
		)
		(polygon
			(pts
				(arc
					(start 447.822066 -311.421526)
					(mid 447.836945 -311.457447)
					(end 447.872866 -311.472326)
				)
				(arc
					(start 449.272406 -311.472326)
					(mid 449.308327 -311.457447)
					(end 449.323206 -311.421526)
				)
				(arc
					(start 449.323206 -311.012586)
					(mid 449.308327 -310.976665)
					(end 449.272406 -310.961786)
				)
				(arc
					(start 447.872866 -310.961786)
					(mid 447.836945 -310.976665)
					(end 447.822066 -311.012586)
				)
			)
		)
	)
	(zone
		(layers "In1.Cu" "In2.Cu")
		(hatch none 0.5)
		(connect_pads
			(clearance 0)
		)
		(min_thickness 0.25)
		(keepout
			(tracks not_allowed)
			(vias allowed)
			(pads allowed)
			(copperpour not_allowed)
			(footprints allowed)
		)
		(placement
			(enabled no)
			(sheetname "")
		)
		(fill yes
			(thermal_gap 0.5)
			(thermal_bridge_width 0.5)
			(island_removal_mode 0)
		)
		(polygon
			(pts
				(arc
					(start 289.605466 -206.871316)
					(mid 289.620345 -206.907237)
					(end 289.656266 -206.922116)
				)
				(arc
					(start 291.055806 -206.922116)
					(mid 291.091727 -206.907237)
					(end 291.106606 -206.871316)
				)
				(arc
					(start 291.106606 -206.462376)
					(mid 291.091727 -206.426455)
					(end 291.055806 -206.411576)
				)
				(arc
					(start 289.656266 -206.411576)
					(mid 289.620345 -206.426455)
					(end 289.605466 -206.462376)
				)
			)
		)
	)
	(zone
		(layers "In1.Cu" "In2.Cu")
		(hatch none 0.5)
		(connect_pads
			(clearance 0)
		)
		(min_thickness 0.25)
		(keepout
			(tracks not_allowed)
			(vias allowed)
			(pads allowed)
			(copperpour not_allowed)
			(footprints allowed)
		)
		(placement
			(enabled no)
			(sheetname "")
		)
		(fill yes
			(thermal_gap 0.5)
			(thermal_bridge_width 0.5)
			(island_removal_mode 0)
		)
		(polygon
			(pts
				(arc
					(start 169.706798 -313.971432)
					(mid 169.721677 -314.007353)
					(end 169.757598 -314.022232)
				)
				(arc
					(start 171.157138 -314.022232)
					(mid 171.193059 -314.007353)
					(end 171.207938 -313.971432)
				)
				(arc
					(start 171.207938 -313.562492)
					(mid 171.193059 -313.526571)
					(end 171.157138 -313.511692)
				)
				(arc
					(start 169.757598 -313.511692)
					(mid 169.721677 -313.526571)
					(end 169.706798 -313.562492)
				)
			)
		)
	)
	(zone
		(layers "In1.Cu" "In2.Cu")
		(hatch none 0.5)
		(connect_pads
			(clearance 0)
		)
		(min_thickness 0.25)
		(keepout
			(tracks not_allowed)
			(vias allowed)
			(pads allowed)
			(copperpour not_allowed)
			(footprints allowed)
		)
		(placement
			(enabled no)
			(sheetname "")
		)
		(fill yes
			(thermal_gap 0.5)
			(thermal_bridge_width 0.5)
			(island_removal_mode 0)
		)
		(polygon
			(pts
				(arc
					(start 203.32573 -232.371392)
					(mid 203.340609 -232.407313)
					(end 203.37653 -232.422192)
				)
				(arc
					(start 204.77607 -232.422192)
					(mid 204.811991 -232.407313)
					(end 204.82687 -232.371392)
				)
				(arc
					(start 204.82687 -231.962452)
					(mid 204.811991 -231.926531)
					(end 204.77607 -231.911652)
				)
				(arc
					(start 203.37653 -231.911652)
					(mid 203.340609 -231.926531)
					(end 203.32573 -231.962452)
				)
			)
		)
	)
	(zone
		(layers "In1.Cu" "In2.Cu")
		(hatch none 0.5)
		(connect_pads
			(clearance 0)
		)
		(min_thickness 0.25)
		(keepout
			(tracks not_allowed)
			(vias allowed)
			(pads allowed)
			(copperpour not_allowed)
			(footprints allowed)
		)
		(placement
			(enabled no)
			(sheetname "")
		)
		(fill yes
			(thermal_gap 0.5)
			(thermal_bridge_width 0.5)
			(island_removal_mode 0)
		)
		(polygon
			(pts
				(arc
					(start 210.86953 -310.571388)
					(mid 210.884409 -310.607309)
					(end 210.92033 -310.622188)
				)
				(arc
					(start 212.31987 -310.622188)
					(mid 212.355791 -310.607309)
					(end 212.37067 -310.571388)
				)
				(arc
					(start 212.37067 -310.162448)
					(mid 212.355791 -310.126527)
					(end 212.31987 -310.111648)
				)
				(arc
					(start 210.92033 -310.111648)
					(mid 210.884409 -310.126527)
					(end 210.86953 -310.162448)
				)
			)
		)
	)
	(zone
		(layers "In1.Cu" "In2.Cu")
		(hatch none 0.5)
		(connect_pads
			(clearance 0)
		)
		(min_thickness 0.25)
		(keepout
			(tracks not_allowed)
			(vias allowed)
			(pads allowed)
			(copperpour not_allowed)
			(footprints allowed)
		)
		(placement
			(enabled no)
			(sheetname "")
		)
		(fill yes
			(thermal_gap 0.5)
			(thermal_bridge_width 0.5)
			(island_removal_mode 0)
		)
		(polygon
			(pts
				(arc
					(start 455.365866 -300.37151)
					(mid 455.380745 -300.407431)
					(end 455.416666 -300.42231)
				)
				(arc
					(start 456.816206 -300.42231)
					(mid 456.852127 -300.407431)
					(end 456.867006 -300.37151)
				)
				(arc
					(start 456.867006 -299.96257)
					(mid 456.852127 -299.926649)
					(end 456.816206 -299.91177)
				)
				(arc
					(start 455.416666 -299.91177)
					(mid 455.380745 -299.926649)
					(end 455.365866 -299.96257)
				)
			)
		)
	)
	(zone
		(layers "In1.Cu" "In2.Cu")
		(hatch none 0.5)
		(connect_pads
			(clearance 0)
		)
		(min_thickness 0.25)
		(keepout
			(tracks not_allowed)
			(vias allowed)
			(pads allowed)
			(copperpour not_allowed)
			(footprints allowed)
		)
		(placement
			(enabled no)
			(sheetname "")
		)
		(fill yes
			(thermal_gap 0.5)
			(thermal_bridge_width 0.5)
			(island_removal_mode 0)
		)
		(polygon
			(pts
				(arc
					(start 285.505398 -217.071448)
					(mid 285.520277 -217.107369)
					(end 285.556198 -217.122248)
				)
				(arc
					(start 286.955738 -217.122248)
					(mid 286.991659 -217.107369)
					(end 287.006538 -217.071448)
				)
				(arc
					(start 287.006538 -216.662508)
					(mid 286.991659 -216.626587)
					(end 286.955738 -216.611708)
				)
				(arc
					(start 285.556198 -216.611708)
					(mid 285.520277 -216.626587)
					(end 285.505398 -216.662508)
				)
			)
		)
	)
	(zone
		(layers "In1.Cu" "In2.Cu")
		(hatch none 0.5)
		(connect_pads
			(clearance 0)
		)
		(min_thickness 0.25)
		(keepout
			(tracks not_allowed)
			(vias allowed)
			(pads allowed)
			(copperpour not_allowed)
			(footprints allowed)
		)
		(placement
			(enabled no)
			(sheetname "")
		)
		(fill yes
			(thermal_gap 0.5)
			(thermal_bridge_width 0.5)
			(island_removal_mode 0)
		)
		(polygon
			(pts
				(arc
					(start 428.634398 -259.57149)
					(mid 428.649277 -259.607411)
					(end 428.685198 -259.62229)
				)
				(arc
					(start 430.084738 -259.62229)
					(mid 430.120659 -259.607411)
					(end 430.135538 -259.57149)
				)
				(arc
					(start 430.135538 -259.16255)
					(mid 430.120659 -259.126629)
					(end 430.084738 -259.11175)
				)
				(arc
					(start 428.685198 -259.11175)
					(mid 428.649277 -259.126629)
					(end 428.634398 -259.16255)
				)
			)
		)
	)
	(zone
		(layers "In1.Cu" "In2.Cu")
		(hatch none 0.5)
		(connect_pads
			(clearance 0)
		)
		(min_thickness 0.25)
		(keepout
			(tracks not_allowed)
			(vias allowed)
			(pads allowed)
			(copperpour not_allowed)
			(footprints allowed)
		)
		(placement
			(enabled no)
			(sheetname "")
		)
		(fill yes
			(thermal_gap 0.5)
			(thermal_bridge_width 0.5)
			(island_removal_mode 0)
		)
		(polygon
			(pts
				(arc
					(start 304.693066 -240.871502)
					(mid 304.707945 -240.907423)
					(end 304.743866 -240.922302)
				)
				(arc
					(start 306.143406 -240.922302)
					(mid 306.179327 -240.907423)
					(end 306.194206 -240.871502)
				)
				(arc
					(start 306.194206 -240.462562)
					(mid 306.179327 -240.426641)
					(end 306.143406 -240.411762)
				)
				(arc
					(start 304.743866 -240.411762)
					(mid 304.707945 -240.426641)
					(end 304.693066 -240.462562)
				)
			)
		)
	)
	(zone
		(layers "In1.Cu" "In2.Cu")
		(hatch none 0.5)
		(connect_pads
			(clearance 0)
		)
		(min_thickness 0.25)
		(keepout
			(tracks not_allowed)
			(vias allowed)
			(pads allowed)
			(copperpour not_allowed)
			(footprints allowed)
		)
		(placement
			(enabled no)
			(sheetname "")
		)
		(fill yes
			(thermal_gap 0.5)
			(thermal_bridge_width 0.5)
			(island_removal_mode 0)
		)
		(polygon
			(pts
				(arc
					(start 410.103066 -222.171514)
					(mid 410.117945 -222.207435)
					(end 410.153866 -222.222314)
				)
				(arc
					(start 411.553406 -222.222314)
					(mid 411.589327 -222.207435)
					(end 411.604206 -222.171514)
				)
				(arc
					(start 411.604206 -221.762574)
					(mid 411.589327 -221.726653)
					(end 411.553406 -221.711774)
				)
				(arc
					(start 410.153866 -221.711774)
					(mid 410.117945 -221.726653)
					(end 410.103066 -221.762574)
				)
			)
		)
	)
	(zone
		(layers "In1.Cu" "In2.Cu")
		(hatch none 0.5)
		(connect_pads
			(clearance 0)
		)
		(min_thickness 0.25)
		(keepout
			(tracks not_allowed)
			(vias allowed)
			(pads allowed)
			(copperpour not_allowed)
			(footprints allowed)
		)
		(placement
			(enabled no)
			(sheetname "")
		)
		(fill yes
			(thermal_gap 0.5)
			(thermal_bridge_width 0.5)
			(island_removal_mode 0)
		)
		(polygon
			(pts
				(arc
					(start 410.103066 -248.521474)
					(mid 410.117945 -248.557395)
					(end 410.153866 -248.572274)
				)
				(arc
					(start 411.553406 -248.572274)
					(mid 411.589327 -248.557395)
					(end 411.604206 -248.521474)
				)
				(arc
					(start 411.604206 -248.112534)
					(mid 411.589327 -248.076613)
					(end 411.553406 -248.061734)
				)
				(arc
					(start 410.153866 -248.061734)
					(mid 410.117945 -248.076613)
					(end 410.103066 -248.112534)
				)
			)
		)
	)
	(zone
		(layers "In1.Cu" "In2.Cu")
		(hatch none 0.5)
		(connect_pads
			(clearance 0)
		)
		(min_thickness 0.25)
		(keepout
			(tracks not_allowed)
			(vias allowed)
			(pads allowed)
			(copperpour not_allowed)
			(footprints allowed)
		)
		(placement
			(enabled no)
			(sheetname "")
		)
		(fill yes
			(thermal_gap 0.5)
			(thermal_bridge_width 0.5)
			(island_removal_mode 0)
		)
		(polygon
			(pts
				(arc
					(start 14.93393 -273.171412)
					(mid 14.948809 -273.207333)
					(end 14.98473 -273.222212)
				)
				(arc
					(start 16.38427 -273.222212)
					(mid 16.420191 -273.207333)
					(end 16.43507 -273.171412)
				)
				(arc
					(start 16.43507 -272.762472)
					(mid 16.420191 -272.726551)
					(end 16.38427 -272.711672)
				)
				(arc
					(start 14.98473 -272.711672)
					(mid 14.948809 -272.726551)
					(end 14.93393 -272.762472)
				)
			)
		)
	)
	(zone
		(layers "In1.Cu" "In2.Cu")
		(hatch none 0.5)
		(connect_pads
			(clearance 0)
		)
		(min_thickness 0.25)
		(keepout
			(tracks not_allowed)
			(vias allowed)
			(pads allowed)
			(copperpour not_allowed)
			(footprints allowed)
		)
		(placement
			(enabled no)
			(sheetname "")
		)
		(fill yes
			(thermal_gap 0.5)
			(thermal_bridge_width 0.5)
			(island_removal_mode 0)
		)
		(polygon
			(pts
				(arc
					(start 165.60673 -207.721454)
					(mid 165.621609 -207.757375)
					(end 165.65753 -207.772254)
				)
				(arc
					(start 167.05707 -207.772254)
					(mid 167.092991 -207.757375)
					(end 167.10787 -207.721454)
				)
				(arc
					(start 167.10787 -207.312514)
					(mid 167.092991 -207.276593)
					(end 167.05707 -207.261714)
				)
				(arc
					(start 165.65753 -207.261714)
					(mid 165.621609 -207.276593)
					(end 165.60673 -207.312514)
				)
			)
		)
	)
	(zone
		(layers "In1.Cu" "In2.Cu")
		(hatch none 0.5)
		(connect_pads
			(clearance 0)
		)
		(min_thickness 0.25)
		(keepout
			(tracks not_allowed)
			(vias allowed)
			(pads allowed)
			(copperpour not_allowed)
			(footprints allowed)
		)
		(placement
			(enabled no)
			(sheetname "")
		)
		(fill yes
			(thermal_gap 0.5)
			(thermal_bridge_width 0.5)
			(island_removal_mode 0)
		)
		(polygon
			(pts
				(arc
					(start 428.634398 -262.971534)
					(mid 428.649277 -263.007455)
					(end 428.685198 -263.022334)
				)
				(arc
					(start 430.084738 -263.022334)
					(mid 430.120659 -263.007455)
					(end 430.135538 -262.971534)
				)
				(arc
					(start 430.135538 -262.562594)
					(mid 430.120659 -262.526673)
					(end 430.084738 -262.511794)
				)
				(arc
					(start 428.685198 -262.511794)
					(mid 428.649277 -262.526673)
					(end 428.634398 -262.562594)
				)
			)
		)
	)
	(zone
		(layers "In1.Cu" "In2.Cu")
		(hatch none 0.5)
		(connect_pads
			(clearance 0)
		)
		(min_thickness 0.25)
		(keepout
			(tracks not_allowed)
			(vias allowed)
			(pads allowed)
			(copperpour not_allowed)
			(footprints allowed)
		)
		(placement
			(enabled no)
			(sheetname "")
		)
		(fill yes
			(thermal_gap 0.5)
			(thermal_bridge_width 0.5)
			(island_removal_mode 0)
		)
		(polygon
			(pts
				(arc
					(start 458.809598 -204.32141)
					(mid 458.824477 -204.357331)
					(end 458.860398 -204.37221)
				)
				(arc
					(start 460.259938 -204.37221)
					(mid 460.295859 -204.357331)
					(end 460.310738 -204.32141)
				)
				(arc
					(start 460.310738 -203.91247)
					(mid 460.295859 -203.876549)
					(end 460.259938 -203.86167)
				)
				(arc
					(start 458.860398 -203.86167)
					(mid 458.824477 -203.876549)
					(end 458.809598 -203.91247)
				)
			)
		)
	)
	(zone
		(layers "In1.Cu" "In2.Cu")
		(hatch none 0.5)
		(connect_pads
			(clearance 0)
		)
		(min_thickness 0.25)
		(keepout
			(tracks not_allowed)
			(vias allowed)
			(pads allowed)
			(copperpour not_allowed)
			(footprints allowed)
		)
		(placement
			(enabled no)
			(sheetname "")
		)
		(fill yes
			(thermal_gap 0.5)
			(thermal_bridge_width 0.5)
			(island_removal_mode 0)
		)
		(polygon
			(pts
				(arc
					(start 300.592998 -296.121328)
					(mid 300.607877 -296.157249)
					(end 300.643798 -296.172128)
				)
				(arc
					(start 302.043338 -296.172128)
					(mid 302.079259 -296.157249)
					(end 302.094138 -296.121328)
				)
				(arc
					(start 302.094138 -295.712388)
					(mid 302.079259 -295.676467)
					(end 302.043338 -295.661588)
				)
				(arc
					(start 300.643798 -295.661588)
					(mid 300.607877 -295.676467)
					(end 300.592998 -295.712388)
				)
			)
		)
	)
	(zone
		(layers "In1.Cu" "In2.Cu")
		(hatch none 0.5)
		(connect_pads
			(clearance 0)
		)
		(min_thickness 0.25)
		(keepout
			(tracks not_allowed)
			(vias allowed)
			(pads allowed)
			(copperpour not_allowed)
			(footprints allowed)
		)
		(placement
			(enabled no)
			(sheetname "")
		)
		(fill yes
			(thermal_gap 0.5)
			(thermal_bridge_width 0.5)
			(island_removal_mode 0)
		)
		(polygon
			(pts
				(arc
					(start 406.002998 -218.77147)
					(mid 406.017877 -218.807391)
					(end 406.053798 -218.82227)
				)
				(arc
					(start 407.453338 -218.82227)
					(mid 407.489259 -218.807391)
					(end 407.504138 -218.77147)
				)
				(arc
					(start 407.504138 -218.36253)
					(mid 407.489259 -218.326609)
					(end 407.453338 -218.31173)
				)
				(arc
					(start 406.053798 -218.31173)
					(mid 406.017877 -218.326609)
					(end 406.002998 -218.36253)
				)
			)
		)
	)
	(zone
		(layers "In1.Cu" "In2.Cu")
		(hatch none 0.5)
		(connect_pads
			(clearance 0)
		)
		(min_thickness 0.25)
		(keepout
			(tracks not_allowed)
			(vias allowed)
			(pads allowed)
			(copperpour not_allowed)
			(footprints allowed)
		)
		(placement
			(enabled no)
			(sheetname "")
		)
		(fill yes
			(thermal_gap 0.5)
			(thermal_bridge_width 0.5)
			(island_removal_mode 0)
		)
		(polygon
			(pts
				(arc
					(start 262.873998 -314.821316)
					(mid 262.888877 -314.857237)
					(end 262.924798 -314.872116)
				)
				(arc
					(start 264.324338 -314.872116)
					(mid 264.360259 -314.857237)
					(end 264.375138 -314.821316)
				)
				(arc
					(start 264.375138 -314.412376)
					(mid 264.360259 -314.376455)
					(end 264.324338 -314.361576)
				)
				(arc
					(start 262.924798 -314.361576)
					(mid 262.888877 -314.376455)
					(end 262.873998 -314.412376)
				)
			)
		)
	)
	(zone
		(layers "In1.Cu" "In2.Cu")
		(hatch none 0.5)
		(connect_pads
			(clearance 0)
		)
		(min_thickness 0.25)
		(keepout
			(tracks not_allowed)
			(vias allowed)
			(pads allowed)
			(copperpour not_allowed)
			(footprints allowed)
		)
		(placement
			(enabled no)
			(sheetname "")
		)
		(fill yes
			(thermal_gap 0.5)
			(thermal_bridge_width 0.5)
			(island_removal_mode 0)
		)
		(polygon
			(pts
				(arc
					(start 425.190666 -285.92145)
					(mid 425.205545 -285.957371)
					(end 425.241466 -285.97225)
				)
				(arc
					(start 426.641006 -285.97225)
					(mid 426.676927 -285.957371)
					(end 426.691806 -285.92145)
				)
				(arc
					(start 426.691806 -285.51251)
					(mid 426.676927 -285.476589)
					(end 426.641006 -285.46171)
				)
				(arc
					(start 425.241466 -285.46171)
					(mid 425.205545 -285.476589)
					(end 425.190666 -285.51251)
				)
			)
		)
	)
	(zone
		(layers "In1.Cu" "In2.Cu")
		(hatch none 0.5)
		(connect_pads
			(clearance 0)
		)
		(min_thickness 0.25)
		(keepout
			(tracks not_allowed)
			(vias allowed)
			(pads allowed)
			(copperpour not_allowed)
			(footprints allowed)
		)
		(placement
			(enabled no)
			(sheetname "")
		)
		(fill yes
			(thermal_gap 0.5)
			(thermal_bridge_width 0.5)
			(island_removal_mode 0)
		)
		(polygon
			(pts
				(arc
					(start 45.10913 -213.671404)
					(mid 45.124009 -213.707325)
					(end 45.15993 -213.722204)
				)
				(arc
					(start 46.55947 -213.722204)
					(mid 46.595391 -213.707325)
					(end 46.61027 -213.671404)
				)
				(arc
					(start 46.61027 -213.262464)
					(mid 46.595391 -213.226543)
					(end 46.55947 -213.211664)
				)
				(arc
					(start 45.15993 -213.211664)
					(mid 45.124009 -213.226543)
					(end 45.10913 -213.262464)
				)
			)
		)
	)
	(zone
		(layers "In1.Cu" "In2.Cu")
		(hatch none 0.5)
		(connect_pads
			(clearance 0)
		)
		(min_thickness 0.25)
		(keepout
			(tracks not_allowed)
			(vias allowed)
			(pads allowed)
			(copperpour not_allowed)
			(footprints allowed)
		)
		(placement
			(enabled no)
			(sheetname "")
		)
		(fill yes
			(thermal_gap 0.5)
			(thermal_bridge_width 0.5)
			(island_removal_mode 0)
		)
		(polygon
			(pts
				(arc
					(start 436.178198 -243.421408)
					(mid 436.193077 -243.457329)
					(end 436.228998 -243.472208)
				)
				(arc
					(start 437.628538 -243.472208)
					(mid 437.664459 -243.457329)
					(end 437.679338 -243.421408)
				)
				(arc
					(start 437.679338 -243.012468)
					(mid 437.664459 -242.976547)
					(end 437.628538 -242.961668)
				)
				(arc
					(start 436.228998 -242.961668)
					(mid 436.193077 -242.976547)
					(end 436.178198 -243.012468)
				)
			)
		)
	)
	(zone
		(layers "In1.Cu" "In2.Cu")
		(hatch none 0.5)
		(connect_pads
			(clearance 0)
		)
		(min_thickness 0.25)
		(keepout
			(tracks not_allowed)
			(vias allowed)
			(pads allowed)
			(copperpour not_allowed)
			(footprints allowed)
		)
		(placement
			(enabled no)
			(sheetname "")
		)
		(fill yes
			(thermal_gap 0.5)
			(thermal_bridge_width 0.5)
			(island_removal_mode 0)
		)
		(polygon
			(pts
				(arc
					(start 443.721998 -204.32141)
					(mid 443.736877 -204.357331)
					(end 443.772798 -204.37221)
				)
				(arc
					(start 445.172338 -204.37221)
					(mid 445.208259 -204.357331)
					(end 445.223138 -204.32141)
				)
				(arc
					(start 445.223138 -203.91247)
					(mid 445.208259 -203.876549)
					(end 445.172338 -203.86167)
				)
				(arc
					(start 443.772798 -203.86167)
					(mid 443.736877 -203.876549)
					(end 443.721998 -203.91247)
				)
			)
		)
	)
	(zone
		(layers "In1.Cu" "In2.Cu")
		(hatch none 0.5)
		(connect_pads
			(clearance 0)
		)
		(min_thickness 0.25)
		(keepout
			(tracks not_allowed)
			(vias allowed)
			(pads allowed)
			(copperpour not_allowed)
			(footprints allowed)
		)
		(placement
			(enabled no)
			(sheetname "")
		)
		(fill yes
			(thermal_gap 0.5)
			(thermal_bridge_width 0.5)
			(island_removal_mode 0)
		)
		(polygon
			(pts
				(arc
					(start 455.365866 -265.52144)
					(mid 455.380745 -265.557361)
					(end 455.416666 -265.57224)
				)
				(arc
					(start 456.816206 -265.57224)
					(mid 456.852127 -265.557361)
					(end 456.867006 -265.52144)
				)
				(arc
					(start 456.867006 -265.1125)
					(mid 456.852127 -265.076579)
					(end 456.816206 -265.0617)
				)
				(arc
					(start 455.416666 -265.0617)
					(mid 455.380745 -265.076579)
					(end 455.365866 -265.1125)
				)
			)
		)
	)
	(zone
		(layers "In1.Cu" "In2.Cu")
		(hatch none 0.5)
		(connect_pads
			(clearance 0)
		)
		(min_thickness 0.25)
		(keepout
			(tracks not_allowed)
			(vias allowed)
			(pads allowed)
			(copperpour not_allowed)
			(footprints allowed)
		)
		(placement
			(enabled no)
			(sheetname "")
		)
		(fill yes
			(thermal_gap 0.5)
			(thermal_bridge_width 0.5)
			(island_removal_mode 0)
		)
		(polygon
			(pts
				(arc
					(start 421.090598 -302.921416)
					(mid 421.105477 -302.957337)
					(end 421.141398 -302.972216)
				)
				(arc
					(start 422.540938 -302.972216)
					(mid 422.576859 -302.957337)
					(end 422.591738 -302.921416)
				)
				(arc
					(start 422.591738 -302.512476)
					(mid 422.576859 -302.476555)
					(end 422.540938 -302.461676)
				)
				(arc
					(start 421.141398 -302.461676)
					(mid 421.105477 -302.476555)
					(end 421.090598 -302.512476)
				)
			)
		)
	)
	(zone
		(layers "In1.Cu" "In2.Cu")
		(hatch none 0.5)
		(connect_pads
			(clearance 0)
		)
		(min_thickness 0.25)
		(keepout
			(tracks not_allowed)
			(vias allowed)
			(pads allowed)
			(copperpour not_allowed)
			(footprints allowed)
		)
		(placement
			(enabled no)
			(sheetname "")
		)
		(fill yes
			(thermal_gap 0.5)
			(thermal_bridge_width 0.5)
			(island_removal_mode 0)
		)
		(polygon
			(pts
				(arc
					(start 410.103066 -289.321494)
					(mid 410.117945 -289.357415)
					(end 410.153866 -289.372294)
				)
				(arc
					(start 411.553406 -289.372294)
					(mid 411.589327 -289.357415)
					(end 411.604206 -289.321494)
				)
				(arc
					(start 411.604206 -288.912554)
					(mid 411.589327 -288.876633)
					(end 411.553406 -288.861754)
				)
				(arc
					(start 410.153866 -288.861754)
					(mid 410.117945 -288.876633)
					(end 410.103066 -288.912554)
				)
			)
		)
	)
	(zone
		(layers "In1.Cu" "In2.Cu")
		(hatch none 0.5)
		(connect_pads
			(clearance 0)
		)
		(min_thickness 0.25)
		(keepout
			(tracks not_allowed)
			(vias allowed)
			(pads allowed)
			(copperpour not_allowed)
			(footprints allowed)
		)
		(placement
			(enabled no)
			(sheetname "")
		)
		(fill yes
			(thermal_gap 0.5)
			(thermal_bridge_width 0.5)
			(island_removal_mode 0)
		)
		(polygon
			(pts
				(arc
					(start 425.190666 -274.02155)
					(mid 425.205545 -274.057471)
					(end 425.241466 -274.07235)
				)
				(arc
					(start 426.641006 -274.07235)
					(mid 426.676927 -274.057471)
					(end 426.691806 -274.02155)
				)
				(arc
					(start 426.691806 -273.61261)
					(mid 426.676927 -273.576689)
					(end 426.641006 -273.56181)
				)
				(arc
					(start 425.241466 -273.56181)
					(mid 425.205545 -273.576689)
					(end 425.190666 -273.61261)
				)
			)
		)
	)
	(zone
		(layers "In1.Cu" "In2.Cu")
		(hatch none 0.5)
		(connect_pads
			(clearance 0)
		)
		(min_thickness 0.25)
		(keepout
			(tracks not_allowed)
			(vias allowed)
			(pads allowed)
			(copperpour not_allowed)
			(footprints allowed)
		)
		(placement
			(enabled no)
			(sheetname "")
		)
		(fill yes
			(thermal_gap 0.5)
			(thermal_bridge_width 0.5)
			(island_removal_mode 0)
		)
		(polygon
			(pts
				(arc
					(start 184.794398 -250.221496)
					(mid 184.809277 -250.257417)
					(end 184.845198 -250.272296)
				)
				(arc
					(start 186.244738 -250.272296)
					(mid 186.280659 -250.257417)
					(end 186.295538 -250.221496)
				)
				(arc
					(start 186.295538 -249.812556)
					(mid 186.280659 -249.776635)
					(end 186.244738 -249.761756)
				)
				(arc
					(start 184.845198 -249.761756)
					(mid 184.809277 -249.776635)
					(end 184.794398 -249.812556)
				)
			)
		)
	)
	(zone
		(layers "In1.Cu" "In2.Cu")
		(hatch none 0.5)
		(connect_pads
			(clearance 0)
		)
		(min_thickness 0.25)
		(keepout
			(tracks not_allowed)
			(vias allowed)
			(pads allowed)
			(copperpour not_allowed)
			(footprints allowed)
		)
		(placement
			(enabled no)
			(sheetname "")
		)
		(fill yes
			(thermal_gap 0.5)
			(thermal_bridge_width 0.5)
			(island_removal_mode 0)
		)
		(polygon
			(pts
				(arc
					(start 162.162998 -284.221428)
					(mid 162.177877 -284.257349)
					(end 162.213798 -284.272228)
				)
				(arc
					(start 163.613338 -284.272228)
					(mid 163.649259 -284.257349)
					(end 163.664138 -284.221428)
				)
				(arc
					(start 163.664138 -283.812488)
					(mid 163.649259 -283.776567)
					(end 163.613338 -283.761688)
				)
				(arc
					(start 162.213798 -283.761688)
					(mid 162.177877 -283.776567)
					(end 162.162998 -283.812488)
				)
			)
		)
	)
	(zone
		(layers "In1.Cu" "In2.Cu")
		(hatch none 0.5)
		(connect_pads
			(clearance 0)
		)
		(min_thickness 0.25)
		(keepout
			(tracks not_allowed)
			(vias allowed)
			(pads allowed)
			(copperpour not_allowed)
			(footprints allowed)
		)
		(placement
			(enabled no)
			(sheetname "")
		)
		(fill yes
			(thermal_gap 0.5)
			(thermal_bridge_width 0.5)
			(island_removal_mode 0)
		)
		(polygon
			(pts
				(arc
					(start 428.634398 -226.421442)
					(mid 428.649277 -226.457363)
					(end 428.685198 -226.472242)
				)
				(arc
					(start 430.084738 -226.472242)
					(mid 430.120659 -226.457363)
					(end 430.135538 -226.421442)
				)
				(arc
					(start 430.135538 -226.012502)
					(mid 430.120659 -225.976581)
					(end 430.084738 -225.961702)
				)
				(arc
					(start 428.685198 -225.961702)
					(mid 428.649277 -225.976581)
					(end 428.634398 -226.012502)
				)
			)
		)
	)
	(zone
		(layers "In1.Cu" "In2.Cu")
		(hatch none 0.5)
		(connect_pads
			(clearance 0)
		)
		(min_thickness 0.25)
		(keepout
			(tracks not_allowed)
			(vias allowed)
			(pads allowed)
			(copperpour not_allowed)
			(footprints allowed)
		)
		(placement
			(enabled no)
			(sheetname "")
		)
		(fill yes
			(thermal_gap 0.5)
			(thermal_bridge_width 0.5)
			(island_removal_mode 0)
		)
		(polygon
			(pts
				(arc
					(start 304.693066 -289.321494)
					(mid 304.707945 -289.357415)
					(end 304.743866 -289.372294)
				)
				(arc
					(start 306.143406 -289.372294)
					(mid 306.179327 -289.357415)
					(end 306.194206 -289.321494)
				)
				(arc
					(start 306.194206 -288.912554)
					(mid 306.179327 -288.876633)
					(end 306.143406 -288.861754)
				)
				(arc
					(start 304.743866 -288.861754)
					(mid 304.707945 -288.876633)
					(end 304.693066 -288.912554)
				)
			)
		)
	)
	(zone
		(layers "In1.Cu" "In2.Cu")
		(hatch none 0.5)
		(connect_pads
			(clearance 0)
		)
		(min_thickness 0.25)
		(keepout
			(tracks not_allowed)
			(vias allowed)
			(pads allowed)
			(copperpour not_allowed)
			(footprints allowed)
		)
		(placement
			(enabled no)
			(sheetname "")
		)
		(fill yes
			(thermal_gap 0.5)
			(thermal_bridge_width 0.5)
			(island_removal_mode 0)
		)
		(polygon
			(pts
				(arc
					(start 14.93393 -313.121294)
					(mid 14.948809 -313.157215)
					(end 14.98473 -313.172094)
				)
				(arc
					(start 16.38427 -313.172094)
					(mid 16.420191 -313.157215)
					(end 16.43507 -313.121294)
				)
				(arc
					(start 16.43507 -312.712354)
					(mid 16.420191 -312.676433)
					(end 16.38427 -312.661554)
				)
				(arc
					(start 14.98473 -312.661554)
					(mid 14.948809 -312.676433)
					(end 14.93393 -312.712354)
				)
			)
		)
	)
	(zone
		(layers "In1.Cu" "In2.Cu")
		(hatch none 0.5)
		(connect_pads
			(clearance 0)
		)
		(min_thickness 0.25)
		(keepout
			(tracks not_allowed)
			(vias allowed)
			(pads allowed)
			(copperpour not_allowed)
			(footprints allowed)
		)
		(placement
			(enabled no)
			(sheetname "")
		)
		(fill yes
			(thermal_gap 0.5)
			(thermal_bridge_width 0.5)
			(island_removal_mode 0)
		)
		(polygon
			(pts
				(arc
					(start 312.236866 -259.57149)
					(mid 312.251745 -259.607411)
					(end 312.287666 -259.62229)
				)
				(arc
					(start 313.687206 -259.62229)
					(mid 313.723127 -259.607411)
					(end 313.738006 -259.57149)
				)
				(arc
					(start 313.738006 -259.16255)
					(mid 313.723127 -259.126629)
					(end 313.687206 -259.11175)
				)
				(arc
					(start 312.287666 -259.11175)
					(mid 312.251745 -259.126629)
					(end 312.236866 -259.16255)
				)
			)
		)
	)
	(zone
		(layers "In1.Cu" "In2.Cu")
		(hatch none 0.5)
		(connect_pads
			(clearance 0)
		)
		(min_thickness 0.25)
		(keepout
			(tracks not_allowed)
			(vias allowed)
			(pads allowed)
			(copperpour not_allowed)
			(footprints allowed)
		)
		(placement
			(enabled no)
			(sheetname "")
		)
		(fill yes
			(thermal_gap 0.5)
			(thermal_bridge_width 0.5)
			(island_removal_mode 0)
		)
		(polygon
			(pts
				(arc
					(start 22.47773 -307.171344)
					(mid 22.492609 -307.207265)
					(end 22.52853 -307.222144)
				)
				(arc
					(start 23.92807 -307.222144)
					(mid 23.963991 -307.207265)
					(end 23.97887 -307.171344)
				)
				(arc
					(start 23.97887 -306.762404)
					(mid 23.963991 -306.726483)
					(end 23.92807 -306.711604)
				)
				(arc
					(start 22.52853 -306.711604)
					(mid 22.492609 -306.726483)
					(end 22.47773 -306.762404)
				)
			)
		)
	)
	(zone
		(layers "In1.Cu" "In2.Cu")
		(hatch none 0.5)
		(connect_pads
			(clearance 0)
		)
		(min_thickness 0.25)
		(keepout
			(tracks not_allowed)
			(vias allowed)
			(pads allowed)
			(copperpour not_allowed)
			(footprints allowed)
		)
		(placement
			(enabled no)
			(sheetname "")
		)
		(fill yes
			(thermal_gap 0.5)
			(thermal_bridge_width 0.5)
			(island_removal_mode 0)
		)
		(polygon
			(pts
				(arc
					(start 262.873998 -286.771334)
					(mid 262.888877 -286.807255)
					(end 262.924798 -286.822134)
				)
				(arc
					(start 264.324338 -286.822134)
					(mid 264.360259 -286.807255)
					(end 264.375138 -286.771334)
				)
				(arc
					(start 264.375138 -286.362394)
					(mid 264.360259 -286.326473)
					(end 264.324338 -286.311594)
				)
				(arc
					(start 262.924798 -286.311594)
					(mid 262.888877 -286.326473)
					(end 262.873998 -286.362394)
				)
			)
		)
	)
	(zone
		(layers "In1.Cu" "In2.Cu")
		(hatch none 0.5)
		(connect_pads
			(clearance 0)
		)
		(min_thickness 0.25)
		(keepout
			(tracks not_allowed)
			(vias allowed)
			(pads allowed)
			(copperpour not_allowed)
			(footprints allowed)
		)
		(placement
			(enabled no)
			(sheetname "")
		)
		(fill yes
			(thermal_gap 0.5)
			(thermal_bridge_width 0.5)
			(island_removal_mode 0)
		)
		(polygon
			(pts
				(arc
					(start 455.365866 -218.77147)
					(mid 455.380745 -218.807391)
					(end 455.416666 -218.82227)
				)
				(arc
					(start 456.816206 -218.82227)
					(mid 456.852127 -218.807391)
					(end 456.867006 -218.77147)
				)
				(arc
					(start 456.867006 -218.36253)
					(mid 456.852127 -218.326609)
					(end 456.816206 -218.31173)
				)
				(arc
					(start 455.416666 -218.31173)
					(mid 455.380745 -218.326609)
					(end 455.365866 -218.36253)
				)
			)
		)
	)
	(zone
		(layers "In1.Cu" "In2.Cu")
		(hatch none 0.5)
		(connect_pads
			(clearance 0)
		)
		(min_thickness 0.25)
		(keepout
			(tracks not_allowed)
			(vias allowed)
			(pads allowed)
			(copperpour not_allowed)
			(footprints allowed)
		)
		(placement
			(enabled no)
			(sheetname "")
		)
		(fill yes
			(thermal_gap 0.5)
			(thermal_bridge_width 0.5)
			(island_removal_mode 0)
		)
		(polygon
			(pts
				(arc
					(start 282.061666 -298.671488)
					(mid 282.076545 -298.707409)
					(end 282.112466 -298.722288)
				)
				(arc
					(start 283.512006 -298.722288)
					(mid 283.547927 -298.707409)
					(end 283.562806 -298.671488)
				)
				(arc
					(start 283.562806 -298.262548)
					(mid 283.547927 -298.226627)
					(end 283.512006 -298.211748)
				)
				(arc
					(start 282.112466 -298.211748)
					(mid 282.076545 -298.226627)
					(end 282.061666 -298.262548)
				)
			)
		)
	)
	(zone
		(layers "In1.Cu" "In2.Cu")
		(hatch none 0.5)
		(connect_pads
			(clearance 0)
		)
		(min_thickness 0.25)
		(keepout
			(tracks not_allowed)
			(vias allowed)
			(pads allowed)
			(copperpour not_allowed)
			(footprints allowed)
		)
		(placement
			(enabled no)
			(sheetname "")
		)
		(fill yes
			(thermal_gap 0.5)
			(thermal_bridge_width 0.5)
			(island_removal_mode 0)
		)
		(polygon
			(pts
				(arc
					(start 312.236866 -300.37151)
					(mid 312.251745 -300.407431)
					(end 312.287666 -300.42231)
				)
				(arc
					(start 313.687206 -300.42231)
					(mid 313.723127 -300.407431)
					(end 313.738006 -300.37151)
				)
				(arc
					(start 313.738006 -299.96257)
					(mid 313.723127 -299.926649)
					(end 313.687206 -299.91177)
				)
				(arc
					(start 312.287666 -299.91177)
					(mid 312.251745 -299.926649)
					(end 312.236866 -299.96257)
				)
			)
		)
	)
	(zone
		(layers "In1.Cu" "In2.Cu")
		(hatch none 0.5)
		(connect_pads
			(clearance 0)
		)
		(min_thickness 0.25)
		(keepout
			(tracks not_allowed)
			(vias allowed)
			(pads allowed)
			(copperpour not_allowed)
			(footprints allowed)
		)
		(placement
			(enabled no)
			(sheetname "")
		)
		(fill yes
			(thermal_gap 0.5)
			(thermal_bridge_width 0.5)
			(island_removal_mode 0)
		)
		(polygon
			(pts
				(arc
					(start 52.65293 -303.7713)
					(mid 52.667809 -303.807221)
					(end 52.70373 -303.8221)
				)
				(arc
					(start 54.10327 -303.8221)
					(mid 54.139191 -303.807221)
					(end 54.15407 -303.7713)
				)
				(arc
					(start 54.15407 -303.36236)
					(mid 54.139191 -303.326439)
					(end 54.10327 -303.31156)
				)
				(arc
					(start 52.70373 -303.31156)
					(mid 52.667809 -303.326439)
					(end 52.65293 -303.36236)
				)
			)
		)
	)
	(zone
		(layers "In1.Cu" "In2.Cu")
		(hatch none 0.5)
		(connect_pads
			(clearance 0)
		)
		(min_thickness 0.25)
		(keepout
			(tracks not_allowed)
			(vias allowed)
			(pads allowed)
			(copperpour not_allowed)
			(footprints allowed)
		)
		(placement
			(enabled no)
			(sheetname "")
		)
		(fill yes
			(thermal_gap 0.5)
			(thermal_bridge_width 0.5)
			(island_removal_mode 0)
		)
		(polygon
			(pts
				(arc
					(start 52.65293 -299.521372)
					(mid 52.667809 -299.557293)
					(end 52.70373 -299.572172)
				)
				(arc
					(start 54.10327 -299.572172)
					(mid 54.139191 -299.557293)
					(end 54.15407 -299.521372)
				)
				(arc
					(start 54.15407 -299.112432)
					(mid 54.139191 -299.076511)
					(end 54.10327 -299.061632)
				)
				(arc
					(start 52.70373 -299.061632)
					(mid 52.667809 -299.076511)
					(end 52.65293 -299.112432)
				)
			)
		)
	)
	(zone
		(layers "In1.Cu" "In2.Cu")
		(hatch none 0.5)
		(connect_pads
			(clearance 0)
		)
		(min_thickness 0.25)
		(keepout
			(tracks not_allowed)
			(vias allowed)
			(pads allowed)
			(copperpour not_allowed)
			(footprints allowed)
		)
		(placement
			(enabled no)
			(sheetname "")
		)
		(fill yes
			(thermal_gap 0.5)
			(thermal_bridge_width 0.5)
			(island_removal_mode 0)
		)
		(polygon
			(pts
				(arc
					(start 165.60673 -284.221428)
					(mid 165.621609 -284.257349)
					(end 165.65753 -284.272228)
				)
				(arc
					(start 167.05707 -284.272228)
					(mid 167.092991 -284.257349)
					(end 167.10787 -284.221428)
				)
				(arc
					(start 167.10787 -283.812488)
					(mid 167.092991 -283.776567)
					(end 167.05707 -283.761688)
				)
				(arc
					(start 165.65753 -283.761688)
					(mid 165.621609 -283.776567)
					(end 165.60673 -283.812488)
				)
			)
		)
	)
	(zone
		(layers "In1.Cu" "In2.Cu")
		(hatch none 0.5)
		(connect_pads
			(clearance 0)
		)
		(min_thickness 0.25)
		(keepout
			(tracks not_allowed)
			(vias allowed)
			(pads allowed)
			(copperpour not_allowed)
			(footprints allowed)
		)
		(placement
			(enabled no)
			(sheetname "")
		)
		(fill yes
			(thermal_gap 0.5)
			(thermal_bridge_width 0.5)
			(island_removal_mode 0)
		)
		(polygon
			(pts
				(arc
					(start 458.809598 -262.971534)
					(mid 458.824477 -263.007455)
					(end 458.860398 -263.022334)
				)
				(arc
					(start 460.259938 -263.022334)
					(mid 460.295859 -263.007455)
					(end 460.310738 -262.971534)
				)
				(arc
					(start 460.310738 -262.562594)
					(mid 460.295859 -262.526673)
					(end 460.259938 -262.511794)
				)
				(arc
					(start 458.860398 -262.511794)
					(mid 458.824477 -262.526673)
					(end 458.809598 -262.562594)
				)
			)
		)
	)
	(zone
		(layers "In1.Cu" "In2.Cu")
		(hatch none 0.5)
		(connect_pads
			(clearance 0)
		)
		(min_thickness 0.25)
		(keepout
			(tracks not_allowed)
			(vias allowed)
			(pads allowed)
			(copperpour not_allowed)
			(footprints allowed)
		)
		(placement
			(enabled no)
			(sheetname "")
		)
		(fill yes
			(thermal_gap 0.5)
			(thermal_bridge_width 0.5)
			(island_removal_mode 0)
		)
		(polygon
			(pts
				(arc
					(start 440.278266 -293.571422)
					(mid 440.293145 -293.607343)
					(end 440.329066 -293.622222)
				)
				(arc
					(start 441.728606 -293.622222)
					(mid 441.764527 -293.607343)
					(end 441.779406 -293.571422)
				)
				(arc
					(start 441.779406 -293.162482)
					(mid 441.764527 -293.126561)
					(end 441.728606 -293.111682)
				)
				(arc
					(start 440.329066 -293.111682)
					(mid 440.293145 -293.126561)
					(end 440.278266 -293.162482)
				)
			)
		)
	)
	(zone
		(layers "In1.Cu" "In2.Cu")
		(hatch none 0.5)
		(connect_pads
			(clearance 0)
		)
		(min_thickness 0.25)
		(keepout
			(tracks not_allowed)
			(vias allowed)
			(pads allowed)
			(copperpour not_allowed)
			(footprints allowed)
		)
		(placement
			(enabled no)
			(sheetname "")
		)
		(fill yes
			(thermal_gap 0.5)
			(thermal_bridge_width 0.5)
			(island_removal_mode 0)
		)
		(polygon
			(pts
				(arc
					(start 180.69433 -226.421442)
					(mid 180.709209 -226.457363)
					(end 180.74513 -226.472242)
				)
				(arc
					(start 182.14467 -226.472242)
					(mid 182.180591 -226.457363)
					(end 182.19547 -226.421442)
				)
				(arc
					(start 182.19547 -226.012502)
					(mid 182.180591 -225.976581)
					(end 182.14467 -225.961702)
				)
				(arc
					(start 180.74513 -225.961702)
					(mid 180.709209 -225.976581)
					(end 180.69433 -226.012502)
				)
			)
		)
	)
	(zone
		(layers "In1.Cu" "In2.Cu")
		(hatch none 0.5)
		(connect_pads
			(clearance 0)
		)
		(min_thickness 0.25)
		(keepout
			(tracks not_allowed)
			(vias allowed)
			(pads allowed)
			(copperpour not_allowed)
			(footprints allowed)
		)
		(placement
			(enabled no)
			(sheetname "")
		)
		(fill yes
			(thermal_gap 0.5)
			(thermal_bridge_width 0.5)
			(island_removal_mode 0)
		)
		(polygon
			(pts
				(arc
					(start 297.149266 -292.721538)
					(mid 297.164145 -292.757459)
					(end 297.200066 -292.772338)
				)
				(arc
					(start 298.599606 -292.772338)
					(mid 298.635527 -292.757459)
					(end 298.650406 -292.721538)
				)
				(arc
					(start 298.650406 -292.312598)
					(mid 298.635527 -292.276677)
					(end 298.599606 -292.261798)
				)
				(arc
					(start 297.200066 -292.261798)
					(mid 297.164145 -292.276677)
					(end 297.149266 -292.312598)
				)
			)
		)
	)
	(zone
		(layers "In1.Cu" "In2.Cu")
		(hatch none 0.5)
		(connect_pads
			(clearance 0)
		)
		(min_thickness 0.25)
		(keepout
			(tracks not_allowed)
			(vias allowed)
			(pads allowed)
			(copperpour not_allowed)
			(footprints allowed)
		)
		(placement
			(enabled no)
			(sheetname "")
		)
		(fill yes
			(thermal_gap 0.5)
			(thermal_bridge_width 0.5)
			(island_removal_mode 0)
		)
		(polygon
			(pts
				(arc
					(start 436.178198 -200.921366)
					(mid 436.193077 -200.957287)
					(end 436.228998 -200.972166)
				)
				(arc
					(start 437.628538 -200.972166)
					(mid 437.664459 -200.957287)
					(end 437.679338 -200.921366)
				)
				(arc
					(start 437.679338 -200.512426)
					(mid 437.664459 -200.476505)
					(end 437.628538 -200.461626)
				)
				(arc
					(start 436.228998 -200.461626)
					(mid 436.193077 -200.476505)
					(end 436.178198 -200.512426)
				)
			)
		)
	)
	(zone
		(layers "In1.Cu" "In2.Cu")
		(hatch none 0.5)
		(connect_pads
			(clearance 0)
		)
		(min_thickness 0.25)
		(keepout
			(tracks not_allowed)
			(vias allowed)
			(pads allowed)
			(copperpour not_allowed)
			(footprints allowed)
		)
		(placement
			(enabled no)
			(sheetname "")
		)
		(fill yes
			(thermal_gap 0.5)
			(thermal_bridge_width 0.5)
			(island_removal_mode 0)
		)
		(polygon
			(pts
				(arc
					(start 443.721998 -215.371426)
					(mid 443.736877 -215.407347)
					(end 443.772798 -215.422226)
				)
				(arc
					(start 445.172338 -215.422226)
					(mid 445.208259 -215.407347)
					(end 445.223138 -215.371426)
				)
				(arc
					(start 445.223138 -214.962486)
					(mid 445.208259 -214.926565)
					(end 445.172338 -214.911686)
				)
				(arc
					(start 443.772798 -214.911686)
					(mid 443.736877 -214.926565)
					(end 443.721998 -214.962486)
				)
			)
		)
	)
	(zone
		(layers "In1.Cu" "In2.Cu")
		(hatch none 0.5)
		(connect_pads
			(clearance 0)
		)
		(min_thickness 0.25)
		(keepout
			(tracks not_allowed)
			(vias allowed)
			(pads allowed)
			(copperpour not_allowed)
			(footprints allowed)
		)
		(placement
			(enabled no)
			(sheetname "")
		)
		(fill yes
			(thermal_gap 0.5)
			(thermal_bridge_width 0.5)
			(island_removal_mode 0)
		)
		(polygon
			(pts
				(arc
					(start 41.665398 -260.421374)
					(mid 41.680277 -260.457295)
					(end 41.716198 -260.472174)
				)
				(arc
					(start 43.115738 -260.472174)
					(mid 43.151659 -260.457295)
					(end 43.166538 -260.421374)
				)
				(arc
					(start 43.166538 -260.012434)
					(mid 43.151659 -259.976513)
					(end 43.115738 -259.961634)
				)
				(arc
					(start 41.716198 -259.961634)
					(mid 41.680277 -259.976513)
					(end 41.665398 -260.012434)
				)
			)
		)
	)
	(zone
		(layers "In1.Cu" "In2.Cu")
		(hatch none 0.5)
		(connect_pads
			(clearance 0)
		)
		(min_thickness 0.25)
		(keepout
			(tracks not_allowed)
			(vias allowed)
			(pads allowed)
			(copperpour not_allowed)
			(footprints allowed)
		)
		(placement
			(enabled no)
			(sheetname "")
		)
		(fill yes
			(thermal_gap 0.5)
			(thermal_bridge_width 0.5)
			(island_removal_mode 0)
		)
		(polygon
			(pts
				(arc
					(start 406.002998 -269.771368)
					(mid 406.017877 -269.807289)
					(end 406.053798 -269.822168)
				)
				(arc
					(start 407.453338 -269.822168)
					(mid 407.489259 -269.807289)
					(end 407.504138 -269.771368)
				)
				(arc
					(start 407.504138 -269.362428)
					(mid 407.489259 -269.326507)
					(end 407.453338 -269.311628)
				)
				(arc
					(start 406.053798 -269.311628)
					(mid 406.017877 -269.326507)
					(end 406.002998 -269.362428)
				)
			)
		)
	)
	(zone
		(layers "In1.Cu" "In2.Cu")
		(hatch none 0.5)
		(connect_pads
			(clearance 0)
		)
		(min_thickness 0.25)
		(keepout
			(tracks not_allowed)
			(vias allowed)
			(pads allowed)
			(copperpour not_allowed)
			(footprints allowed)
		)
		(placement
			(enabled no)
			(sheetname "")
		)
		(fill yes
			(thermal_gap 0.5)
			(thermal_bridge_width 0.5)
			(island_removal_mode 0)
		)
		(polygon
			(pts
				(arc
					(start 282.061666 -279.9715)
					(mid 282.076545 -280.007421)
					(end 282.112466 -280.0223)
				)
				(arc
					(start 283.512006 -280.0223)
					(mid 283.547927 -280.007421)
					(end 283.562806 -279.9715)
				)
				(arc
					(start 283.562806 -279.56256)
					(mid 283.547927 -279.526639)
					(end 283.512006 -279.51176)
				)
				(arc
					(start 282.112466 -279.51176)
					(mid 282.076545 -279.526639)
					(end 282.061666 -279.56256)
				)
			)
		)
	)
	(zone
		(layers "In1.Cu" "In2.Cu")
		(hatch none 0.5)
		(connect_pads
			(clearance 0)
		)
		(min_thickness 0.25)
		(keepout
			(tracks not_allowed)
			(vias allowed)
			(pads allowed)
			(copperpour not_allowed)
			(footprints allowed)
		)
		(placement
			(enabled no)
			(sheetname "")
		)
		(fill yes
			(thermal_gap 0.5)
			(thermal_bridge_width 0.5)
			(island_removal_mode 0)
		)
		(polygon
			(pts
				(arc
					(start 192.338198 -225.571304)
					(mid 192.353077 -225.607225)
					(end 192.388998 -225.622104)
				)
				(arc
					(start 193.788538 -225.622104)
					(mid 193.824459 -225.607225)
					(end 193.839338 -225.571304)
				)
				(arc
					(start 193.839338 -225.162364)
					(mid 193.824459 -225.126443)
					(end 193.788538 -225.111564)
				)
				(arc
					(start 192.388998 -225.111564)
					(mid 192.353077 -225.126443)
					(end 192.338198 -225.162364)
				)
			)
		)
	)
	(zone
		(layers "In1.Cu" "In2.Cu")
		(hatch none 0.5)
		(connect_pads
			(clearance 0)
		)
		(min_thickness 0.25)
		(keepout
			(tracks not_allowed)
			(vias allowed)
			(pads allowed)
			(copperpour not_allowed)
			(footprints allowed)
		)
		(placement
			(enabled no)
			(sheetname "")
		)
		(fill yes
			(thermal_gap 0.5)
			(thermal_bridge_width 0.5)
			(island_removal_mode 0)
		)
		(polygon
			(pts
				(arc
					(start 165.60673 -235.771436)
					(mid 165.621609 -235.807357)
					(end 165.65753 -235.822236)
				)
				(arc
					(start 167.05707 -235.822236)
					(mid 167.092991 -235.807357)
					(end 167.10787 -235.771436)
				)
				(arc
					(start 167.10787 -235.362496)
					(mid 167.092991 -235.326575)
					(end 167.05707 -235.311696)
				)
				(arc
					(start 165.65753 -235.311696)
					(mid 165.621609 -235.326575)
					(end 165.60673 -235.362496)
				)
			)
		)
	)
	(zone
		(layers "In1.Cu" "In2.Cu")
		(hatch none 0.5)
		(connect_pads
			(clearance 0)
		)
		(min_thickness 0.25)
		(keepout
			(tracks not_allowed)
			(vias allowed)
			(pads allowed)
			(copperpour not_allowed)
			(footprints allowed)
		)
		(placement
			(enabled no)
			(sheetname "")
		)
		(fill yes
			(thermal_gap 0.5)
			(thermal_bridge_width 0.5)
			(island_removal_mode 0)
		)
		(polygon
			(pts
				(arc
					(start 312.236866 -239.17148)
					(mid 312.251745 -239.207401)
					(end 312.287666 -239.22228)
				)
				(arc
					(start 313.687206 -239.22228)
					(mid 313.723127 -239.207401)
					(end 313.738006 -239.17148)
				)
				(arc
					(start 313.738006 -238.76254)
					(mid 313.723127 -238.726619)
					(end 313.687206 -238.71174)
				)
				(arc
					(start 312.287666 -238.71174)
					(mid 312.251745 -238.726619)
					(end 312.236866 -238.76254)
				)
			)
		)
	)
	(zone
		(layers "In1.Cu" "In2.Cu")
		(hatch none 0.5)
		(connect_pads
			(clearance 0)
		)
		(min_thickness 0.25)
		(keepout
			(tracks not_allowed)
			(vias allowed)
			(pads allowed)
			(copperpour not_allowed)
			(footprints allowed)
		)
		(placement
			(enabled no)
			(sheetname "")
		)
		(fill yes
			(thermal_gap 0.5)
			(thermal_bridge_width 0.5)
			(island_removal_mode 0)
		)
		(polygon
			(pts
				(arc
					(start 158.06293 -266.371324)
					(mid 158.077809 -266.407245)
					(end 158.11373 -266.422124)
				)
				(arc
					(start 159.51327 -266.422124)
					(mid 159.549191 -266.407245)
					(end 159.56407 -266.371324)
				)
				(arc
					(start 159.56407 -265.962384)
					(mid 159.549191 -265.926463)
					(end 159.51327 -265.911584)
				)
				(arc
					(start 158.11373 -265.911584)
					(mid 158.077809 -265.926463)
					(end 158.06293 -265.962384)
				)
			)
		)
	)
	(zone
		(layers "In1.Cu" "In2.Cu")
		(hatch none 0.5)
		(connect_pads
			(clearance 0)
		)
		(min_thickness 0.25)
		(keepout
			(tracks not_allowed)
			(vias allowed)
			(pads allowed)
			(copperpour not_allowed)
			(footprints allowed)
		)
		(placement
			(enabled no)
			(sheetname "")
		)
		(fill yes
			(thermal_gap 0.5)
			(thermal_bridge_width 0.5)
			(island_removal_mode 0)
		)
		(polygon
			(pts
				(arc
					(start 203.32573 -209.421476)
					(mid 203.340609 -209.457397)
					(end 203.37653 -209.472276)
				)
				(arc
					(start 204.77607 -209.472276)
					(mid 204.811991 -209.457397)
					(end 204.82687 -209.421476)
				)
				(arc
					(start 204.82687 -209.012536)
					(mid 204.811991 -208.976615)
					(end 204.77607 -208.961736)
				)
				(arc
					(start 203.37653 -208.961736)
					(mid 203.340609 -208.976615)
					(end 203.32573 -209.012536)
				)
			)
		)
	)
	(zone
		(layers "In1.Cu" "In2.Cu")
		(hatch none 0.5)
		(connect_pads
			(clearance 0)
		)
		(min_thickness 0.25)
		(keepout
			(tracks not_allowed)
			(vias allowed)
			(pads allowed)
			(copperpour not_allowed)
			(footprints allowed)
		)
		(placement
			(enabled no)
			(sheetname "")
		)
		(fill yes
			(thermal_gap 0.5)
			(thermal_bridge_width 0.5)
			(island_removal_mode 0)
		)
		(polygon
			(pts
				(arc
					(start 41.665398 -283.371544)
					(mid 41.680277 -283.407465)
					(end 41.716198 -283.422344)
				)
				(arc
					(start 43.115738 -283.422344)
					(mid 43.151659 -283.407465)
					(end 43.166538 -283.371544)
				)
				(arc
					(start 43.166538 -282.962604)
					(mid 43.151659 -282.926683)
					(end 43.115738 -282.911804)
				)
				(arc
					(start 41.716198 -282.911804)
					(mid 41.680277 -282.926683)
					(end 41.665398 -282.962604)
				)
			)
		)
	)
	(zone
		(layers "In1.Cu" "In2.Cu")
		(hatch none 0.5)
		(connect_pads
			(clearance 0)
		)
		(min_thickness 0.25)
		(keepout
			(tracks not_allowed)
			(vias allowed)
			(pads allowed)
			(copperpour not_allowed)
			(footprints allowed)
		)
		(placement
			(enabled no)
			(sheetname "")
		)
		(fill yes
			(thermal_gap 0.5)
			(thermal_bridge_width 0.5)
			(island_removal_mode 0)
		)
		(polygon
			(pts
				(arc
					(start 274.517866 -304.621438)
					(mid 274.532745 -304.657359)
					(end 274.568666 -304.672238)
				)
				(arc
					(start 275.968206 -304.672238)
					(mid 276.004127 -304.657359)
					(end 276.019006 -304.621438)
				)
				(arc
					(start 276.019006 -304.212498)
					(mid 276.004127 -304.176577)
					(end 275.968206 -304.161698)
				)
				(arc
					(start 274.568666 -304.161698)
					(mid 274.532745 -304.176577)
					(end 274.517866 -304.212498)
				)
			)
		)
	)
	(zone
		(layers "In1.Cu" "In2.Cu")
		(hatch none 0.5)
		(connect_pads
			(clearance 0)
		)
		(min_thickness 0.25)
		(keepout
			(tracks not_allowed)
			(vias allowed)
			(pads allowed)
			(copperpour not_allowed)
			(footprints allowed)
		)
		(placement
			(enabled no)
			(sheetname "")
		)
		(fill yes
			(thermal_gap 0.5)
			(thermal_bridge_width 0.5)
			(island_removal_mode 0)
		)
		(polygon
			(pts
				(arc
					(start 436.178198 -273.171412)
					(mid 436.193077 -273.207333)
					(end 436.228998 -273.222212)
				)
				(arc
					(start 437.628538 -273.222212)
					(mid 437.664459 -273.207333)
					(end 437.679338 -273.171412)
				)
				(arc
					(start 437.679338 -272.762472)
					(mid 437.664459 -272.726551)
					(end 437.628538 -272.711672)
				)
				(arc
					(start 436.228998 -272.711672)
					(mid 436.193077 -272.726551)
					(end 436.178198 -272.762472)
				)
			)
		)
	)
	(zone
		(layers "In1.Cu" "In2.Cu")
		(hatch none 0.5)
		(connect_pads
			(clearance 0)
		)
		(min_thickness 0.25)
		(keepout
			(tracks not_allowed)
			(vias allowed)
			(pads allowed)
			(copperpour not_allowed)
			(footprints allowed)
		)
		(placement
			(enabled no)
			(sheetname "")
		)
		(fill yes
			(thermal_gap 0.5)
			(thermal_bridge_width 0.5)
			(island_removal_mode 0)
		)
		(polygon
			(pts
				(arc
					(start 293.049198 -282.521406)
					(mid 293.064077 -282.557327)
					(end 293.099998 -282.572206)
				)
				(arc
					(start 294.499538 -282.572206)
					(mid 294.535459 -282.557327)
					(end 294.550338 -282.521406)
				)
				(arc
					(start 294.550338 -282.112466)
					(mid 294.535459 -282.076545)
					(end 294.499538 -282.061666)
				)
				(arc
					(start 293.099998 -282.061666)
					(mid 293.064077 -282.076545)
					(end 293.049198 -282.112466)
				)
			)
		)
	)
	(zone
		(layers "In1.Cu" "In2.Cu")
		(hatch none 0.5)
		(connect_pads
			(clearance 0)
		)
		(min_thickness 0.25)
		(keepout
			(tracks not_allowed)
			(vias allowed)
			(pads allowed)
			(copperpour not_allowed)
			(footprints allowed)
		)
		(placement
			(enabled no)
			(sheetname "")
		)
		(fill yes
			(thermal_gap 0.5)
			(thermal_bridge_width 0.5)
			(island_removal_mode 0)
		)
		(polygon
			(pts
				(arc
					(start 207.425798 -203.471526)
					(mid 207.440677 -203.507447)
					(end 207.476598 -203.522326)
				)
				(arc
					(start 208.876138 -203.522326)
					(mid 208.912059 -203.507447)
					(end 208.926938 -203.471526)
				)
				(arc
					(start 208.926938 -203.062586)
					(mid 208.912059 -203.026665)
					(end 208.876138 -203.011786)
				)
				(arc
					(start 207.476598 -203.011786)
					(mid 207.440677 -203.026665)
					(end 207.425798 -203.062586)
				)
			)
		)
	)
	(zone
		(layers "In1.Cu" "In2.Cu")
		(hatch none 0.5)
		(connect_pads
			(clearance 0)
		)
		(min_thickness 0.25)
		(keepout
			(tracks not_allowed)
			(vias allowed)
			(pads allowed)
			(copperpour not_allowed)
			(footprints allowed)
		)
		(placement
			(enabled no)
			(sheetname "")
		)
		(fill yes
			(thermal_gap 0.5)
			(thermal_bridge_width 0.5)
			(island_removal_mode 0)
		)
		(polygon
			(pts
				(arc
					(start 210.86953 -215.371426)
					(mid 210.884409 -215.407347)
					(end 210.92033 -215.422226)
				)
				(arc
					(start 212.31987 -215.422226)
					(mid 212.355791 -215.407347)
					(end 212.37067 -215.371426)
				)
				(arc
					(start 212.37067 -214.962486)
					(mid 212.355791 -214.926565)
					(end 212.31987 -214.911686)
				)
				(arc
					(start 210.92033 -214.911686)
					(mid 210.884409 -214.926565)
					(end 210.86953 -214.962486)
				)
			)
		)
	)
	(zone
		(layers "In1.Cu" "In2.Cu")
		(hatch none 0.5)
		(connect_pads
			(clearance 0)
		)
		(min_thickness 0.25)
		(keepout
			(tracks not_allowed)
			(vias allowed)
			(pads allowed)
			(copperpour not_allowed)
			(footprints allowed)
		)
		(placement
			(enabled no)
			(sheetname "")
		)
		(fill yes
			(thermal_gap 0.5)
			(thermal_bridge_width 0.5)
			(island_removal_mode 0)
		)
		(polygon
			(pts
				(arc
					(start 285.505398 -223.021398)
					(mid 285.520277 -223.057319)
					(end 285.556198 -223.072198)
				)
				(arc
					(start 286.955738 -223.072198)
					(mid 286.991659 -223.057319)
					(end 287.006538 -223.021398)
				)
				(arc
					(start 287.006538 -222.612458)
					(mid 286.991659 -222.576537)
					(end 286.955738 -222.561658)
				)
				(arc
					(start 285.556198 -222.561658)
					(mid 285.520277 -222.576537)
					(end 285.505398 -222.612458)
				)
			)
		)
	)
	(zone
		(layers "In1.Cu" "In2.Cu")
		(hatch none 0.5)
		(connect_pads
			(clearance 0)
		)
		(min_thickness 0.25)
		(keepout
			(tracks not_allowed)
			(vias allowed)
			(pads allowed)
			(copperpour not_allowed)
			(footprints allowed)
		)
		(placement
			(enabled no)
			(sheetname "")
		)
		(fill yes
			(thermal_gap 0.5)
			(thermal_bridge_width 0.5)
			(island_removal_mode 0)
		)
		(polygon
			(pts
				(arc
					(start 428.634398 -228.971348)
					(mid 428.649277 -229.007269)
					(end 428.685198 -229.022148)
				)
				(arc
					(start 430.084738 -229.022148)
					(mid 430.120659 -229.007269)
					(end 430.135538 -228.971348)
				)
				(arc
					(start 430.135538 -228.562408)
					(mid 430.120659 -228.526487)
					(end 430.084738 -228.511608)
				)
				(arc
					(start 428.685198 -228.511608)
					(mid 428.649277 -228.526487)
					(end 428.634398 -228.562408)
				)
			)
		)
	)
	(zone
		(layers "In1.Cu" "In2.Cu")
		(hatch none 0.5)
		(connect_pads
			(clearance 0)
		)
		(min_thickness 0.25)
		(keepout
			(tracks not_allowed)
			(vias allowed)
			(pads allowed)
			(copperpour not_allowed)
			(footprints allowed)
		)
		(placement
			(enabled no)
			(sheetname "")
		)
		(fill yes
			(thermal_gap 0.5)
			(thermal_bridge_width 0.5)
			(island_removal_mode 0)
		)
		(polygon
			(pts
				(arc
					(start 462.909666 -267.221462)
					(mid 462.924545 -267.257383)
					(end 462.960466 -267.272262)
				)
				(arc
					(start 464.360006 -267.272262)
					(mid 464.395927 -267.257383)
					(end 464.410806 -267.221462)
				)
				(arc
					(start 464.410806 -266.812522)
					(mid 464.395927 -266.776601)
					(end 464.360006 -266.761722)
				)
				(arc
					(start 462.960466 -266.761722)
					(mid 462.924545 -266.776601)
					(end 462.909666 -266.812522)
				)
			)
		)
	)
	(zone
		(layers "In1.Cu" "In2.Cu")
		(hatch none 0.5)
		(connect_pads
			(clearance 0)
		)
		(min_thickness 0.25)
		(keepout
			(tracks not_allowed)
			(vias allowed)
			(pads allowed)
			(copperpour not_allowed)
			(footprints allowed)
		)
		(placement
			(enabled no)
			(sheetname "")
		)
		(fill yes
			(thermal_gap 0.5)
			(thermal_bridge_width 0.5)
			(island_removal_mode 0)
		)
		(polygon
			(pts
				(arc
					(start 49.209198 -248.521474)
					(mid 49.224077 -248.557395)
					(end 49.259998 -248.572274)
				)
				(arc
					(start 50.659538 -248.572274)
					(mid 50.695459 -248.557395)
					(end 50.710338 -248.521474)
				)
				(arc
					(start 50.710338 -248.112534)
					(mid 50.695459 -248.076613)
					(end 50.659538 -248.061734)
				)
				(arc
					(start 49.259998 -248.061734)
					(mid 49.224077 -248.076613)
					(end 49.209198 -248.112534)
				)
			)
		)
	)
	(zone
		(layers "In1.Cu" "In2.Cu")
		(hatch none 0.5)
		(connect_pads
			(clearance 0)
		)
		(min_thickness 0.25)
		(keepout
			(tracks not_allowed)
			(vias allowed)
			(pads allowed)
			(copperpour not_allowed)
			(footprints allowed)
		)
		(placement
			(enabled no)
			(sheetname "")
		)
		(fill yes
			(thermal_gap 0.5)
			(thermal_bridge_width 0.5)
			(island_removal_mode 0)
		)
		(polygon
			(pts
				(arc
					(start 30.02153 -219.621354)
					(mid 30.036409 -219.657275)
					(end 30.07233 -219.672154)
				)
				(arc
					(start 31.47187 -219.672154)
					(mid 31.507791 -219.657275)
					(end 31.52267 -219.621354)
				)
				(arc
					(start 31.52267 -219.212414)
					(mid 31.507791 -219.176493)
					(end 31.47187 -219.161614)
				)
				(arc
					(start 30.07233 -219.161614)
					(mid 30.036409 -219.176493)
					(end 30.02153 -219.212414)
				)
			)
		)
	)
	(zone
		(layers "In1.Cu" "In2.Cu")
		(hatch none 0.5)
		(connect_pads
			(clearance 0)
		)
		(min_thickness 0.25)
		(keepout
			(tracks not_allowed)
			(vias allowed)
			(pads allowed)
			(copperpour not_allowed)
			(footprints allowed)
		)
		(placement
			(enabled no)
			(sheetname "")
		)
		(fill yes
			(thermal_gap 0.5)
			(thermal_bridge_width 0.5)
			(island_removal_mode 0)
		)
		(polygon
			(pts
				(arc
					(start 49.209198 -311.421526)
					(mid 49.224077 -311.457447)
					(end 49.259998 -311.472326)
				)
				(arc
					(start 50.659538 -311.472326)
					(mid 50.695459 -311.457447)
					(end 50.710338 -311.421526)
				)
				(arc
					(start 50.710338 -311.012586)
					(mid 50.695459 -310.976665)
					(end 50.659538 -310.961786)
				)
				(arc
					(start 49.259998 -310.961786)
					(mid 49.224077 -310.976665)
					(end 49.209198 -311.012586)
				)
			)
		)
	)
	(zone
		(layers "In1.Cu" "In2.Cu")
		(hatch none 0.5)
		(connect_pads
			(clearance 0)
		)
		(min_thickness 0.25)
		(keepout
			(tracks not_allowed)
			(vias allowed)
			(pads allowed)
			(copperpour not_allowed)
			(footprints allowed)
		)
		(placement
			(enabled no)
			(sheetname "")
		)
		(fill yes
			(thermal_gap 0.5)
			(thermal_bridge_width 0.5)
			(island_removal_mode 0)
		)
		(polygon
			(pts
				(arc
					(start 413.546798 -259.57149)
					(mid 413.561677 -259.607411)
					(end 413.597598 -259.62229)
				)
				(arc
					(start 414.997138 -259.62229)
					(mid 415.033059 -259.607411)
					(end 415.047938 -259.57149)
				)
				(arc
					(start 415.047938 -259.16255)
					(mid 415.033059 -259.126629)
					(end 414.997138 -259.11175)
				)
				(arc
					(start 413.597598 -259.11175)
					(mid 413.561677 -259.126629)
					(end 413.546798 -259.16255)
				)
			)
		)
	)
	(zone
		(layers "In1.Cu" "In2.Cu")
		(hatch none 0.5)
		(connect_pads
			(clearance 0)
		)
		(min_thickness 0.25)
		(keepout
			(tracks not_allowed)
			(vias allowed)
			(pads allowed)
			(copperpour not_allowed)
			(footprints allowed)
		)
		(placement
			(enabled no)
			(sheetname "")
		)
		(fill yes
			(thermal_gap 0.5)
			(thermal_bridge_width 0.5)
			(island_removal_mode 0)
		)
		(polygon
			(pts
				(arc
					(start 49.209198 -284.221428)
					(mid 49.224077 -284.257349)
					(end 49.259998 -284.272228)
				)
				(arc
					(start 50.659538 -284.272228)
					(mid 50.695459 -284.257349)
					(end 50.710338 -284.221428)
				)
				(arc
					(start 50.710338 -283.812488)
					(mid 50.695459 -283.776567)
					(end 50.659538 -283.761688)
				)
				(arc
					(start 49.259998 -283.761688)
					(mid 49.224077 -283.776567)
					(end 49.209198 -283.812488)
				)
			)
		)
	)
	(zone
		(layers "In1.Cu" "In2.Cu")
		(hatch none 0.5)
		(connect_pads
			(clearance 0)
		)
		(min_thickness 0.25)
		(keepout
			(tracks not_allowed)
			(vias allowed)
			(pads allowed)
			(copperpour not_allowed)
			(footprints allowed)
		)
		(placement
			(enabled no)
			(sheetname "")
		)
		(fill yes
			(thermal_gap 0.5)
			(thermal_bridge_width 0.5)
			(island_removal_mode 0)
		)
		(polygon
			(pts
				(arc
					(start 425.190666 -245.12143)
					(mid 425.205545 -245.157351)
					(end 425.241466 -245.17223)
				)
				(arc
					(start 426.641006 -245.17223)
					(mid 426.676927 -245.157351)
					(end 426.691806 -245.12143)
				)
				(arc
					(start 426.691806 -244.71249)
					(mid 426.676927 -244.676569)
					(end 426.641006 -244.66169)
				)
				(arc
					(start 425.241466 -244.66169)
					(mid 425.205545 -244.676569)
					(end 425.190666 -244.71249)
				)
			)
		)
	)
	(zone
		(layers "In1.Cu" "In2.Cu")
		(hatch none 0.5)
		(connect_pads
			(clearance 0)
		)
		(min_thickness 0.25)
		(keepout
			(tracks not_allowed)
			(vias allowed)
			(pads allowed)
			(copperpour not_allowed)
			(footprints allowed)
		)
		(placement
			(enabled no)
			(sheetname "")
		)
		(fill yes
			(thermal_gap 0.5)
			(thermal_bridge_width 0.5)
			(island_removal_mode 0)
		)
		(polygon
			(pts
				(arc
					(start 192.338198 -248.521474)
					(mid 192.353077 -248.557395)
					(end 192.388998 -248.572274)
				)
				(arc
					(start 193.788538 -248.572274)
					(mid 193.824459 -248.557395)
					(end 193.839338 -248.521474)
				)
				(arc
					(start 193.839338 -248.112534)
					(mid 193.824459 -248.076613)
					(end 193.788538 -248.061734)
				)
				(arc
					(start 192.388998 -248.061734)
					(mid 192.353077 -248.076613)
					(end 192.338198 -248.112534)
				)
			)
		)
	)
	(zone
		(layers "In1.Cu" "In2.Cu")
		(hatch none 0.5)
		(connect_pads
			(clearance 0)
		)
		(min_thickness 0.25)
		(keepout
			(tracks not_allowed)
			(vias allowed)
			(pads allowed)
			(copperpour not_allowed)
			(footprints allowed)
		)
		(placement
			(enabled no)
			(sheetname "")
		)
		(fill yes
			(thermal_gap 0.5)
			(thermal_bridge_width 0.5)
			(island_removal_mode 0)
		)
		(polygon
			(pts
				(arc
					(start 173.15053 -202.621388)
					(mid 173.165409 -202.657309)
					(end 173.20133 -202.672188)
				)
				(arc
					(start 174.60087 -202.672188)
					(mid 174.636791 -202.657309)
					(end 174.65167 -202.621388)
				)
				(arc
					(start 174.65167 -202.212448)
					(mid 174.636791 -202.176527)
					(end 174.60087 -202.161648)
				)
				(arc
					(start 173.20133 -202.161648)
					(mid 173.165409 -202.176527)
					(end 173.15053 -202.212448)
				)
			)
		)
	)
	(zone
		(layers "In1.Cu" "In2.Cu")
		(hatch none 0.5)
		(connect_pads
			(clearance 0)
		)
		(min_thickness 0.25)
		(keepout
			(tracks not_allowed)
			(vias allowed)
			(pads allowed)
			(copperpour not_allowed)
			(footprints allowed)
		)
		(placement
			(enabled no)
			(sheetname "")
		)
		(fill yes
			(thermal_gap 0.5)
			(thermal_bridge_width 0.5)
			(island_removal_mode 0)
		)
		(polygon
			(pts
				(arc
					(start 177.250598 -284.221428)
					(mid 177.265477 -284.257349)
					(end 177.301398 -284.272228)
				)
				(arc
					(start 178.700938 -284.272228)
					(mid 178.736859 -284.257349)
					(end 178.751738 -284.221428)
				)
				(arc
					(start 178.751738 -283.812488)
					(mid 178.736859 -283.776567)
					(end 178.700938 -283.761688)
				)
				(arc
					(start 177.301398 -283.761688)
					(mid 177.265477 -283.776567)
					(end 177.250598 -283.812488)
				)
			)
		)
	)
	(zone
		(layers "In1.Cu" "In2.Cu")
		(hatch none 0.5)
		(connect_pads
			(clearance 0)
		)
		(min_thickness 0.25)
		(keepout
			(tracks not_allowed)
			(vias allowed)
			(pads allowed)
			(copperpour not_allowed)
			(footprints allowed)
		)
		(placement
			(enabled no)
			(sheetname "")
		)
		(fill yes
			(thermal_gap 0.5)
			(thermal_bridge_width 0.5)
			(island_removal_mode 0)
		)
		(polygon
			(pts
				(arc
					(start 443.721998 -230.67137)
					(mid 443.736877 -230.707291)
					(end 443.772798 -230.72217)
				)
				(arc
					(start 445.172338 -230.72217)
					(mid 445.208259 -230.707291)
					(end 445.223138 -230.67137)
				)
				(arc
					(start 445.223138 -230.26243)
					(mid 445.208259 -230.226509)
					(end 445.172338 -230.21163)
				)
				(arc
					(start 443.772798 -230.21163)
					(mid 443.736877 -230.226509)
					(end 443.721998 -230.26243)
				)
			)
		)
	)
	(zone
		(layers "In1.Cu" "In2.Cu")
		(hatch none 0.5)
		(connect_pads
			(clearance 0)
		)
		(min_thickness 0.25)
		(keepout
			(tracks not_allowed)
			(vias allowed)
			(pads allowed)
			(copperpour not_allowed)
			(footprints allowed)
		)
		(placement
			(enabled no)
			(sheetname "")
		)
		(fill yes
			(thermal_gap 0.5)
			(thermal_bridge_width 0.5)
			(island_removal_mode 0)
		)
		(polygon
			(pts
				(arc
					(start 413.546798 -274.871434)
					(mid 413.561677 -274.907355)
					(end 413.597598 -274.922234)
				)
				(arc
					(start 414.997138 -274.922234)
					(mid 415.033059 -274.907355)
					(end 415.047938 -274.871434)
				)
				(arc
					(start 415.047938 -274.462494)
					(mid 415.033059 -274.426573)
					(end 414.997138 -274.411694)
				)
				(arc
					(start 413.597598 -274.411694)
					(mid 413.561677 -274.426573)
					(end 413.546798 -274.462494)
				)
			)
		)
	)
	(zone
		(layers "In1.Cu" "In2.Cu")
		(hatch none 0.5)
		(connect_pads
			(clearance 0)
		)
		(min_thickness 0.25)
		(keepout
			(tracks not_allowed)
			(vias allowed)
			(pads allowed)
			(copperpour not_allowed)
			(footprints allowed)
		)
		(placement
			(enabled no)
			(sheetname "")
		)
		(fill yes
			(thermal_gap 0.5)
			(thermal_bridge_width 0.5)
			(island_removal_mode 0)
		)
		(polygon
			(pts
				(arc
					(start 432.734466 -285.92145)
					(mid 432.749345 -285.957371)
					(end 432.785266 -285.97225)
				)
				(arc
					(start 434.184806 -285.97225)
					(mid 434.220727 -285.957371)
					(end 434.235606 -285.92145)
				)
				(arc
					(start 434.235606 -285.51251)
					(mid 434.220727 -285.476589)
					(end 434.184806 -285.46171)
				)
				(arc
					(start 432.785266 -285.46171)
					(mid 432.749345 -285.476589)
					(end 432.734466 -285.51251)
				)
			)
		)
	)
	(zone
		(layers "In1.Cu" "In2.Cu")
		(hatch none 0.5)
		(connect_pads
			(clearance 0)
		)
		(min_thickness 0.25)
		(keepout
			(tracks not_allowed)
			(vias allowed)
			(pads allowed)
			(copperpour not_allowed)
			(footprints allowed)
		)
		(placement
			(enabled no)
			(sheetname "")
		)
		(fill yes
			(thermal_gap 0.5)
			(thermal_bridge_width 0.5)
			(island_removal_mode 0)
		)
		(polygon
			(pts
				(arc
					(start 266.974066 -251.921518)
					(mid 266.988945 -251.957439)
					(end 267.024866 -251.972318)
				)
				(arc
					(start 268.424406 -251.972318)
					(mid 268.460327 -251.957439)
					(end 268.475206 -251.921518)
				)
				(arc
					(start 268.475206 -251.512578)
					(mid 268.460327 -251.476657)
					(end 268.424406 -251.461778)
				)
				(arc
					(start 267.024866 -251.461778)
					(mid 266.988945 -251.476657)
					(end 266.974066 -251.512578)
				)
			)
		)
	)
	(zone
		(layers "In1.Cu" "In2.Cu")
		(hatch none 0.5)
		(connect_pads
			(clearance 0)
		)
		(min_thickness 0.25)
		(keepout
			(tracks not_allowed)
			(vias allowed)
			(pads allowed)
			(copperpour not_allowed)
			(footprints allowed)
		)
		(placement
			(enabled no)
			(sheetname "")
		)
		(fill yes
			(thermal_gap 0.5)
			(thermal_bridge_width 0.5)
			(island_removal_mode 0)
		)
		(polygon
			(pts
				(arc
					(start 60.19673 -251.07138)
					(mid 60.211609 -251.107301)
					(end 60.24753 -251.12218)
				)
				(arc
					(start 61.64707 -251.12218)
					(mid 61.682991 -251.107301)
					(end 61.69787 -251.07138)
				)
				(arc
					(start 61.69787 -250.66244)
					(mid 61.682991 -250.626519)
					(end 61.64707 -250.61164)
				)
				(arc
					(start 60.24753 -250.61164)
					(mid 60.211609 -250.626519)
					(end 60.19673 -250.66244)
				)
			)
		)
	)
	(zone
		(layers "In1.Cu" "In2.Cu")
		(hatch none 0.5)
		(connect_pads
			(clearance 0)
		)
		(min_thickness 0.25)
		(keepout
			(tracks not_allowed)
			(vias allowed)
			(pads allowed)
			(copperpour not_allowed)
			(footprints allowed)
		)
		(placement
			(enabled no)
			(sheetname "")
		)
		(fill yes
			(thermal_gap 0.5)
			(thermal_bridge_width 0.5)
			(island_removal_mode 0)
		)
		(polygon
			(pts
				(arc
					(start 26.577798 -300.37151)
					(mid 26.592677 -300.407431)
					(end 26.628598 -300.42231)
				)
				(arc
					(start 28.028138 -300.42231)
					(mid 28.064059 -300.407431)
					(end 28.078938 -300.37151)
				)
				(arc
					(start 28.078938 -299.96257)
					(mid 28.064059 -299.926649)
					(end 28.028138 -299.91177)
				)
				(arc
					(start 26.628598 -299.91177)
					(mid 26.592677 -299.926649)
					(end 26.577798 -299.96257)
				)
			)
		)
	)
	(zone
		(layers "In1.Cu" "In2.Cu")
		(hatch none 0.5)
		(connect_pads
			(clearance 0)
		)
		(min_thickness 0.25)
		(keepout
			(tracks not_allowed)
			(vias allowed)
			(pads allowed)
			(copperpour not_allowed)
			(footprints allowed)
		)
		(placement
			(enabled no)
			(sheetname "")
		)
		(fill yes
			(thermal_gap 0.5)
			(thermal_bridge_width 0.5)
			(island_removal_mode 0)
		)
		(polygon
			(pts
				(arc
					(start 270.417798 -241.721386)
					(mid 270.432677 -241.757307)
					(end 270.468598 -241.772186)
				)
				(arc
					(start 271.868138 -241.772186)
					(mid 271.904059 -241.757307)
					(end 271.918938 -241.721386)
				)
				(arc
					(start 271.918938 -241.312446)
					(mid 271.904059 -241.276525)
					(end 271.868138 -241.261646)
				)
				(arc
					(start 270.468598 -241.261646)
					(mid 270.432677 -241.276525)
					(end 270.417798 -241.312446)
				)
			)
		)
	)
	(zone
		(layers "In1.Cu" "In2.Cu")
		(hatch none 0.5)
		(connect_pads
			(clearance 0)
		)
		(min_thickness 0.25)
		(keepout
			(tracks not_allowed)
			(vias allowed)
			(pads allowed)
			(copperpour not_allowed)
			(footprints allowed)
		)
		(placement
			(enabled no)
			(sheetname "")
		)
		(fill yes
			(thermal_gap 0.5)
			(thermal_bridge_width 0.5)
			(island_removal_mode 0)
		)
		(polygon
			(pts
				(arc
					(start 447.822066 -279.9715)
					(mid 447.836945 -280.007421)
					(end 447.872866 -280.0223)
				)
				(arc
					(start 449.272406 -280.0223)
					(mid 449.308327 -280.007421)
					(end 449.323206 -279.9715)
				)
				(arc
					(start 449.323206 -279.56256)
					(mid 449.308327 -279.526639)
					(end 449.272406 -279.51176)
				)
				(arc
					(start 447.872866 -279.51176)
					(mid 447.836945 -279.526639)
					(end 447.822066 -279.56256)
				)
			)
		)
	)
	(zone
		(layers "In1.Cu" "In2.Cu")
		(hatch none 0.5)
		(connect_pads
			(clearance 0)
		)
		(min_thickness 0.25)
		(keepout
			(tracks not_allowed)
			(vias allowed)
			(pads allowed)
			(copperpour not_allowed)
			(footprints allowed)
		)
		(placement
			(enabled no)
			(sheetname "")
		)
		(fill yes
			(thermal_gap 0.5)
			(thermal_bridge_width 0.5)
			(island_removal_mode 0)
		)
		(polygon
			(pts
				(arc
					(start 462.909666 -272.321528)
					(mid 462.924545 -272.357449)
					(end 462.960466 -272.372328)
				)
				(arc
					(start 464.360006 -272.372328)
					(mid 464.395927 -272.357449)
					(end 464.410806 -272.321528)
				)
				(arc
					(start 464.410806 -271.912588)
					(mid 464.395927 -271.876667)
					(end 464.360006 -271.861788)
				)
				(arc
					(start 462.960466 -271.861788)
					(mid 462.924545 -271.876667)
					(end 462.909666 -271.912588)
				)
			)
		)
	)
	(zone
		(layers "In1.Cu" "In2.Cu")
		(hatch none 0.5)
		(connect_pads
			(clearance 0)
		)
		(min_thickness 0.25)
		(keepout
			(tracks not_allowed)
			(vias allowed)
			(pads allowed)
			(copperpour not_allowed)
			(footprints allowed)
		)
		(placement
			(enabled no)
			(sheetname "")
		)
		(fill yes
			(thermal_gap 0.5)
			(thermal_bridge_width 0.5)
			(island_removal_mode 0)
		)
		(polygon
			(pts
				(arc
					(start 19.033998 -313.971432)
					(mid 19.048877 -314.007353)
					(end 19.084798 -314.022232)
				)
				(arc
					(start 20.484338 -314.022232)
					(mid 20.520259 -314.007353)
					(end 20.535138 -313.971432)
				)
				(arc
					(start 20.535138 -313.562492)
					(mid 20.520259 -313.526571)
					(end 20.484338 -313.511692)
				)
				(arc
					(start 19.084798 -313.511692)
					(mid 19.048877 -313.526571)
					(end 19.033998 -313.562492)
				)
			)
		)
	)
	(zone
		(layers "In1.Cu" "In2.Cu")
		(hatch none 0.5)
		(connect_pads
			(clearance 0)
		)
		(min_thickness 0.25)
		(keepout
			(tracks not_allowed)
			(vias allowed)
			(pads allowed)
			(copperpour not_allowed)
			(footprints allowed)
		)
		(placement
			(enabled no)
			(sheetname "")
		)
		(fill yes
			(thermal_gap 0.5)
			(thermal_bridge_width 0.5)
			(island_removal_mode 0)
		)
		(polygon
			(pts
				(arc
					(start 60.19673 -275.721318)
					(mid 60.211609 -275.757239)
					(end 60.24753 -275.772118)
				)
				(arc
					(start 61.64707 -275.772118)
					(mid 61.682991 -275.757239)
					(end 61.69787 -275.721318)
				)
				(arc
					(start 61.69787 -275.312378)
					(mid 61.682991 -275.276457)
					(end 61.64707 -275.261578)
				)
				(arc
					(start 60.24753 -275.261578)
					(mid 60.211609 -275.276457)
					(end 60.19673 -275.312378)
				)
			)
		)
	)
	(zone
		(layers "In1.Cu" "In2.Cu")
		(hatch none 0.5)
		(connect_pads
			(clearance 0)
		)
		(min_thickness 0.25)
		(keepout
			(tracks not_allowed)
			(vias allowed)
			(pads allowed)
			(copperpour not_allowed)
			(footprints allowed)
		)
		(placement
			(enabled no)
			(sheetname "")
		)
		(fill yes
			(thermal_gap 0.5)
			(thermal_bridge_width 0.5)
			(island_removal_mode 0)
		)
		(polygon
			(pts
				(arc
					(start 14.93393 -280.821384)
					(mid 14.948809 -280.857305)
					(end 14.98473 -280.872184)
				)
				(arc
					(start 16.38427 -280.872184)
					(mid 16.420191 -280.857305)
					(end 16.43507 -280.821384)
				)
				(arc
					(start 16.43507 -280.412444)
					(mid 16.420191 -280.376523)
					(end 16.38427 -280.361644)
				)
				(arc
					(start 14.98473 -280.361644)
					(mid 14.948809 -280.376523)
					(end 14.93393 -280.412444)
				)
			)
		)
	)
	(zone
		(layers "In1.Cu" "In2.Cu")
		(hatch none 0.5)
		(connect_pads
			(clearance 0)
		)
		(min_thickness 0.25)
		(keepout
			(tracks not_allowed)
			(vias allowed)
			(pads allowed)
			(copperpour not_allowed)
			(footprints allowed)
		)
		(placement
			(enabled no)
			(sheetname "")
		)
		(fill yes
			(thermal_gap 0.5)
			(thermal_bridge_width 0.5)
			(island_removal_mode 0)
		)
		(polygon
			(pts
				(arc
					(start 49.209198 -200.071482)
					(mid 49.224077 -200.107403)
					(end 49.259998 -200.122282)
				)
				(arc
					(start 50.659538 -200.122282)
					(mid 50.695459 -200.107403)
					(end 50.710338 -200.071482)
				)
				(arc
					(start 50.710338 -199.662542)
					(mid 50.695459 -199.626621)
					(end 50.659538 -199.611742)
				)
				(arc
					(start 49.259998 -199.611742)
					(mid 49.224077 -199.626621)
					(end 49.209198 -199.662542)
				)
			)
		)
	)
	(zone
		(layers "In1.Cu" "In2.Cu")
		(hatch none 0.5)
		(connect_pads
			(clearance 0)
		)
		(min_thickness 0.25)
		(keepout
			(tracks not_allowed)
			(vias allowed)
			(pads allowed)
			(copperpour not_allowed)
			(footprints allowed)
		)
		(placement
			(enabled no)
			(sheetname "")
		)
		(fill yes
			(thermal_gap 0.5)
			(thermal_bridge_width 0.5)
			(island_removal_mode 0)
		)
		(polygon
			(pts
				(arc
					(start 455.365866 -276.571456)
					(mid 455.380745 -276.607377)
					(end 455.416666 -276.622256)
				)
				(arc
					(start 456.816206 -276.622256)
					(mid 456.852127 -276.607377)
					(end 456.867006 -276.571456)
				)
				(arc
					(start 456.867006 -276.162516)
					(mid 456.852127 -276.126595)
					(end 456.816206 -276.111716)
				)
				(arc
					(start 455.416666 -276.111716)
					(mid 455.380745 -276.126595)
					(end 455.365866 -276.162516)
				)
			)
		)
	)
	(zone
		(layers "In1.Cu" "In2.Cu")
		(hatch none 0.5)
		(connect_pads
			(clearance 0)
		)
		(min_thickness 0.25)
		(keepout
			(tracks not_allowed)
			(vias allowed)
			(pads allowed)
			(copperpour not_allowed)
			(footprints allowed)
		)
		(placement
			(enabled no)
			(sheetname "")
		)
		(fill yes
			(thermal_gap 0.5)
			(thermal_bridge_width 0.5)
			(island_removal_mode 0)
		)
		(polygon
			(pts
				(arc
					(start 282.061666 -248.521474)
					(mid 282.076545 -248.557395)
					(end 282.112466 -248.572274)
				)
				(arc
					(start 283.512006 -248.572274)
					(mid 283.547927 -248.557395)
					(end 283.562806 -248.521474)
				)
				(arc
					(start 283.562806 -248.112534)
					(mid 283.547927 -248.076613)
					(end 283.512006 -248.061734)
				)
				(arc
					(start 282.112466 -248.061734)
					(mid 282.076545 -248.076613)
					(end 282.061666 -248.112534)
				)
			)
		)
	)
	(zone
		(layers "In1.Cu" "In2.Cu")
		(hatch none 0.5)
		(connect_pads
			(clearance 0)
		)
		(min_thickness 0.25)
		(keepout
			(tracks not_allowed)
			(vias allowed)
			(pads allowed)
			(copperpour not_allowed)
			(footprints allowed)
		)
		(placement
			(enabled no)
			(sheetname "")
		)
		(fill yes
			(thermal_gap 0.5)
			(thermal_bridge_width 0.5)
			(island_removal_mode 0)
		)
		(polygon
			(pts
				(arc
					(start 188.23813 -285.071312)
					(mid 188.253009 -285.107233)
					(end 188.28893 -285.122112)
				)
				(arc
					(start 189.68847 -285.122112)
					(mid 189.724391 -285.107233)
					(end 189.73927 -285.071312)
				)
				(arc
					(start 189.73927 -284.662372)
					(mid 189.724391 -284.626451)
					(end 189.68847 -284.611572)
				)
				(arc
					(start 188.28893 -284.611572)
					(mid 188.253009 -284.626451)
					(end 188.23813 -284.662372)
				)
			)
		)
	)
	(zone
		(layers "In1.Cu" "In2.Cu")
		(hatch none 0.5)
		(connect_pads
			(clearance 0)
		)
		(min_thickness 0.25)
		(keepout
			(tracks not_allowed)
			(vias allowed)
			(pads allowed)
			(copperpour not_allowed)
			(footprints allowed)
		)
		(placement
			(enabled no)
			(sheetname "")
		)
		(fill yes
			(thermal_gap 0.5)
			(thermal_bridge_width 0.5)
			(island_removal_mode 0)
		)
		(polygon
			(pts
				(arc
					(start 169.706798 -246.821452)
					(mid 169.721677 -246.857373)
					(end 169.757598 -246.872252)
				)
				(arc
					(start 171.157138 -246.872252)
					(mid 171.193059 -246.857373)
					(end 171.207938 -246.821452)
				)
				(arc
					(start 171.207938 -246.412512)
					(mid 171.193059 -246.376591)
					(end 171.157138 -246.361712)
				)
				(arc
					(start 169.757598 -246.361712)
					(mid 169.721677 -246.376591)
					(end 169.706798 -246.412512)
				)
			)
		)
	)
	(zone
		(layers "In1.Cu" "In2.Cu")
		(hatch none 0.5)
		(connect_pads
			(clearance 0)
		)
		(min_thickness 0.25)
		(keepout
			(tracks not_allowed)
			(vias allowed)
			(pads allowed)
			(copperpour not_allowed)
			(footprints allowed)
		)
		(placement
			(enabled no)
			(sheetname "")
		)
		(fill yes
			(thermal_gap 0.5)
			(thermal_bridge_width 0.5)
			(island_removal_mode 0)
		)
		(polygon
			(pts
				(arc
					(start 19.033998 -205.171548)
					(mid 19.048877 -205.207469)
					(end 19.084798 -205.222348)
				)
				(arc
					(start 20.484338 -205.222348)
					(mid 20.520259 -205.207469)
					(end 20.535138 -205.171548)
				)
				(arc
					(start 20.535138 -204.762608)
					(mid 20.520259 -204.726687)
					(end 20.484338 -204.711808)
				)
				(arc
					(start 19.084798 -204.711808)
					(mid 19.048877 -204.726687)
					(end 19.033998 -204.762608)
				)
			)
		)
	)
	(zone
		(layers "In1.Cu" "In2.Cu")
		(hatch none 0.5)
		(connect_pads
			(clearance 0)
		)
		(min_thickness 0.25)
		(keepout
			(tracks not_allowed)
			(vias allowed)
			(pads allowed)
			(copperpour not_allowed)
			(footprints allowed)
		)
		(placement
			(enabled no)
			(sheetname "")
		)
		(fill yes
			(thermal_gap 0.5)
			(thermal_bridge_width 0.5)
			(island_removal_mode 0)
		)
		(polygon
			(pts
				(arc
					(start 455.365866 -311.421526)
					(mid 455.380745 -311.457447)
					(end 455.416666 -311.472326)
				)
				(arc
					(start 456.816206 -311.472326)
					(mid 456.852127 -311.457447)
					(end 456.867006 -311.421526)
				)
				(arc
					(start 456.867006 -311.012586)
					(mid 456.852127 -310.976665)
					(end 456.816206 -310.961786)
				)
				(arc
					(start 455.416666 -310.961786)
					(mid 455.380745 -310.976665)
					(end 455.365866 -311.012586)
				)
			)
		)
	)
	(zone
		(layers "In1.Cu" "In2.Cu")
		(hatch none 0.5)
		(connect_pads
			(clearance 0)
		)
		(min_thickness 0.25)
		(keepout
			(tracks not_allowed)
			(vias allowed)
			(pads allowed)
			(copperpour not_allowed)
			(footprints allowed)
		)
		(placement
			(enabled no)
			(sheetname "")
		)
		(fill yes
			(thermal_gap 0.5)
			(thermal_bridge_width 0.5)
			(island_removal_mode 0)
		)
		(polygon
			(pts
				(arc
					(start 289.605466 -209.421476)
					(mid 289.620345 -209.457397)
					(end 289.656266 -209.472276)
				)
				(arc
					(start 291.055806 -209.472276)
					(mid 291.091727 -209.457397)
					(end 291.106606 -209.421476)
				)
				(arc
					(start 291.106606 -209.012536)
					(mid 291.091727 -208.976615)
					(end 291.055806 -208.961736)
				)
				(arc
					(start 289.656266 -208.961736)
					(mid 289.620345 -208.976615)
					(end 289.605466 -209.012536)
				)
			)
		)
	)
	(zone
		(layers "In1.Cu" "In2.Cu")
		(hatch none 0.5)
		(connect_pads
			(clearance 0)
		)
		(min_thickness 0.25)
		(keepout
			(tracks not_allowed)
			(vias allowed)
			(pads allowed)
			(copperpour not_allowed)
			(footprints allowed)
		)
		(placement
			(enabled no)
			(sheetname "")
		)
		(fill yes
			(thermal_gap 0.5)
			(thermal_bridge_width 0.5)
			(island_removal_mode 0)
		)
		(polygon
			(pts
				(arc
					(start 443.721998 -235.771436)
					(mid 443.736877 -235.807357)
					(end 443.772798 -235.822236)
				)
				(arc
					(start 445.172338 -235.822236)
					(mid 445.208259 -235.807357)
					(end 445.223138 -235.771436)
				)
				(arc
					(start 445.223138 -235.362496)
					(mid 445.208259 -235.326575)
					(end 445.172338 -235.311696)
				)
				(arc
					(start 443.772798 -235.311696)
					(mid 443.736877 -235.326575)
					(end 443.721998 -235.362496)
				)
			)
		)
	)
	(zone
		(layers "In1.Cu" "In2.Cu")
		(hatch none 0.5)
		(connect_pads
			(clearance 0)
		)
		(min_thickness 0.25)
		(keepout
			(tracks not_allowed)
			(vias allowed)
			(pads allowed)
			(copperpour not_allowed)
			(footprints allowed)
		)
		(placement
			(enabled no)
			(sheetname "")
		)
		(fill yes
			(thermal_gap 0.5)
			(thermal_bridge_width 0.5)
			(island_removal_mode 0)
		)
		(polygon
			(pts
				(arc
					(start 428.634398 -221.321376)
					(mid 428.649277 -221.357297)
					(end 428.685198 -221.372176)
				)
				(arc
					(start 430.084738 -221.372176)
					(mid 430.120659 -221.357297)
					(end 430.135538 -221.321376)
				)
				(arc
					(start 430.135538 -220.912436)
					(mid 430.120659 -220.876515)
					(end 430.084738 -220.861636)
				)
				(arc
					(start 428.685198 -220.861636)
					(mid 428.649277 -220.876515)
					(end 428.634398 -220.912436)
				)
			)
		)
	)
	(zone
		(layers "In1.Cu" "In2.Cu")
		(hatch none 0.5)
		(connect_pads
			(clearance 0)
		)
		(min_thickness 0.25)
		(keepout
			(tracks not_allowed)
			(vias allowed)
			(pads allowed)
			(copperpour not_allowed)
			(footprints allowed)
		)
		(placement
			(enabled no)
			(sheetname "")
		)
		(fill yes
			(thermal_gap 0.5)
			(thermal_bridge_width 0.5)
			(island_removal_mode 0)
		)
		(polygon
			(pts
				(arc
					(start 421.090598 -213.671404)
					(mid 421.105477 -213.707325)
					(end 421.141398 -213.722204)
				)
				(arc
					(start 422.540938 -213.722204)
					(mid 422.576859 -213.707325)
					(end 422.591738 -213.671404)
				)
				(arc
					(start 422.591738 -213.262464)
					(mid 422.576859 -213.226543)
					(end 422.540938 -213.211664)
				)
				(arc
					(start 421.141398 -213.211664)
					(mid 421.105477 -213.226543)
					(end 421.090598 -213.262464)
				)
			)
		)
	)
	(zone
		(layers "In1.Cu" "In2.Cu")
		(hatch none 0.5)
		(connect_pads
			(clearance 0)
		)
		(min_thickness 0.25)
		(keepout
			(tracks not_allowed)
			(vias allowed)
			(pads allowed)
			(copperpour not_allowed)
			(footprints allowed)
		)
		(placement
			(enabled no)
			(sheetname "")
		)
		(fill yes
			(thermal_gap 0.5)
			(thermal_bridge_width 0.5)
			(island_removal_mode 0)
		)
		(polygon
			(pts
				(arc
					(start 259.430266 -234.921298)
					(mid 259.445145 -234.957219)
					(end 259.481066 -234.972098)
				)
				(arc
					(start 260.880606 -234.972098)
					(mid 260.916527 -234.957219)
					(end 260.931406 -234.921298)
				)
				(arc
					(start 260.931406 -234.512358)
					(mid 260.916527 -234.476437)
					(end 260.880606 -234.461558)
				)
				(arc
					(start 259.481066 -234.461558)
					(mid 259.445145 -234.476437)
					(end 259.430266 -234.512358)
				)
			)
		)
	)
	(zone
		(layers "In1.Cu" "In2.Cu")
		(hatch none 0.5)
		(connect_pads
			(clearance 0)
		)
		(min_thickness 0.25)
		(keepout
			(tracks not_allowed)
			(vias allowed)
			(pads allowed)
			(copperpour not_allowed)
			(footprints allowed)
		)
		(placement
			(enabled no)
			(sheetname "")
		)
		(fill yes
			(thermal_gap 0.5)
			(thermal_bridge_width 0.5)
			(island_removal_mode 0)
		)
		(polygon
			(pts
				(arc
					(start 293.049198 -293.571422)
					(mid 293.064077 -293.607343)
					(end 293.099998 -293.622222)
				)
				(arc
					(start 294.499538 -293.622222)
					(mid 294.535459 -293.607343)
					(end 294.550338 -293.571422)
				)
				(arc
					(start 294.550338 -293.162482)
					(mid 294.535459 -293.126561)
					(end 294.499538 -293.111682)
				)
				(arc
					(start 293.099998 -293.111682)
					(mid 293.064077 -293.126561)
					(end 293.049198 -293.162482)
				)
			)
		)
	)
	(zone
		(layers "In1.Cu" "In2.Cu")
		(hatch none 0.5)
		(connect_pads
			(clearance 0)
		)
		(min_thickness 0.25)
		(keepout
			(tracks not_allowed)
			(vias allowed)
			(pads allowed)
			(copperpour not_allowed)
			(footprints allowed)
		)
		(placement
			(enabled no)
			(sheetname "")
		)
		(fill yes
			(thermal_gap 0.5)
			(thermal_bridge_width 0.5)
			(island_removal_mode 0)
		)
		(polygon
			(pts
				(arc
					(start 282.061666 -260.421374)
					(mid 282.076545 -260.457295)
					(end 282.112466 -260.472174)
				)
				(arc
					(start 283.512006 -260.472174)
					(mid 283.547927 -260.457295)
					(end 283.562806 -260.421374)
				)
				(arc
					(start 283.562806 -260.012434)
					(mid 283.547927 -259.976513)
					(end 283.512006 -259.961634)
				)
				(arc
					(start 282.112466 -259.961634)
					(mid 282.076545 -259.976513)
					(end 282.061666 -260.012434)
				)
			)
		)
	)
	(zone
		(layers "In1.Cu" "In2.Cu")
		(hatch none 0.5)
		(connect_pads
			(clearance 0)
		)
		(min_thickness 0.25)
		(keepout
			(tracks not_allowed)
			(vias allowed)
			(pads allowed)
			(copperpour not_allowed)
			(footprints allowed)
		)
		(placement
			(enabled no)
			(sheetname "")
		)
		(fill yes
			(thermal_gap 0.5)
			(thermal_bridge_width 0.5)
			(island_removal_mode 0)
		)
		(polygon
			(pts
				(arc
					(start 64.296798 -296.971466)
					(mid 64.311677 -297.007387)
					(end 64.347598 -297.022266)
				)
				(arc
					(start 65.747138 -297.022266)
					(mid 65.783059 -297.007387)
					(end 65.797938 -296.971466)
				)
				(arc
					(start 65.797938 -296.562526)
					(mid 65.783059 -296.526605)
					(end 65.747138 -296.511726)
				)
				(arc
					(start 64.347598 -296.511726)
					(mid 64.311677 -296.526605)
					(end 64.296798 -296.562526)
				)
			)
		)
	)
	(zone
		(layers "In1.Cu" "In2.Cu")
		(hatch none 0.5)
		(connect_pads
			(clearance 0)
		)
		(min_thickness 0.25)
		(keepout
			(tracks not_allowed)
			(vias allowed)
			(pads allowed)
			(copperpour not_allowed)
			(footprints allowed)
		)
		(placement
			(enabled no)
			(sheetname "")
		)
		(fill yes
			(thermal_gap 0.5)
			(thermal_bridge_width 0.5)
			(island_removal_mode 0)
		)
		(polygon
			(pts
				(arc
					(start 37.56533 -262.971534)
					(mid 37.580209 -263.007455)
					(end 37.61613 -263.022334)
				)
				(arc
					(start 39.01567 -263.022334)
					(mid 39.051591 -263.007455)
					(end 39.06647 -262.971534)
				)
				(arc
					(start 39.06647 -262.562594)
					(mid 39.051591 -262.526673)
					(end 39.01567 -262.511794)
				)
				(arc
					(start 37.61613 -262.511794)
					(mid 37.580209 -262.526673)
					(end 37.56533 -262.562594)
				)
			)
		)
	)
	(zone
		(layers "In1.Cu" "In2.Cu")
		(hatch none 0.5)
		(connect_pads
			(clearance 0)
		)
		(min_thickness 0.25)
		(keepout
			(tracks not_allowed)
			(vias allowed)
			(pads allowed)
			(copperpour not_allowed)
			(footprints allowed)
		)
		(placement
			(enabled no)
			(sheetname "")
		)
		(fill yes
			(thermal_gap 0.5)
			(thermal_bridge_width 0.5)
			(island_removal_mode 0)
		)
		(polygon
			(pts
				(arc
					(start 165.60673 -240.021364)
					(mid 165.621609 -240.057285)
					(end 165.65753 -240.072164)
				)
				(arc
					(start 167.05707 -240.072164)
					(mid 167.092991 -240.057285)
					(end 167.10787 -240.021364)
				)
				(arc
					(start 167.10787 -239.612424)
					(mid 167.092991 -239.576503)
					(end 167.05707 -239.561624)
				)
				(arc
					(start 165.65753 -239.561624)
					(mid 165.621609 -239.576503)
					(end 165.60673 -239.612424)
				)
			)
		)
	)
	(zone
		(layers "In1.Cu" "In2.Cu")
		(hatch none 0.5)
		(connect_pads
			(clearance 0)
		)
		(min_thickness 0.25)
		(keepout
			(tracks not_allowed)
			(vias allowed)
			(pads allowed)
			(copperpour not_allowed)
			(footprints allowed)
		)
		(placement
			(enabled no)
			(sheetname "")
		)
		(fill yes
			(thermal_gap 0.5)
			(thermal_bridge_width 0.5)
			(island_removal_mode 0)
		)
		(polygon
			(pts
				(arc
					(start 173.15053 -200.071482)
					(mid 173.165409 -200.107403)
					(end 173.20133 -200.122282)
				)
				(arc
					(start 174.60087 -200.122282)
					(mid 174.636791 -200.107403)
					(end 174.65167 -200.071482)
				)
				(arc
					(start 174.65167 -199.662542)
					(mid 174.636791 -199.626621)
					(end 174.60087 -199.611742)
				)
				(arc
					(start 173.20133 -199.611742)
					(mid 173.165409 -199.626621)
					(end 173.15053 -199.662542)
				)
			)
		)
	)
	(zone
		(layers "In1.Cu" "In2.Cu")
		(hatch none 0.5)
		(connect_pads
			(clearance 0)
		)
		(min_thickness 0.25)
		(keepout
			(tracks not_allowed)
			(vias allowed)
			(pads allowed)
			(copperpour not_allowed)
			(footprints allowed)
		)
		(placement
			(enabled no)
			(sheetname "")
		)
		(fill yes
			(thermal_gap 0.5)
			(thermal_bridge_width 0.5)
			(island_removal_mode 0)
		)
		(polygon
			(pts
				(arc
					(start 41.665398 -281.671522)
					(mid 41.680277 -281.707443)
					(end 41.716198 -281.722322)
				)
				(arc
					(start 43.115738 -281.722322)
					(mid 43.151659 -281.707443)
					(end 43.166538 -281.671522)
				)
				(arc
					(start 43.166538 -281.262582)
					(mid 43.151659 -281.226661)
					(end 43.115738 -281.211782)
				)
				(arc
					(start 41.716198 -281.211782)
					(mid 41.680277 -281.226661)
					(end 41.665398 -281.262582)
				)
			)
		)
	)
	(zone
		(layers "In1.Cu" "In2.Cu")
		(hatch none 0.5)
		(connect_pads
			(clearance 0)
		)
		(min_thickness 0.25)
		(keepout
			(tracks not_allowed)
			(vias allowed)
			(pads allowed)
			(copperpour not_allowed)
			(footprints allowed)
		)
		(placement
			(enabled no)
			(sheetname "")
		)
		(fill yes
			(thermal_gap 0.5)
			(thermal_bridge_width 0.5)
			(island_removal_mode 0)
		)
		(polygon
			(pts
				(arc
					(start 214.969598 -300.37151)
					(mid 214.984477 -300.407431)
					(end 215.020398 -300.42231)
				)
				(arc
					(start 216.419938 -300.42231)
					(mid 216.455859 -300.407431)
					(end 216.470738 -300.37151)
				)
				(arc
					(start 216.470738 -299.96257)
					(mid 216.455859 -299.926649)
					(end 216.419938 -299.91177)
				)
				(arc
					(start 215.020398 -299.91177)
					(mid 214.984477 -299.926649)
					(end 214.969598 -299.96257)
				)
			)
		)
	)
	(zone
		(layers "In1.Cu" "In2.Cu")
		(hatch none 0.5)
		(connect_pads
			(clearance 0)
		)
		(min_thickness 0.25)
		(keepout
			(tracks not_allowed)
			(vias allowed)
			(pads allowed)
			(copperpour not_allowed)
			(footprints allowed)
		)
		(placement
			(enabled no)
			(sheetname "")
		)
		(fill yes
			(thermal_gap 0.5)
			(thermal_bridge_width 0.5)
			(island_removal_mode 0)
		)
		(polygon
			(pts
				(arc
					(start 207.425798 -287.621472)
					(mid 207.440677 -287.657393)
					(end 207.476598 -287.672272)
				)
				(arc
					(start 208.876138 -287.672272)
					(mid 208.912059 -287.657393)
					(end 208.926938 -287.621472)
				)
				(arc
					(start 208.926938 -287.212532)
					(mid 208.912059 -287.176611)
					(end 208.876138 -287.161732)
				)
				(arc
					(start 207.476598 -287.161732)
					(mid 207.440677 -287.176611)
					(end 207.425798 -287.212532)
				)
			)
		)
	)
	(zone
		(layers "In1.Cu" "In2.Cu")
		(hatch none 0.5)
		(connect_pads
			(clearance 0)
		)
		(min_thickness 0.25)
		(keepout
			(tracks not_allowed)
			(vias allowed)
			(pads allowed)
			(copperpour not_allowed)
			(footprints allowed)
		)
		(placement
			(enabled no)
			(sheetname "")
		)
		(fill yes
			(thermal_gap 0.5)
			(thermal_bridge_width 0.5)
			(island_removal_mode 0)
		)
		(polygon
			(pts
				(arc
					(start 297.149266 -208.571338)
					(mid 297.164145 -208.607259)
					(end 297.200066 -208.622138)
				)
				(arc
					(start 298.599606 -208.622138)
					(mid 298.635527 -208.607259)
					(end 298.650406 -208.571338)
				)
				(arc
					(start 298.650406 -208.162398)
					(mid 298.635527 -208.126477)
					(end 298.599606 -208.111598)
				)
				(arc
					(start 297.200066 -208.111598)
					(mid 297.164145 -208.126477)
					(end 297.149266 -208.162398)
				)
			)
		)
	)
	(zone
		(layers "In1.Cu" "In2.Cu")
		(hatch none 0.5)
		(connect_pads
			(clearance 0)
		)
		(min_thickness 0.25)
		(keepout
			(tracks not_allowed)
			(vias allowed)
			(pads allowed)
			(copperpour not_allowed)
			(footprints allowed)
		)
		(placement
			(enabled no)
			(sheetname "")
		)
		(fill yes
			(thermal_gap 0.5)
			(thermal_bridge_width 0.5)
			(island_removal_mode 0)
		)
		(polygon
			(pts
				(arc
					(start 60.19673 -273.171412)
					(mid 60.211609 -273.207333)
					(end 60.24753 -273.222212)
				)
				(arc
					(start 61.64707 -273.222212)
					(mid 61.682991 -273.207333)
					(end 61.69787 -273.171412)
				)
				(arc
					(start 61.69787 -272.762472)
					(mid 61.682991 -272.726551)
					(end 61.64707 -272.711672)
				)
				(arc
					(start 60.24753 -272.711672)
					(mid 60.211609 -272.726551)
					(end 60.19673 -272.762472)
				)
			)
		)
	)
	(zone
		(layers "In1.Cu" "In2.Cu")
		(hatch none 0.5)
		(connect_pads
			(clearance 0)
		)
		(min_thickness 0.25)
		(keepout
			(tracks not_allowed)
			(vias allowed)
			(pads allowed)
			(copperpour not_allowed)
			(footprints allowed)
		)
		(placement
			(enabled no)
			(sheetname "")
		)
		(fill yes
			(thermal_gap 0.5)
			(thermal_bridge_width 0.5)
			(island_removal_mode 0)
		)
		(polygon
			(pts
				(arc
					(start 428.634398 -293.571422)
					(mid 428.649277 -293.607343)
					(end 428.685198 -293.622222)
				)
				(arc
					(start 430.084738 -293.622222)
					(mid 430.120659 -293.607343)
					(end 430.135538 -293.571422)
				)
				(arc
					(start 430.135538 -293.162482)
					(mid 430.120659 -293.126561)
					(end 430.084738 -293.111682)
				)
				(arc
					(start 428.685198 -293.111682)
					(mid 428.649277 -293.126561)
					(end 428.634398 -293.162482)
				)
			)
		)
	)
	(zone
		(layers "In1.Cu" "In2.Cu")
		(hatch none 0.5)
		(connect_pads
			(clearance 0)
		)
		(min_thickness 0.25)
		(keepout
			(tracks not_allowed)
			(vias allowed)
			(pads allowed)
			(copperpour not_allowed)
			(footprints allowed)
		)
		(placement
			(enabled no)
			(sheetname "")
		)
		(fill yes
			(thermal_gap 0.5)
			(thermal_bridge_width 0.5)
			(island_removal_mode 0)
		)
		(polygon
			(pts
				(arc
					(start 432.734466 -218.77147)
					(mid 432.749345 -218.807391)
					(end 432.785266 -218.82227)
				)
				(arc
					(start 434.184806 -218.82227)
					(mid 434.220727 -218.807391)
					(end 434.235606 -218.77147)
				)
				(arc
					(start 434.235606 -218.36253)
					(mid 434.220727 -218.326609)
					(end 434.184806 -218.31173)
				)
				(arc
					(start 432.785266 -218.31173)
					(mid 432.749345 -218.326609)
					(end 432.734466 -218.36253)
				)
			)
		)
	)
	(zone
		(layers "In1.Cu" "In2.Cu")
		(hatch none 0.5)
		(connect_pads
			(clearance 0)
		)
		(min_thickness 0.25)
		(keepout
			(tracks not_allowed)
			(vias allowed)
			(pads allowed)
			(copperpour not_allowed)
			(footprints allowed)
		)
		(placement
			(enabled no)
			(sheetname "")
		)
		(fill yes
			(thermal_gap 0.5)
			(thermal_bridge_width 0.5)
			(island_removal_mode 0)
		)
		(polygon
			(pts
				(arc
					(start 285.505398 -243.421408)
					(mid 285.520277 -243.457329)
					(end 285.556198 -243.472208)
				)
				(arc
					(start 286.955738 -243.472208)
					(mid 286.991659 -243.457329)
					(end 287.006538 -243.421408)
				)
				(arc
					(start 287.006538 -243.012468)
					(mid 286.991659 -242.976547)
					(end 286.955738 -242.961668)
				)
				(arc
					(start 285.556198 -242.961668)
					(mid 285.520277 -242.976547)
					(end 285.505398 -243.012468)
				)
			)
		)
	)
	(zone
		(layers "In1.Cu" "In2.Cu")
		(hatch none 0.5)
		(connect_pads
			(clearance 0)
		)
		(min_thickness 0.25)
		(keepout
			(tracks not_allowed)
			(vias allowed)
			(pads allowed)
			(copperpour not_allowed)
			(footprints allowed)
		)
		(placement
			(enabled no)
			(sheetname "")
		)
		(fill yes
			(thermal_gap 0.5)
			(thermal_bridge_width 0.5)
			(island_removal_mode 0)
		)
		(polygon
			(pts
				(arc
					(start 413.546798 -286.771334)
					(mid 413.561677 -286.807255)
					(end 413.597598 -286.822134)
				)
				(arc
					(start 414.997138 -286.822134)
					(mid 415.033059 -286.807255)
					(end 415.047938 -286.771334)
				)
				(arc
					(start 415.047938 -286.362394)
					(mid 415.033059 -286.326473)
					(end 414.997138 -286.311594)
				)
				(arc
					(start 413.597598 -286.311594)
					(mid 413.561677 -286.326473)
					(end 413.546798 -286.362394)
				)
			)
		)
	)
	(zone
		(layers "In1.Cu" "In2.Cu")
		(hatch none 0.5)
		(connect_pads
			(clearance 0)
		)
		(min_thickness 0.25)
		(keepout
			(tracks not_allowed)
			(vias allowed)
			(pads allowed)
			(copperpour not_allowed)
			(footprints allowed)
		)
		(placement
			(enabled no)
			(sheetname "")
		)
		(fill yes
			(thermal_gap 0.5)
			(thermal_bridge_width 0.5)
			(island_removal_mode 0)
		)
		(polygon
			(pts
				(arc
					(start 455.365866 -203.471526)
					(mid 455.380745 -203.507447)
					(end 455.416666 -203.522326)
				)
				(arc
					(start 456.816206 -203.522326)
					(mid 456.852127 -203.507447)
					(end 456.867006 -203.471526)
				)
				(arc
					(start 456.867006 -203.062586)
					(mid 456.852127 -203.026665)
					(end 456.816206 -203.011786)
				)
				(arc
					(start 455.416666 -203.011786)
					(mid 455.380745 -203.026665)
					(end 455.365866 -203.062586)
				)
			)
		)
	)
	(zone
		(layers "In1.Cu" "In2.Cu")
		(hatch none 0.5)
		(connect_pads
			(clearance 0)
		)
		(min_thickness 0.25)
		(keepout
			(tracks not_allowed)
			(vias allowed)
			(pads allowed)
			(copperpour not_allowed)
			(footprints allowed)
		)
		(placement
			(enabled no)
			(sheetname "")
		)
		(fill yes
			(thermal_gap 0.5)
			(thermal_bridge_width 0.5)
			(island_removal_mode 0)
		)
		(polygon
			(pts
				(arc
					(start 462.909666 -308.021482)
					(mid 462.924545 -308.057403)
					(end 462.960466 -308.072282)
				)
				(arc
					(start 464.360006 -308.072282)
					(mid 464.395927 -308.057403)
					(end 464.410806 -308.021482)
				)
				(arc
					(start 464.410806 -307.612542)
					(mid 464.395927 -307.576621)
					(end 464.360006 -307.561742)
				)
				(arc
					(start 462.960466 -307.561742)
					(mid 462.924545 -307.576621)
					(end 462.909666 -307.612542)
				)
			)
		)
	)
	(zone
		(layers "In1.Cu" "In2.Cu")
		(hatch none 0.5)
		(connect_pads
			(clearance 0)
		)
		(min_thickness 0.25)
		(keepout
			(tracks not_allowed)
			(vias allowed)
			(pads allowed)
			(copperpour not_allowed)
			(footprints allowed)
		)
		(placement
			(enabled no)
			(sheetname "")
		)
		(fill yes
			(thermal_gap 0.5)
			(thermal_bridge_width 0.5)
			(island_removal_mode 0)
		)
		(polygon
			(pts
				(arc
					(start 180.69433 -285.071312)
					(mid 180.709209 -285.107233)
					(end 180.74513 -285.122112)
				)
				(arc
					(start 182.14467 -285.122112)
					(mid 182.180591 -285.107233)
					(end 182.19547 -285.071312)
				)
				(arc
					(start 182.19547 -284.662372)
					(mid 182.180591 -284.626451)
					(end 182.14467 -284.611572)
				)
				(arc
					(start 180.74513 -284.611572)
					(mid 180.709209 -284.626451)
					(end 180.69433 -284.662372)
				)
			)
		)
	)
	(zone
		(layers "In1.Cu" "In2.Cu")
		(hatch none 0.5)
		(connect_pads
			(clearance 0)
		)
		(min_thickness 0.25)
		(keepout
			(tracks not_allowed)
			(vias allowed)
			(pads allowed)
			(copperpour not_allowed)
			(footprints allowed)
		)
		(placement
			(enabled no)
			(sheetname "")
		)
		(fill yes
			(thermal_gap 0.5)
			(thermal_bridge_width 0.5)
			(island_removal_mode 0)
		)
		(polygon
			(pts
				(arc
					(start 300.592998 -240.021364)
					(mid 300.607877 -240.057285)
					(end 300.643798 -240.072164)
				)
				(arc
					(start 302.043338 -240.072164)
					(mid 302.079259 -240.057285)
					(end 302.094138 -240.021364)
				)
				(arc
					(start 302.094138 -239.612424)
					(mid 302.079259 -239.576503)
					(end 302.043338 -239.561624)
				)
				(arc
					(start 300.643798 -239.561624)
					(mid 300.607877 -239.576503)
					(end 300.592998 -239.612424)
				)
			)
		)
	)
	(zone
		(layers "In1.Cu" "In2.Cu")
		(hatch none 0.5)
		(connect_pads
			(clearance 0)
		)
		(min_thickness 0.25)
		(keepout
			(tracks not_allowed)
			(vias allowed)
			(pads allowed)
			(copperpour not_allowed)
			(footprints allowed)
		)
		(placement
			(enabled no)
			(sheetname "")
		)
		(fill yes
			(thermal_gap 0.5)
			(thermal_bridge_width 0.5)
			(island_removal_mode 0)
		)
		(polygon
			(pts
				(arc
					(start 158.06293 -294.421306)
					(mid 158.077809 -294.457227)
					(end 158.11373 -294.472106)
				)
				(arc
					(start 159.51327 -294.472106)
					(mid 159.549191 -294.457227)
					(end 159.56407 -294.421306)
				)
				(arc
					(start 159.56407 -294.012366)
					(mid 159.549191 -293.976445)
					(end 159.51327 -293.961566)
				)
				(arc
					(start 158.11373 -293.961566)
					(mid 158.077809 -293.976445)
					(end 158.06293 -294.012366)
				)
			)
		)
	)
	(zone
		(layers "In1.Cu" "In2.Cu")
		(hatch none 0.5)
		(connect_pads
			(clearance 0)
		)
		(min_thickness 0.25)
		(keepout
			(tracks not_allowed)
			(vias allowed)
			(pads allowed)
			(copperpour not_allowed)
			(footprints allowed)
		)
		(placement
			(enabled no)
			(sheetname "")
		)
		(fill yes
			(thermal_gap 0.5)
			(thermal_bridge_width 0.5)
			(island_removal_mode 0)
		)
		(polygon
			(pts
				(arc
					(start 285.505398 -279.121362)
					(mid 285.520277 -279.157283)
					(end 285.556198 -279.172162)
				)
				(arc
					(start 286.955738 -279.172162)
					(mid 286.991659 -279.157283)
					(end 287.006538 -279.121362)
				)
				(arc
					(start 287.006538 -278.712422)
					(mid 286.991659 -278.676501)
					(end 286.955738 -278.661622)
				)
				(arc
					(start 285.556198 -278.661622)
					(mid 285.520277 -278.676501)
					(end 285.505398 -278.712422)
				)
			)
		)
	)
	(zone
		(layers "In1.Cu" "In2.Cu")
		(hatch none 0.5)
		(connect_pads
			(clearance 0)
		)
		(min_thickness 0.25)
		(keepout
			(tracks not_allowed)
			(vias allowed)
			(pads allowed)
			(copperpour not_allowed)
			(footprints allowed)
		)
		(placement
			(enabled no)
			(sheetname "")
		)
		(fill yes
			(thermal_gap 0.5)
			(thermal_bridge_width 0.5)
			(island_removal_mode 0)
		)
		(polygon
			(pts
				(arc
					(start 162.162998 -274.871434)
					(mid 162.177877 -274.907355)
					(end 162.213798 -274.922234)
				)
				(arc
					(start 163.613338 -274.922234)
					(mid 163.649259 -274.907355)
					(end 163.664138 -274.871434)
				)
				(arc
					(start 163.664138 -274.462494)
					(mid 163.649259 -274.426573)
					(end 163.613338 -274.411694)
				)
				(arc
					(start 162.213798 -274.411694)
					(mid 162.177877 -274.426573)
					(end 162.162998 -274.462494)
				)
			)
		)
	)
	(zone
		(layers "In1.Cu" "In2.Cu")
		(hatch none 0.5)
		(connect_pads
			(clearance 0)
		)
		(min_thickness 0.25)
		(keepout
			(tracks not_allowed)
			(vias allowed)
			(pads allowed)
			(copperpour not_allowed)
			(footprints allowed)
		)
		(placement
			(enabled no)
			(sheetname "")
		)
		(fill yes
			(thermal_gap 0.5)
			(thermal_bridge_width 0.5)
			(island_removal_mode 0)
		)
		(polygon
			(pts
				(arc
					(start 56.752998 -206.871316)
					(mid 56.767877 -206.907237)
					(end 56.803798 -206.922116)
				)
				(arc
					(start 58.203338 -206.922116)
					(mid 58.239259 -206.907237)
					(end 58.254138 -206.871316)
				)
				(arc
					(start 58.254138 -206.462376)
					(mid 58.239259 -206.426455)
					(end 58.203338 -206.411576)
				)
				(arc
					(start 56.803798 -206.411576)
					(mid 56.767877 -206.426455)
					(end 56.752998 -206.462376)
				)
			)
		)
	)
	(zone
		(layers "In1.Cu" "In2.Cu")
		(hatch none 0.5)
		(connect_pads
			(clearance 0)
		)
		(min_thickness 0.25)
		(keepout
			(tracks not_allowed)
			(vias allowed)
			(pads allowed)
			(copperpour not_allowed)
			(footprints allowed)
		)
		(placement
			(enabled no)
			(sheetname "")
		)
		(fill yes
			(thermal_gap 0.5)
			(thermal_bridge_width 0.5)
			(island_removal_mode 0)
		)
		(polygon
			(pts
				(arc
					(start 262.873998 -291.8714)
					(mid 262.888877 -291.907321)
					(end 262.924798 -291.9222)
				)
				(arc
					(start 264.324338 -291.9222)
					(mid 264.360259 -291.907321)
					(end 264.375138 -291.8714)
				)
				(arc
					(start 264.375138 -291.46246)
					(mid 264.360259 -291.426539)
					(end 264.324338 -291.41166)
				)
				(arc
					(start 262.924798 -291.41166)
					(mid 262.888877 -291.426539)
					(end 262.873998 -291.46246)
				)
			)
		)
	)
	(zone
		(layers "In1.Cu" "In2.Cu")
		(hatch none 0.5)
		(connect_pads
			(clearance 0)
		)
		(min_thickness 0.25)
		(keepout
			(tracks not_allowed)
			(vias allowed)
			(pads allowed)
			(copperpour not_allowed)
			(footprints allowed)
		)
		(placement
			(enabled no)
			(sheetname "")
		)
		(fill yes
			(thermal_gap 0.5)
			(thermal_bridge_width 0.5)
			(island_removal_mode 0)
		)
		(polygon
			(pts
				(arc
					(start 274.517866 -214.521542)
					(mid 274.532745 -214.557463)
					(end 274.568666 -214.572342)
				)
				(arc
					(start 275.968206 -214.572342)
					(mid 276.004127 -214.557463)
					(end 276.019006 -214.521542)
				)
				(arc
					(start 276.019006 -214.112602)
					(mid 276.004127 -214.076681)
					(end 275.968206 -214.061802)
				)
				(arc
					(start 274.568666 -214.061802)
					(mid 274.532745 -214.076681)
					(end 274.517866 -214.112602)
				)
			)
		)
	)
	(zone
		(layers "In1.Cu" "In2.Cu")
		(hatch none 0.5)
		(connect_pads
			(clearance 0)
		)
		(min_thickness 0.25)
		(keepout
			(tracks not_allowed)
			(vias allowed)
			(pads allowed)
			(copperpour not_allowed)
			(footprints allowed)
		)
		(placement
			(enabled no)
			(sheetname "")
		)
		(fill yes
			(thermal_gap 0.5)
			(thermal_bridge_width 0.5)
			(island_removal_mode 0)
		)
		(polygon
			(pts
				(arc
					(start 293.049198 -279.121362)
					(mid 293.064077 -279.157283)
					(end 293.099998 -279.172162)
				)
				(arc
					(start 294.499538 -279.172162)
					(mid 294.535459 -279.157283)
					(end 294.550338 -279.121362)
				)
				(arc
					(start 294.550338 -278.712422)
					(mid 294.535459 -278.676501)
					(end 294.499538 -278.661622)
				)
				(arc
					(start 293.099998 -278.661622)
					(mid 293.064077 -278.676501)
					(end 293.049198 -278.712422)
				)
			)
		)
	)
	(zone
		(layers "In1.Cu" "In2.Cu")
		(hatch none 0.5)
		(connect_pads
			(clearance 0)
		)
		(min_thickness 0.25)
		(keepout
			(tracks not_allowed)
			(vias allowed)
			(pads allowed)
			(copperpour not_allowed)
			(footprints allowed)
		)
		(placement
			(enabled no)
			(sheetname "")
		)
		(fill yes
			(thermal_gap 0.5)
			(thermal_bridge_width 0.5)
			(island_removal_mode 0)
		)
		(polygon
			(pts
				(arc
					(start 308.136798 -244.271292)
					(mid 308.151677 -244.307213)
					(end 308.187598 -244.322092)
				)
				(arc
					(start 309.587138 -244.322092)
					(mid 309.623059 -244.307213)
					(end 309.637938 -244.271292)
				)
				(arc
					(start 309.637938 -243.862352)
					(mid 309.623059 -243.826431)
					(end 309.587138 -243.811552)
				)
				(arc
					(start 308.187598 -243.811552)
					(mid 308.151677 -243.826431)
					(end 308.136798 -243.862352)
				)
			)
		)
	)
	(zone
		(layers "In1.Cu" "In2.Cu")
		(hatch none 0.5)
		(connect_pads
			(clearance 0)
		)
		(min_thickness 0.25)
		(keepout
			(tracks not_allowed)
			(vias allowed)
			(pads allowed)
			(copperpour not_allowed)
			(footprints allowed)
		)
		(placement
			(enabled no)
			(sheetname "")
		)
		(fill yes
			(thermal_gap 0.5)
			(thermal_bridge_width 0.5)
			(island_removal_mode 0)
		)
		(polygon
			(pts
				(arc
					(start 417.646866 -293.571422)
					(mid 417.661745 -293.607343)
					(end 417.697666 -293.622222)
				)
				(arc
					(start 419.097206 -293.622222)
					(mid 419.133127 -293.607343)
					(end 419.148006 -293.571422)
				)
				(arc
					(start 419.148006 -293.162482)
					(mid 419.133127 -293.126561)
					(end 419.097206 -293.111682)
				)
				(arc
					(start 417.697666 -293.111682)
					(mid 417.661745 -293.126561)
					(end 417.646866 -293.162482)
				)
			)
		)
	)
	(zone
		(layers "In1.Cu" "In2.Cu")
		(hatch none 0.5)
		(connect_pads
			(clearance 0)
		)
		(min_thickness 0.25)
		(keepout
			(tracks not_allowed)
			(vias allowed)
			(pads allowed)
			(copperpour not_allowed)
			(footprints allowed)
		)
		(placement
			(enabled no)
			(sheetname "")
		)
		(fill yes
			(thermal_gap 0.5)
			(thermal_bridge_width 0.5)
			(island_removal_mode 0)
		)
		(polygon
			(pts
				(arc
					(start 214.969598 -199.221344)
					(mid 214.984477 -199.257265)
					(end 215.020398 -199.272144)
				)
				(arc
					(start 216.419938 -199.272144)
					(mid 216.455859 -199.257265)
					(end 216.470738 -199.221344)
				)
				(arc
					(start 216.470738 -198.812404)
					(mid 216.455859 -198.776483)
					(end 216.419938 -198.761604)
				)
				(arc
					(start 215.020398 -198.761604)
					(mid 214.984477 -198.776483)
					(end 214.969598 -198.812404)
				)
			)
		)
	)
	(zone
		(layers "In1.Cu" "In2.Cu")
		(hatch none 0.5)
		(connect_pads
			(clearance 0)
		)
		(min_thickness 0.25)
		(keepout
			(tracks not_allowed)
			(vias allowed)
			(pads allowed)
			(copperpour not_allowed)
			(footprints allowed)
		)
		(placement
			(enabled no)
			(sheetname "")
		)
		(fill yes
			(thermal_gap 0.5)
			(thermal_bridge_width 0.5)
			(island_removal_mode 0)
		)
		(polygon
			(pts
				(arc
					(start 432.734466 -245.12143)
					(mid 432.749345 -245.157351)
					(end 432.785266 -245.17223)
				)
				(arc
					(start 434.184806 -245.17223)
					(mid 434.220727 -245.157351)
					(end 434.235606 -245.12143)
				)
				(arc
					(start 434.235606 -244.71249)
					(mid 434.220727 -244.676569)
					(end 434.184806 -244.66169)
				)
				(arc
					(start 432.785266 -244.66169)
					(mid 432.749345 -244.676569)
					(end 432.734466 -244.71249)
				)
			)
		)
	)
	(zone
		(layers "In1.Cu" "In2.Cu")
		(hatch none 0.5)
		(connect_pads
			(clearance 0)
		)
		(min_thickness 0.25)
		(keepout
			(tracks not_allowed)
			(vias allowed)
			(pads allowed)
			(copperpour not_allowed)
			(footprints allowed)
		)
		(placement
			(enabled no)
			(sheetname "")
		)
		(fill yes
			(thermal_gap 0.5)
			(thermal_bridge_width 0.5)
			(island_removal_mode 0)
		)
		(polygon
			(pts
				(arc
					(start 274.517866 -296.971466)
					(mid 274.532745 -297.007387)
					(end 274.568666 -297.022266)
				)
				(arc
					(start 275.968206 -297.022266)
					(mid 276.004127 -297.007387)
					(end 276.019006 -296.971466)
				)
				(arc
					(start 276.019006 -296.562526)
					(mid 276.004127 -296.526605)
					(end 275.968206 -296.511726)
				)
				(arc
					(start 274.568666 -296.511726)
					(mid 274.532745 -296.526605)
					(end 274.517866 -296.562526)
				)
			)
		)
	)
	(zone
		(layers "In1.Cu" "In2.Cu")
		(hatch none 0.5)
		(connect_pads
			(clearance 0)
		)
		(min_thickness 0.25)
		(keepout
			(tracks not_allowed)
			(vias allowed)
			(pads allowed)
			(copperpour not_allowed)
			(footprints allowed)
		)
		(placement
			(enabled no)
			(sheetname "")
		)
		(fill yes
			(thermal_gap 0.5)
			(thermal_bridge_width 0.5)
			(island_removal_mode 0)
		)
		(polygon
			(pts
				(arc
					(start 203.32573 -245.971314)
					(mid 203.340609 -246.007235)
					(end 203.37653 -246.022114)
				)
				(arc
					(start 204.77607 -246.022114)
					(mid 204.811991 -246.007235)
					(end 204.82687 -245.971314)
				)
				(arc
					(start 204.82687 -245.562374)
					(mid 204.811991 -245.526453)
					(end 204.77607 -245.511574)
				)
				(arc
					(start 203.37653 -245.511574)
					(mid 203.340609 -245.526453)
					(end 203.32573 -245.562374)
				)
			)
		)
	)
	(zone
		(layers "In1.Cu" "In2.Cu")
		(hatch none 0.5)
		(connect_pads
			(clearance 0)
		)
		(min_thickness 0.25)
		(keepout
			(tracks not_allowed)
			(vias allowed)
			(pads allowed)
			(copperpour not_allowed)
			(footprints allowed)
		)
		(placement
			(enabled no)
			(sheetname "")
		)
		(fill yes
			(thermal_gap 0.5)
			(thermal_bridge_width 0.5)
			(island_removal_mode 0)
		)
		(polygon
			(pts
				(arc
					(start 52.65293 -217.071448)
					(mid 52.667809 -217.107369)
					(end 52.70373 -217.122248)
				)
				(arc
					(start 54.10327 -217.122248)
					(mid 54.139191 -217.107369)
					(end 54.15407 -217.071448)
				)
				(arc
					(start 54.15407 -216.662508)
					(mid 54.139191 -216.626587)
					(end 54.10327 -216.611708)
				)
				(arc
					(start 52.70373 -216.611708)
					(mid 52.667809 -216.626587)
					(end 52.65293 -216.662508)
				)
			)
		)
	)
	(zone
		(layers "In1.Cu" "In2.Cu")
		(hatch none 0.5)
		(connect_pads
			(clearance 0)
		)
		(min_thickness 0.25)
		(keepout
			(tracks not_allowed)
			(vias allowed)
			(pads allowed)
			(copperpour not_allowed)
			(footprints allowed)
		)
		(placement
			(enabled no)
			(sheetname "")
		)
		(fill yes
			(thermal_gap 0.5)
			(thermal_bridge_width 0.5)
			(island_removal_mode 0)
		)
		(polygon
			(pts
				(arc
					(start 447.822066 -265.52144)
					(mid 447.836945 -265.557361)
					(end 447.872866 -265.57224)
				)
				(arc
					(start 449.272406 -265.57224)
					(mid 449.308327 -265.557361)
					(end 449.323206 -265.52144)
				)
				(arc
					(start 449.323206 -265.1125)
					(mid 449.308327 -265.076579)
					(end 449.272406 -265.0617)
				)
				(arc
					(start 447.872866 -265.0617)
					(mid 447.836945 -265.076579)
					(end 447.822066 -265.1125)
				)
			)
		)
	)
	(zone
		(layers "In1.Cu" "In2.Cu")
		(hatch none 0.5)
		(connect_pads
			(clearance 0)
		)
		(min_thickness 0.25)
		(keepout
			(tracks not_allowed)
			(vias allowed)
			(pads allowed)
			(copperpour not_allowed)
			(footprints allowed)
		)
		(placement
			(enabled no)
			(sheetname "")
		)
		(fill yes
			(thermal_gap 0.5)
			(thermal_bridge_width 0.5)
			(island_removal_mode 0)
		)
		(polygon
			(pts
				(arc
					(start 440.278266 -225.571304)
					(mid 440.293145 -225.607225)
					(end 440.329066 -225.622104)
				)
				(arc
					(start 441.728606 -225.622104)
					(mid 441.764527 -225.607225)
					(end 441.779406 -225.571304)
				)
				(arc
					(start 441.779406 -225.162364)
					(mid 441.764527 -225.126443)
					(end 441.728606 -225.111564)
				)
				(arc
					(start 440.329066 -225.111564)
					(mid 440.293145 -225.126443)
					(end 440.278266 -225.162364)
				)
			)
		)
	)
	(zone
		(layers "In1.Cu" "In2.Cu")
		(hatch none 0.5)
		(connect_pads
			(clearance 0)
		)
		(min_thickness 0.25)
		(keepout
			(tracks not_allowed)
			(vias allowed)
			(pads allowed)
			(copperpour not_allowed)
			(footprints allowed)
		)
		(placement
			(enabled no)
			(sheetname "")
		)
		(fill yes
			(thermal_gap 0.5)
			(thermal_bridge_width 0.5)
			(island_removal_mode 0)
		)
		(polygon
			(pts
				(arc
					(start 64.296798 -205.171548)
					(mid 64.311677 -205.207469)
					(end 64.347598 -205.222348)
				)
				(arc
					(start 65.747138 -205.222348)
					(mid 65.783059 -205.207469)
					(end 65.797938 -205.171548)
				)
				(arc
					(start 65.797938 -204.762608)
					(mid 65.783059 -204.726687)
					(end 65.747138 -204.711808)
				)
				(arc
					(start 64.347598 -204.711808)
					(mid 64.311677 -204.726687)
					(end 64.296798 -204.762608)
				)
			)
		)
	)
	(zone
		(layers "In1.Cu" "In2.Cu")
		(hatch none 0.5)
		(connect_pads
			(clearance 0)
		)
		(min_thickness 0.25)
		(keepout
			(tracks not_allowed)
			(vias allowed)
			(pads allowed)
			(copperpour not_allowed)
			(footprints allowed)
		)
		(placement
			(enabled no)
			(sheetname "")
		)
		(fill yes
			(thermal_gap 0.5)
			(thermal_bridge_width 0.5)
			(island_removal_mode 0)
		)
		(polygon
			(pts
				(arc
					(start 451.265798 -243.421408)
					(mid 451.280677 -243.457329)
					(end 451.316598 -243.472208)
				)
				(arc
					(start 452.716138 -243.472208)
					(mid 452.752059 -243.457329)
					(end 452.766938 -243.421408)
				)
				(arc
					(start 452.766938 -243.012468)
					(mid 452.752059 -242.976547)
					(end 452.716138 -242.961668)
				)
				(arc
					(start 451.316598 -242.961668)
					(mid 451.280677 -242.976547)
					(end 451.265798 -243.012468)
				)
			)
		)
	)
	(zone
		(layers "In1.Cu" "In2.Cu")
		(hatch none 0.5)
		(connect_pads
			(clearance 0)
		)
		(min_thickness 0.25)
		(keepout
			(tracks not_allowed)
			(vias allowed)
			(pads allowed)
			(copperpour not_allowed)
			(footprints allowed)
		)
		(placement
			(enabled no)
			(sheetname "")
		)
		(fill yes
			(thermal_gap 0.5)
			(thermal_bridge_width 0.5)
			(island_removal_mode 0)
		)
		(polygon
			(pts
				(arc
					(start 300.592998 -238.321342)
					(mid 300.607877 -238.357263)
					(end 300.643798 -238.372142)
				)
				(arc
					(start 302.043338 -238.372142)
					(mid 302.079259 -238.357263)
					(end 302.094138 -238.321342)
				)
				(arc
					(start 302.094138 -237.912402)
					(mid 302.079259 -237.876481)
					(end 302.043338 -237.861602)
				)
				(arc
					(start 300.643798 -237.861602)
					(mid 300.607877 -237.876481)
					(end 300.592998 -237.912402)
				)
			)
		)
	)
	(zone
		(layers "In1.Cu" "In2.Cu")
		(hatch none 0.5)
		(connect_pads
			(clearance 0)
		)
		(min_thickness 0.25)
		(keepout
			(tracks not_allowed)
			(vias allowed)
			(pads allowed)
			(copperpour not_allowed)
			(footprints allowed)
		)
		(placement
			(enabled no)
			(sheetname "")
		)
		(fill yes
			(thermal_gap 0.5)
			(thermal_bridge_width 0.5)
			(island_removal_mode 0)
		)
		(polygon
			(pts
				(arc
					(start 440.278266 -278.271478)
					(mid 440.293145 -278.307399)
					(end 440.329066 -278.322278)
				)
				(arc
					(start 441.728606 -278.322278)
					(mid 441.764527 -278.307399)
					(end 441.779406 -278.271478)
				)
				(arc
					(start 441.779406 -277.862538)
					(mid 441.764527 -277.826617)
					(end 441.728606 -277.811738)
				)
				(arc
					(start 440.329066 -277.811738)
					(mid 440.293145 -277.826617)
					(end 440.278266 -277.862538)
				)
			)
		)
	)
	(zone
		(layers "In1.Cu" "In2.Cu")
		(hatch none 0.5)
		(connect_pads
			(clearance 0)
		)
		(min_thickness 0.25)
		(keepout
			(tracks not_allowed)
			(vias allowed)
			(pads allowed)
			(copperpour not_allowed)
			(footprints allowed)
		)
		(placement
			(enabled no)
			(sheetname "")
		)
		(fill yes
			(thermal_gap 0.5)
			(thermal_bridge_width 0.5)
			(island_removal_mode 0)
		)
		(polygon
			(pts
				(arc
					(start 455.365866 -229.821486)
					(mid 455.380745 -229.857407)
					(end 455.416666 -229.872286)
				)
				(arc
					(start 456.816206 -229.872286)
					(mid 456.852127 -229.857407)
					(end 456.867006 -229.821486)
				)
				(arc
					(start 456.867006 -229.412546)
					(mid 456.852127 -229.376625)
					(end 456.816206 -229.361746)
				)
				(arc
					(start 455.416666 -229.361746)
					(mid 455.380745 -229.376625)
					(end 455.365866 -229.412546)
				)
			)
		)
	)
	(zone
		(layers "In1.Cu" "In2.Cu")
		(hatch none 0.5)
		(connect_pads
			(clearance 0)
		)
		(min_thickness 0.25)
		(keepout
			(tracks not_allowed)
			(vias allowed)
			(pads allowed)
			(copperpour not_allowed)
			(footprints allowed)
		)
		(placement
			(enabled no)
			(sheetname "")
		)
		(fill yes
			(thermal_gap 0.5)
			(thermal_bridge_width 0.5)
			(island_removal_mode 0)
		)
		(polygon
			(pts
				(arc
					(start 270.417798 -269.771368)
					(mid 270.432677 -269.807289)
					(end 270.468598 -269.822168)
				)
				(arc
					(start 271.868138 -269.822168)
					(mid 271.904059 -269.807289)
					(end 271.918938 -269.771368)
				)
				(arc
					(start 271.918938 -269.362428)
					(mid 271.904059 -269.326507)
					(end 271.868138 -269.311628)
				)
				(arc
					(start 270.468598 -269.311628)
					(mid 270.432677 -269.326507)
					(end 270.417798 -269.362428)
				)
			)
		)
	)
	(zone
		(layers "In1.Cu" "In2.Cu")
		(hatch none 0.5)
		(connect_pads
			(clearance 0)
		)
		(min_thickness 0.25)
		(keepout
			(tracks not_allowed)
			(vias allowed)
			(pads allowed)
			(copperpour not_allowed)
			(footprints allowed)
		)
		(placement
			(enabled no)
			(sheetname "")
		)
		(fill yes
			(thermal_gap 0.5)
			(thermal_bridge_width 0.5)
			(island_removal_mode 0)
		)
		(polygon
			(pts
				(arc
					(start 421.090598 -230.67137)
					(mid 421.105477 -230.707291)
					(end 421.141398 -230.72217)
				)
				(arc
					(start 422.540938 -230.72217)
					(mid 422.576859 -230.707291)
					(end 422.591738 -230.67137)
				)
				(arc
					(start 422.591738 -230.26243)
					(mid 422.576859 -230.226509)
					(end 422.540938 -230.21163)
				)
				(arc
					(start 421.141398 -230.21163)
					(mid 421.105477 -230.226509)
					(end 421.090598 -230.26243)
				)
			)
		)
	)
	(zone
		(layers "In1.Cu" "In2.Cu")
		(hatch none 0.5)
		(connect_pads
			(clearance 0)
		)
		(min_thickness 0.25)
		(keepout
			(tracks not_allowed)
			(vias allowed)
			(pads allowed)
			(copperpour not_allowed)
			(footprints allowed)
		)
		(placement
			(enabled no)
			(sheetname "")
		)
		(fill yes
			(thermal_gap 0.5)
			(thermal_bridge_width 0.5)
			(island_removal_mode 0)
		)
		(polygon
			(pts
				(arc
					(start 440.278266 -250.221496)
					(mid 440.293145 -250.257417)
					(end 440.329066 -250.272296)
				)
				(arc
					(start 441.728606 -250.272296)
					(mid 441.764527 -250.257417)
					(end 441.779406 -250.221496)
				)
				(arc
					(start 441.779406 -249.812556)
					(mid 441.764527 -249.776635)
					(end 441.728606 -249.761756)
				)
				(arc
					(start 440.329066 -249.761756)
					(mid 440.293145 -249.776635)
					(end 440.278266 -249.812556)
				)
			)
		)
	)
	(zone
		(layers "In1.Cu" "In2.Cu")
		(hatch none 0.5)
		(connect_pads
			(clearance 0)
		)
		(min_thickness 0.25)
		(keepout
			(tracks not_allowed)
			(vias allowed)
			(pads allowed)
			(copperpour not_allowed)
			(footprints allowed)
		)
		(placement
			(enabled no)
			(sheetname "")
		)
		(fill yes
			(thermal_gap 0.5)
			(thermal_bridge_width 0.5)
			(island_removal_mode 0)
		)
		(polygon
			(pts
				(arc
					(start 289.605466 -216.22131)
					(mid 289.620345 -216.257231)
					(end 289.656266 -216.27211)
				)
				(arc
					(start 291.055806 -216.27211)
					(mid 291.091727 -216.257231)
					(end 291.106606 -216.22131)
				)
				(arc
					(start 291.106606 -215.81237)
					(mid 291.091727 -215.776449)
					(end 291.055806 -215.76157)
				)
				(arc
					(start 289.656266 -215.76157)
					(mid 289.620345 -215.776449)
					(end 289.605466 -215.81237)
				)
			)
		)
	)
	(zone
		(layers "In1.Cu" "In2.Cu")
		(hatch none 0.5)
		(connect_pads
			(clearance 0)
		)
		(min_thickness 0.25)
		(keepout
			(tracks not_allowed)
			(vias allowed)
			(pads allowed)
			(copperpour not_allowed)
			(footprints allowed)
		)
		(placement
			(enabled no)
			(sheetname "")
		)
		(fill yes
			(thermal_gap 0.5)
			(thermal_bridge_width 0.5)
			(island_removal_mode 0)
		)
		(polygon
			(pts
				(arc
					(start 64.296798 -209.421476)
					(mid 64.311677 -209.457397)
					(end 64.347598 -209.472276)
				)
				(arc
					(start 65.747138 -209.472276)
					(mid 65.783059 -209.457397)
					(end 65.797938 -209.421476)
				)
				(arc
					(start 65.797938 -209.012536)
					(mid 65.783059 -208.976615)
					(end 65.747138 -208.961736)
				)
				(arc
					(start 64.347598 -208.961736)
					(mid 64.311677 -208.976615)
					(end 64.296798 -209.012536)
				)
			)
		)
	)
	(zone
		(layers "In1.Cu" "In2.Cu")
		(hatch none 0.5)
		(connect_pads
			(clearance 0)
		)
		(min_thickness 0.25)
		(keepout
			(tracks not_allowed)
			(vias allowed)
			(pads allowed)
			(copperpour not_allowed)
			(footprints allowed)
		)
		(placement
			(enabled no)
			(sheetname "")
		)
		(fill yes
			(thermal_gap 0.5)
			(thermal_bridge_width 0.5)
			(island_removal_mode 0)
		)
		(polygon
			(pts
				(arc
					(start 192.338198 -265.52144)
					(mid 192.353077 -265.557361)
					(end 192.388998 -265.57224)
				)
				(arc
					(start 193.788538 -265.57224)
					(mid 193.824459 -265.557361)
					(end 193.839338 -265.52144)
				)
				(arc
					(start 193.839338 -265.1125)
					(mid 193.824459 -265.076579)
					(end 193.788538 -265.0617)
				)
				(arc
					(start 192.388998 -265.0617)
					(mid 192.353077 -265.076579)
					(end 192.338198 -265.1125)
				)
			)
		)
	)
	(zone
		(layers "In1.Cu" "In2.Cu")
		(hatch none 0.5)
		(connect_pads
			(clearance 0)
		)
		(min_thickness 0.25)
		(keepout
			(tracks not_allowed)
			(vias allowed)
			(pads allowed)
			(copperpour not_allowed)
			(footprints allowed)
		)
		(placement
			(enabled no)
			(sheetname "")
		)
		(fill yes
			(thermal_gap 0.5)
			(thermal_bridge_width 0.5)
			(island_removal_mode 0)
		)
		(polygon
			(pts
				(arc
					(start 162.162998 -206.871316)
					(mid 162.177877 -206.907237)
					(end 162.213798 -206.922116)
				)
				(arc
					(start 163.613338 -206.922116)
					(mid 163.649259 -206.907237)
					(end 163.664138 -206.871316)
				)
				(arc
					(start 163.664138 -206.462376)
					(mid 163.649259 -206.426455)
					(end 163.613338 -206.411576)
				)
				(arc
					(start 162.213798 -206.411576)
					(mid 162.177877 -206.426455)
					(end 162.162998 -206.462376)
				)
			)
		)
	)
	(zone
		(layers "In1.Cu" "In2.Cu")
		(hatch none 0.5)
		(connect_pads
			(clearance 0)
		)
		(min_thickness 0.25)
		(keepout
			(tracks not_allowed)
			(vias allowed)
			(pads allowed)
			(copperpour not_allowed)
			(footprints allowed)
		)
		(placement
			(enabled no)
			(sheetname "")
		)
		(fill yes
			(thermal_gap 0.5)
			(thermal_bridge_width 0.5)
			(island_removal_mode 0)
		)
		(polygon
			(pts
				(arc
					(start 285.505398 -206.021432)
					(mid 285.520277 -206.057353)
					(end 285.556198 -206.072232)
				)
				(arc
					(start 286.955738 -206.072232)
					(mid 286.991659 -206.057353)
					(end 287.006538 -206.021432)
				)
				(arc
					(start 287.006538 -205.612492)
					(mid 286.991659 -205.576571)
					(end 286.955738 -205.561692)
				)
				(arc
					(start 285.556198 -205.561692)
					(mid 285.520277 -205.576571)
					(end 285.505398 -205.612492)
				)
			)
		)
	)
	(zone
		(layers "In1.Cu" "In2.Cu")
		(hatch none 0.5)
		(connect_pads
			(clearance 0)
		)
		(min_thickness 0.25)
		(keepout
			(tracks not_allowed)
			(vias allowed)
			(pads allowed)
			(copperpour not_allowed)
			(footprints allowed)
		)
		(placement
			(enabled no)
			(sheetname "")
		)
		(fill yes
			(thermal_gap 0.5)
			(thermal_bridge_width 0.5)
			(island_removal_mode 0)
		)
		(polygon
			(pts
				(arc
					(start 184.794398 -274.02155)
					(mid 184.809277 -274.057471)
					(end 184.845198 -274.07235)
				)
				(arc
					(start 186.244738 -274.07235)
					(mid 186.280659 -274.057471)
					(end 186.295538 -274.02155)
				)
				(arc
					(start 186.295538 -273.61261)
					(mid 186.280659 -273.576689)
					(end 186.244738 -273.56181)
				)
				(arc
					(start 184.845198 -273.56181)
					(mid 184.809277 -273.576689)
					(end 184.794398 -273.61261)
				)
			)
		)
	)
	(zone
		(layers "In1.Cu" "In2.Cu")
		(hatch none 0.5)
		(connect_pads
			(clearance 0)
		)
		(min_thickness 0.25)
		(keepout
			(tracks not_allowed)
			(vias allowed)
			(pads allowed)
			(copperpour not_allowed)
			(footprints allowed)
		)
		(placement
			(enabled no)
			(sheetname "")
		)
		(fill yes
			(thermal_gap 0.5)
			(thermal_bridge_width 0.5)
			(island_removal_mode 0)
		)
		(polygon
			(pts
				(arc
					(start 421.090598 -296.121328)
					(mid 421.105477 -296.157249)
					(end 421.141398 -296.172128)
				)
				(arc
					(start 422.540938 -296.172128)
					(mid 422.576859 -296.157249)
					(end 422.591738 -296.121328)
				)
				(arc
					(start 422.591738 -295.712388)
					(mid 422.576859 -295.676467)
					(end 422.540938 -295.661588)
				)
				(arc
					(start 421.141398 -295.661588)
					(mid 421.105477 -295.676467)
					(end 421.090598 -295.712388)
				)
			)
		)
	)
	(zone
		(layers "In1.Cu" "In2.Cu")
		(hatch none 0.5)
		(connect_pads
			(clearance 0)
		)
		(min_thickness 0.25)
		(keepout
			(tracks not_allowed)
			(vias allowed)
			(pads allowed)
			(copperpour not_allowed)
			(footprints allowed)
		)
		(placement
			(enabled no)
			(sheetname "")
		)
		(fill yes
			(thermal_gap 0.5)
			(thermal_bridge_width 0.5)
			(island_removal_mode 0)
		)
		(polygon
			(pts
				(arc
					(start 64.296798 -197.521322)
					(mid 64.311677 -197.557243)
					(end 64.347598 -197.572122)
				)
				(arc
					(start 65.747138 -197.572122)
					(mid 65.783059 -197.557243)
					(end 65.797938 -197.521322)
				)
				(arc
					(start 65.797938 -197.112382)
					(mid 65.783059 -197.076461)
					(end 65.747138 -197.061582)
				)
				(arc
					(start 64.347598 -197.061582)
					(mid 64.311677 -197.076461)
					(end 64.296798 -197.112382)
				)
			)
		)
	)
	(zone
		(layers "In1.Cu" "In2.Cu")
		(hatch none 0.5)
		(connect_pads
			(clearance 0)
		)
		(min_thickness 0.25)
		(keepout
			(tracks not_allowed)
			(vias allowed)
			(pads allowed)
			(copperpour not_allowed)
			(footprints allowed)
		)
		(placement
			(enabled no)
			(sheetname "")
		)
		(fill yes
			(thermal_gap 0.5)
			(thermal_bridge_width 0.5)
			(island_removal_mode 0)
		)
		(polygon
			(pts
				(arc
					(start 428.634398 -219.621354)
					(mid 428.649277 -219.657275)
					(end 428.685198 -219.672154)
				)
				(arc
					(start 430.084738 -219.672154)
					(mid 430.120659 -219.657275)
					(end 430.135538 -219.621354)
				)
				(arc
					(start 430.135538 -219.212414)
					(mid 430.120659 -219.176493)
					(end 430.084738 -219.161614)
				)
				(arc
					(start 428.685198 -219.161614)
					(mid 428.649277 -219.176493)
					(end 428.634398 -219.212414)
				)
			)
		)
	)
	(zone
		(layers "In1.Cu" "In2.Cu")
		(hatch none 0.5)
		(connect_pads
			(clearance 0)
		)
		(min_thickness 0.25)
		(keepout
			(tracks not_allowed)
			(vias allowed)
			(pads allowed)
			(copperpour not_allowed)
			(footprints allowed)
		)
		(placement
			(enabled no)
			(sheetname "")
		)
		(fill yes
			(thermal_gap 0.5)
			(thermal_bridge_width 0.5)
			(island_removal_mode 0)
		)
		(polygon
			(pts
				(arc
					(start 203.32573 -285.071312)
					(mid 203.340609 -285.107233)
					(end 203.37653 -285.122112)
				)
				(arc
					(start 204.77607 -285.122112)
					(mid 204.811991 -285.107233)
					(end 204.82687 -285.071312)
				)
				(arc
					(start 204.82687 -284.662372)
					(mid 204.811991 -284.626451)
					(end 204.77607 -284.611572)
				)
				(arc
					(start 203.37653 -284.611572)
					(mid 203.340609 -284.626451)
					(end 203.32573 -284.662372)
				)
			)
		)
	)
	(zone
		(layers "In1.Cu" "In2.Cu")
		(hatch none 0.5)
		(connect_pads
			(clearance 0)
		)
		(min_thickness 0.25)
		(keepout
			(tracks not_allowed)
			(vias allowed)
			(pads allowed)
			(copperpour not_allowed)
			(footprints allowed)
		)
		(placement
			(enabled no)
			(sheetname "")
		)
		(fill yes
			(thermal_gap 0.5)
			(thermal_bridge_width 0.5)
			(island_removal_mode 0)
		)
		(polygon
			(pts
				(arc
					(start 158.06293 -243.421408)
					(mid 158.077809 -243.457329)
					(end 158.11373 -243.472208)
				)
				(arc
					(start 159.51327 -243.472208)
					(mid 159.549191 -243.457329)
					(end 159.56407 -243.421408)
				)
				(arc
					(start 159.56407 -243.012468)
					(mid 159.549191 -242.976547)
					(end 159.51327 -242.961668)
				)
				(arc
					(start 158.11373 -242.961668)
					(mid 158.077809 -242.976547)
					(end 158.06293 -243.012468)
				)
			)
		)
	)
	(zone
		(layers "In1.Cu" "In2.Cu")
		(hatch none 0.5)
		(connect_pads
			(clearance 0)
		)
		(min_thickness 0.25)
		(keepout
			(tracks not_allowed)
			(vias allowed)
			(pads allowed)
			(copperpour not_allowed)
			(footprints allowed)
		)
		(placement
			(enabled no)
			(sheetname "")
		)
		(fill yes
			(thermal_gap 0.5)
			(thermal_bridge_width 0.5)
			(island_removal_mode 0)
		)
		(polygon
			(pts
				(arc
					(start 297.149266 -228.121464)
					(mid 297.164145 -228.157385)
					(end 297.200066 -228.172264)
				)
				(arc
					(start 298.599606 -228.172264)
					(mid 298.635527 -228.157385)
					(end 298.650406 -228.121464)
				)
				(arc
					(start 298.650406 -227.712524)
					(mid 298.635527 -227.676603)
					(end 298.599606 -227.661724)
				)
				(arc
					(start 297.200066 -227.661724)
					(mid 297.164145 -227.676603)
					(end 297.149266 -227.712524)
				)
			)
		)
	)
	(zone
		(layers "In1.Cu" "In2.Cu")
		(hatch none 0.5)
		(connect_pads
			(clearance 0)
		)
		(min_thickness 0.25)
		(keepout
			(tracks not_allowed)
			(vias allowed)
			(pads allowed)
			(copperpour not_allowed)
			(footprints allowed)
		)
		(placement
			(enabled no)
			(sheetname "")
		)
		(fill yes
			(thermal_gap 0.5)
			(thermal_bridge_width 0.5)
			(island_removal_mode 0)
		)
		(polygon
			(pts
				(arc
					(start 277.961598 -299.521372)
					(mid 277.976477 -299.557293)
					(end 278.012398 -299.572172)
				)
				(arc
					(start 279.411938 -299.572172)
					(mid 279.447859 -299.557293)
					(end 279.462738 -299.521372)
				)
				(arc
					(start 279.462738 -299.112432)
					(mid 279.447859 -299.076511)
					(end 279.411938 -299.061632)
				)
				(arc
					(start 278.012398 -299.061632)
					(mid 277.976477 -299.076511)
					(end 277.961598 -299.112432)
				)
			)
		)
	)
	(zone
		(layers "In1.Cu" "In2.Cu")
		(hatch none 0.5)
		(connect_pads
			(clearance 0)
		)
		(min_thickness 0.25)
		(keepout
			(tracks not_allowed)
			(vias allowed)
			(pads allowed)
			(copperpour not_allowed)
			(footprints allowed)
		)
		(placement
			(enabled no)
			(sheetname "")
		)
		(fill yes
			(thermal_gap 0.5)
			(thermal_bridge_width 0.5)
			(island_removal_mode 0)
		)
		(polygon
			(pts
				(arc
					(start 30.02153 -215.371426)
					(mid 30.036409 -215.407347)
					(end 30.07233 -215.422226)
				)
				(arc
					(start 31.47187 -215.422226)
					(mid 31.507791 -215.407347)
					(end 31.52267 -215.371426)
				)
				(arc
					(start 31.52267 -214.962486)
					(mid 31.507791 -214.926565)
					(end 31.47187 -214.911686)
				)
				(arc
					(start 30.07233 -214.911686)
					(mid 30.036409 -214.926565)
					(end 30.02153 -214.962486)
				)
			)
		)
	)
	(zone
		(layers "In1.Cu" "In2.Cu")
		(hatch none 0.5)
		(connect_pads
			(clearance 0)
		)
		(min_thickness 0.25)
		(keepout
			(tracks not_allowed)
			(vias allowed)
			(pads allowed)
			(copperpour not_allowed)
			(footprints allowed)
		)
		(placement
			(enabled no)
			(sheetname "")
		)
		(fill yes
			(thermal_gap 0.5)
			(thermal_bridge_width 0.5)
			(island_removal_mode 0)
		)
		(polygon
			(pts
				(arc
					(start 297.149266 -306.32146)
					(mid 297.164145 -306.357381)
					(end 297.200066 -306.37226)
				)
				(arc
					(start 298.599606 -306.37226)
					(mid 298.635527 -306.357381)
					(end 298.650406 -306.32146)
				)
				(arc
					(start 298.650406 -305.91252)
					(mid 298.635527 -305.876599)
					(end 298.599606 -305.86172)
				)
				(arc
					(start 297.200066 -305.86172)
					(mid 297.164145 -305.876599)
					(end 297.149266 -305.91252)
				)
			)
		)
	)
	(zone
		(layers "In1.Cu" "In2.Cu")
		(hatch none 0.5)
		(connect_pads
			(clearance 0)
		)
		(min_thickness 0.25)
		(keepout
			(tracks not_allowed)
			(vias allowed)
			(pads allowed)
			(copperpour not_allowed)
			(footprints allowed)
		)
		(placement
			(enabled no)
			(sheetname "")
		)
		(fill yes
			(thermal_gap 0.5)
			(thermal_bridge_width 0.5)
			(island_removal_mode 0)
		)
		(polygon
			(pts
				(arc
					(start 285.505398 -291.8714)
					(mid 285.520277 -291.907321)
					(end 285.556198 -291.9222)
				)
				(arc
					(start 286.955738 -291.9222)
					(mid 286.991659 -291.907321)
					(end 287.006538 -291.8714)
				)
				(arc
					(start 287.006538 -291.46246)
					(mid 286.991659 -291.426539)
					(end 286.955738 -291.41166)
				)
				(arc
					(start 285.556198 -291.41166)
					(mid 285.520277 -291.426539)
					(end 285.505398 -291.46246)
				)
			)
		)
	)
	(zone
		(layers "In1.Cu" "In2.Cu")
		(hatch none 0.5)
		(connect_pads
			(clearance 0)
		)
		(min_thickness 0.25)
		(keepout
			(tracks not_allowed)
			(vias allowed)
			(pads allowed)
			(copperpour not_allowed)
			(footprints allowed)
		)
		(placement
			(enabled no)
			(sheetname "")
		)
		(fill yes
			(thermal_gap 0.5)
			(thermal_bridge_width 0.5)
			(island_removal_mode 0)
		)
		(polygon
			(pts
				(arc
					(start 45.10913 -282.521406)
					(mid 45.124009 -282.557327)
					(end 45.15993 -282.572206)
				)
				(arc
					(start 46.55947 -282.572206)
					(mid 46.595391 -282.557327)
					(end 46.61027 -282.521406)
				)
				(arc
					(start 46.61027 -282.112466)
					(mid 46.595391 -282.076545)
					(end 46.55947 -282.061666)
				)
				(arc
					(start 45.15993 -282.061666)
					(mid 45.124009 -282.076545)
					(end 45.10913 -282.112466)
				)
			)
		)
	)
	(zone
		(layers "In1.Cu" "In2.Cu")
		(hatch none 0.5)
		(connect_pads
			(clearance 0)
		)
		(min_thickness 0.25)
		(keepout
			(tracks not_allowed)
			(vias allowed)
			(pads allowed)
			(copperpour not_allowed)
			(footprints allowed)
		)
		(placement
			(enabled no)
			(sheetname "")
		)
		(fill yes
			(thermal_gap 0.5)
			(thermal_bridge_width 0.5)
			(island_removal_mode 0)
		)
		(polygon
			(pts
				(arc
					(start 30.02153 -200.071482)
					(mid 30.036409 -200.107403)
					(end 30.07233 -200.122282)
				)
				(arc
					(start 31.47187 -200.122282)
					(mid 31.507791 -200.107403)
					(end 31.52267 -200.071482)
				)
				(arc
					(start 31.52267 -199.662542)
					(mid 31.507791 -199.626621)
					(end 31.47187 -199.611742)
				)
				(arc
					(start 30.07233 -199.611742)
					(mid 30.036409 -199.626621)
					(end 30.02153 -199.662542)
				)
			)
		)
	)
	(zone
		(layers "In1.Cu" "In2.Cu")
		(hatch none 0.5)
		(connect_pads
			(clearance 0)
		)
		(min_thickness 0.25)
		(keepout
			(tracks not_allowed)
			(vias allowed)
			(pads allowed)
			(copperpour not_allowed)
			(footprints allowed)
		)
		(placement
			(enabled no)
			(sheetname "")
		)
		(fill yes
			(thermal_gap 0.5)
			(thermal_bridge_width 0.5)
			(island_removal_mode 0)
		)
		(polygon
			(pts
				(arc
					(start 22.47773 -310.571388)
					(mid 22.492609 -310.607309)
					(end 22.52853 -310.622188)
				)
				(arc
					(start 23.92807 -310.622188)
					(mid 23.963991 -310.607309)
					(end 23.97887 -310.571388)
				)
				(arc
					(start 23.97887 -310.162448)
					(mid 23.963991 -310.126527)
					(end 23.92807 -310.111648)
				)
				(arc
					(start 22.52853 -310.111648)
					(mid 22.492609 -310.126527)
					(end 22.47773 -310.162448)
				)
			)
		)
	)
	(zone
		(layers "In1.Cu" "In2.Cu")
		(hatch none 0.5)
		(connect_pads
			(clearance 0)
		)
		(min_thickness 0.25)
		(keepout
			(tracks not_allowed)
			(vias allowed)
			(pads allowed)
			(copperpour not_allowed)
			(footprints allowed)
		)
		(placement
			(enabled no)
			(sheetname "")
		)
		(fill yes
			(thermal_gap 0.5)
			(thermal_bridge_width 0.5)
			(island_removal_mode 0)
		)
		(polygon
			(pts
				(arc
					(start 458.809598 -303.7713)
					(mid 458.824477 -303.807221)
					(end 458.860398 -303.8221)
				)
				(arc
					(start 460.259938 -303.8221)
					(mid 460.295859 -303.807221)
					(end 460.310738 -303.7713)
				)
				(arc
					(start 460.310738 -303.36236)
					(mid 460.295859 -303.326439)
					(end 460.259938 -303.31156)
				)
				(arc
					(start 458.860398 -303.31156)
					(mid 458.824477 -303.326439)
					(end 458.809598 -303.36236)
				)
			)
		)
	)
	(zone
		(layers "In1.Cu" "In2.Cu")
		(hatch none 0.5)
		(connect_pads
			(clearance 0)
		)
		(min_thickness 0.25)
		(keepout
			(tracks not_allowed)
			(vias allowed)
			(pads allowed)
			(copperpour not_allowed)
			(footprints allowed)
		)
		(placement
			(enabled no)
			(sheetname "")
		)
		(fill yes
			(thermal_gap 0.5)
			(thermal_bridge_width 0.5)
			(island_removal_mode 0)
		)
		(polygon
			(pts
				(arc
					(start 41.665398 -267.221462)
					(mid 41.680277 -267.257383)
					(end 41.716198 -267.272262)
				)
				(arc
					(start 43.115738 -267.272262)
					(mid 43.151659 -267.257383)
					(end 43.166538 -267.221462)
				)
				(arc
					(start 43.166538 -266.812522)
					(mid 43.151659 -266.776601)
					(end 43.115738 -266.761722)
				)
				(arc
					(start 41.716198 -266.761722)
					(mid 41.680277 -266.776601)
					(end 41.665398 -266.812522)
				)
			)
		)
	)
	(zone
		(layers "In1.Cu" "In2.Cu")
		(hatch none 0.5)
		(connect_pads
			(clearance 0)
		)
		(min_thickness 0.25)
		(keepout
			(tracks not_allowed)
			(vias allowed)
			(pads allowed)
			(copperpour not_allowed)
			(footprints allowed)
		)
		(placement
			(enabled no)
			(sheetname "")
		)
		(fill yes
			(thermal_gap 0.5)
			(thermal_bridge_width 0.5)
			(island_removal_mode 0)
		)
		(polygon
			(pts
				(arc
					(start 210.86953 -266.371324)
					(mid 210.884409 -266.407245)
					(end 210.92033 -266.422124)
				)
				(arc
					(start 212.31987 -266.422124)
					(mid 212.355791 -266.407245)
					(end 212.37067 -266.371324)
				)
				(arc
					(start 212.37067 -265.962384)
					(mid 212.355791 -265.926463)
					(end 212.31987 -265.911584)
				)
				(arc
					(start 210.92033 -265.911584)
					(mid 210.884409 -265.926463)
					(end 210.86953 -265.962384)
				)
			)
		)
	)
	(zone
		(layers "In1.Cu" "In2.Cu")
		(hatch none 0.5)
		(connect_pads
			(clearance 0)
		)
		(min_thickness 0.25)
		(keepout
			(tracks not_allowed)
			(vias allowed)
			(pads allowed)
			(copperpour not_allowed)
			(footprints allowed)
		)
		(placement
			(enabled no)
			(sheetname "")
		)
		(fill yes
			(thermal_gap 0.5)
			(thermal_bridge_width 0.5)
			(island_removal_mode 0)
		)
		(polygon
			(pts
				(arc
					(start 199.881998 -231.521508)
					(mid 199.896877 -231.557429)
					(end 199.932798 -231.572308)
				)
				(arc
					(start 201.332338 -231.572308)
					(mid 201.368259 -231.557429)
					(end 201.383138 -231.521508)
				)
				(arc
					(start 201.383138 -231.112568)
					(mid 201.368259 -231.076647)
					(end 201.332338 -231.061768)
				)
				(arc
					(start 199.932798 -231.061768)
					(mid 199.896877 -231.076647)
					(end 199.881998 -231.112568)
				)
			)
		)
	)
	(zone
		(layers "In1.Cu" "In2.Cu")
		(hatch none 0.5)
		(connect_pads
			(clearance 0)
		)
		(min_thickness 0.25)
		(keepout
			(tracks not_allowed)
			(vias allowed)
			(pads allowed)
			(copperpour not_allowed)
			(footprints allowed)
		)
		(placement
			(enabled no)
			(sheetname "")
		)
		(fill yes
			(thermal_gap 0.5)
			(thermal_bridge_width 0.5)
			(island_removal_mode 0)
		)
		(polygon
			(pts
				(arc
					(start 277.961598 -269.771368)
					(mid 277.976477 -269.807289)
					(end 278.012398 -269.822168)
				)
				(arc
					(start 279.411938 -269.822168)
					(mid 279.447859 -269.807289)
					(end 279.462738 -269.771368)
				)
				(arc
					(start 279.462738 -269.362428)
					(mid 279.447859 -269.326507)
					(end 279.411938 -269.311628)
				)
				(arc
					(start 278.012398 -269.311628)
					(mid 277.976477 -269.326507)
					(end 277.961598 -269.362428)
				)
			)
		)
	)
	(zone
		(layers "In1.Cu" "In2.Cu")
		(hatch none 0.5)
		(connect_pads
			(clearance 0)
		)
		(min_thickness 0.25)
		(keepout
			(tracks not_allowed)
			(vias allowed)
			(pads allowed)
			(copperpour not_allowed)
			(footprints allowed)
		)
		(placement
			(enabled no)
			(sheetname "")
		)
		(fill yes
			(thermal_gap 0.5)
			(thermal_bridge_width 0.5)
			(island_removal_mode 0)
		)
		(polygon
			(pts
				(arc
					(start 11.490198 -209.421476)
					(mid 11.505077 -209.457397)
					(end 11.540998 -209.472276)
				)
				(arc
					(start 12.940538 -209.472276)
					(mid 12.976459 -209.457397)
					(end 12.991338 -209.421476)
				)
				(arc
					(start 12.991338 -209.012536)
					(mid 12.976459 -208.976615)
					(end 12.940538 -208.961736)
				)
				(arc
					(start 11.540998 -208.961736)
					(mid 11.505077 -208.976615)
					(end 11.490198 -209.012536)
				)
			)
		)
	)
	(zone
		(layers "In1.Cu" "In2.Cu")
		(hatch none 0.5)
		(connect_pads
			(clearance 0)
		)
		(min_thickness 0.25)
		(keepout
			(tracks not_allowed)
			(vias allowed)
			(pads allowed)
			(copperpour not_allowed)
			(footprints allowed)
		)
		(placement
			(enabled no)
			(sheetname "")
		)
		(fill yes
			(thermal_gap 0.5)
			(thermal_bridge_width 0.5)
			(island_removal_mode 0)
		)
		(polygon
			(pts
				(arc
					(start 11.490198 -248.521474)
					(mid 11.505077 -248.557395)
					(end 11.540998 -248.572274)
				)
				(arc
					(start 12.940538 -248.572274)
					(mid 12.976459 -248.557395)
					(end 12.991338 -248.521474)
				)
				(arc
					(start 12.991338 -248.112534)
					(mid 12.976459 -248.076613)
					(end 12.940538 -248.061734)
				)
				(arc
					(start 11.540998 -248.061734)
					(mid 11.505077 -248.076613)
					(end 11.490198 -248.112534)
				)
			)
		)
	)
	(zone
		(layers "In1.Cu" "In2.Cu")
		(hatch none 0.5)
		(connect_pads
			(clearance 0)
		)
		(min_thickness 0.25)
		(keepout
			(tracks not_allowed)
			(vias allowed)
			(pads allowed)
			(copperpour not_allowed)
			(footprints allowed)
		)
		(placement
			(enabled no)
			(sheetname "")
		)
		(fill yes
			(thermal_gap 0.5)
			(thermal_bridge_width 0.5)
			(island_removal_mode 0)
		)
		(polygon
			(pts
				(arc
					(start 37.56533 -241.721386)
					(mid 37.580209 -241.757307)
					(end 37.61613 -241.772186)
				)
				(arc
					(start 39.01567 -241.772186)
					(mid 39.051591 -241.757307)
					(end 39.06647 -241.721386)
				)
				(arc
					(start 39.06647 -241.312446)
					(mid 39.051591 -241.276525)
					(end 39.01567 -241.261646)
				)
				(arc
					(start 37.61613 -241.261646)
					(mid 37.580209 -241.276525)
					(end 37.56533 -241.312446)
				)
			)
		)
	)
	(zone
		(layers "In1.Cu" "In2.Cu")
		(hatch none 0.5)
		(connect_pads
			(clearance 0)
		)
		(min_thickness 0.25)
		(keepout
			(tracks not_allowed)
			(vias allowed)
			(pads allowed)
			(copperpour not_allowed)
			(footprints allowed)
		)
		(placement
			(enabled no)
			(sheetname "")
		)
		(fill yes
			(thermal_gap 0.5)
			(thermal_bridge_width 0.5)
			(island_removal_mode 0)
		)
		(polygon
			(pts
				(arc
					(start 262.873998 -241.721386)
					(mid 262.888877 -241.757307)
					(end 262.924798 -241.772186)
				)
				(arc
					(start 264.324338 -241.772186)
					(mid 264.360259 -241.757307)
					(end 264.375138 -241.721386)
				)
				(arc
					(start 264.375138 -241.312446)
					(mid 264.360259 -241.276525)
					(end 264.324338 -241.261646)
				)
				(arc
					(start 262.924798 -241.261646)
					(mid 262.888877 -241.276525)
					(end 262.873998 -241.312446)
				)
			)
		)
	)
	(zone
		(layers "In1.Cu" "In2.Cu")
		(hatch none 0.5)
		(connect_pads
			(clearance 0)
		)
		(min_thickness 0.25)
		(keepout
			(tracks not_allowed)
			(vias allowed)
			(pads allowed)
			(copperpour not_allowed)
			(footprints allowed)
		)
		(placement
			(enabled no)
			(sheetname "")
		)
		(fill yes
			(thermal_gap 0.5)
			(thermal_bridge_width 0.5)
			(island_removal_mode 0)
		)
		(polygon
			(pts
				(arc
					(start 214.969598 -274.871434)
					(mid 214.984477 -274.907355)
					(end 215.020398 -274.922234)
				)
				(arc
					(start 216.419938 -274.922234)
					(mid 216.455859 -274.907355)
					(end 216.470738 -274.871434)
				)
				(arc
					(start 216.470738 -274.462494)
					(mid 216.455859 -274.426573)
					(end 216.419938 -274.411694)
				)
				(arc
					(start 215.020398 -274.411694)
					(mid 214.984477 -274.426573)
					(end 214.969598 -274.462494)
				)
			)
		)
	)
	(zone
		(layers "In1.Cu" "In2.Cu")
		(hatch none 0.5)
		(connect_pads
			(clearance 0)
		)
		(min_thickness 0.25)
		(keepout
			(tracks not_allowed)
			(vias allowed)
			(pads allowed)
			(copperpour not_allowed)
			(footprints allowed)
		)
		(placement
			(enabled no)
			(sheetname "")
		)
		(fill yes
			(thermal_gap 0.5)
			(thermal_bridge_width 0.5)
			(island_removal_mode 0)
		)
		(polygon
			(pts
				(arc
					(start 64.296798 -293.571422)
					(mid 64.311677 -293.607343)
					(end 64.347598 -293.622222)
				)
				(arc
					(start 65.747138 -293.622222)
					(mid 65.783059 -293.607343)
					(end 65.797938 -293.571422)
				)
				(arc
					(start 65.797938 -293.162482)
					(mid 65.783059 -293.126561)
					(end 65.747138 -293.111682)
				)
				(arc
					(start 64.347598 -293.111682)
					(mid 64.311677 -293.126561)
					(end 64.296798 -293.162482)
				)
			)
		)
	)
	(zone
		(layers "In1.Cu" "In2.Cu")
		(hatch none 0.5)
		(connect_pads
			(clearance 0)
		)
		(min_thickness 0.25)
		(keepout
			(tracks not_allowed)
			(vias allowed)
			(pads allowed)
			(copperpour not_allowed)
			(footprints allowed)
		)
		(placement
			(enabled no)
			(sheetname "")
		)
		(fill yes
			(thermal_gap 0.5)
			(thermal_bridge_width 0.5)
			(island_removal_mode 0)
		)
		(polygon
			(pts
				(arc
					(start 428.634398 -279.121362)
					(mid 428.649277 -279.157283)
					(end 428.685198 -279.172162)
				)
				(arc
					(start 430.084738 -279.172162)
					(mid 430.120659 -279.157283)
					(end 430.135538 -279.121362)
				)
				(arc
					(start 430.135538 -278.712422)
					(mid 430.120659 -278.676501)
					(end 430.084738 -278.661622)
				)
				(arc
					(start 428.685198 -278.661622)
					(mid 428.649277 -278.676501)
					(end 428.634398 -278.712422)
				)
			)
		)
	)
	(zone
		(layers "In1.Cu" "In2.Cu")
		(hatch none 0.5)
		(connect_pads
			(clearance 0)
		)
		(min_thickness 0.25)
		(keepout
			(tracks not_allowed)
			(vias allowed)
			(pads allowed)
			(copperpour not_allowed)
			(footprints allowed)
		)
		(placement
			(enabled no)
			(sheetname "")
		)
		(fill yes
			(thermal_gap 0.5)
			(thermal_bridge_width 0.5)
			(island_removal_mode 0)
		)
		(polygon
			(pts
				(arc
					(start 26.577798 -265.52144)
					(mid 26.592677 -265.557361)
					(end 26.628598 -265.57224)
				)
				(arc
					(start 28.028138 -265.57224)
					(mid 28.064059 -265.557361)
					(end 28.078938 -265.52144)
				)
				(arc
					(start 28.078938 -265.1125)
					(mid 28.064059 -265.076579)
					(end 28.028138 -265.0617)
				)
				(arc
					(start 26.628598 -265.0617)
					(mid 26.592677 -265.076579)
					(end 26.577798 -265.1125)
				)
			)
		)
	)
	(zone
		(layers "In1.Cu" "In2.Cu")
		(hatch none 0.5)
		(connect_pads
			(clearance 0)
		)
		(min_thickness 0.25)
		(keepout
			(tracks not_allowed)
			(vias allowed)
			(pads allowed)
			(copperpour not_allowed)
			(footprints allowed)
		)
		(placement
			(enabled no)
			(sheetname "")
		)
		(fill yes
			(thermal_gap 0.5)
			(thermal_bridge_width 0.5)
			(island_removal_mode 0)
		)
		(polygon
			(pts
				(arc
					(start 425.190666 -246.821452)
					(mid 425.205545 -246.857373)
					(end 425.241466 -246.872252)
				)
				(arc
					(start 426.641006 -246.872252)
					(mid 426.676927 -246.857373)
					(end 426.691806 -246.821452)
				)
				(arc
					(start 426.691806 -246.412512)
					(mid 426.676927 -246.376591)
					(end 426.641006 -246.361712)
				)
				(arc
					(start 425.241466 -246.361712)
					(mid 425.205545 -246.376591)
					(end 425.190666 -246.412512)
				)
			)
		)
	)
	(zone
		(layers "In1.Cu" "In2.Cu")
		(hatch none 0.5)
		(connect_pads
			(clearance 0)
		)
		(min_thickness 0.25)
		(keepout
			(tracks not_allowed)
			(vias allowed)
			(pads allowed)
			(copperpour not_allowed)
			(footprints allowed)
		)
		(placement
			(enabled no)
			(sheetname "")
		)
		(fill yes
			(thermal_gap 0.5)
			(thermal_bridge_width 0.5)
			(island_removal_mode 0)
		)
		(polygon
			(pts
				(arc
					(start 184.794398 -315.671454)
					(mid 184.809277 -315.707375)
					(end 184.845198 -315.722254)
				)
				(arc
					(start 186.244738 -315.722254)
					(mid 186.280659 -315.707375)
					(end 186.295538 -315.671454)
				)
				(arc
					(start 186.295538 -315.262514)
					(mid 186.280659 -315.226593)
					(end 186.244738 -315.211714)
				)
				(arc
					(start 184.845198 -315.211714)
					(mid 184.809277 -315.226593)
					(end 184.794398 -315.262514)
				)
			)
		)
	)
	(zone
		(layers "In1.Cu" "In2.Cu")
		(hatch none 0.5)
		(connect_pads
			(clearance 0)
		)
		(min_thickness 0.25)
		(keepout
			(tracks not_allowed)
			(vias allowed)
			(pads allowed)
			(copperpour not_allowed)
			(footprints allowed)
		)
		(placement
			(enabled no)
			(sheetname "")
		)
		(fill yes
			(thermal_gap 0.5)
			(thermal_bridge_width 0.5)
			(island_removal_mode 0)
		)
		(polygon
			(pts
				(arc
					(start 443.721998 -294.421306)
					(mid 443.736877 -294.457227)
					(end 443.772798 -294.472106)
				)
				(arc
					(start 445.172338 -294.472106)
					(mid 445.208259 -294.457227)
					(end 445.223138 -294.421306)
				)
				(arc
					(start 445.223138 -294.012366)
					(mid 445.208259 -293.976445)
					(end 445.172338 -293.961566)
				)
				(arc
					(start 443.772798 -293.961566)
					(mid 443.736877 -293.976445)
					(end 443.721998 -294.012366)
				)
			)
		)
	)
	(zone
		(layers "In1.Cu" "In2.Cu")
		(hatch none 0.5)
		(connect_pads
			(clearance 0)
		)
		(min_thickness 0.25)
		(keepout
			(tracks not_allowed)
			(vias allowed)
			(pads allowed)
			(copperpour not_allowed)
			(footprints allowed)
		)
		(placement
			(enabled no)
			(sheetname "")
		)
		(fill yes
			(thermal_gap 0.5)
			(thermal_bridge_width 0.5)
			(island_removal_mode 0)
		)
		(polygon
			(pts
				(arc
					(start 432.734466 -278.271478)
					(mid 432.749345 -278.307399)
					(end 432.785266 -278.322278)
				)
				(arc
					(start 434.184806 -278.322278)
					(mid 434.220727 -278.307399)
					(end 434.235606 -278.271478)
				)
				(arc
					(start 434.235606 -277.862538)
					(mid 434.220727 -277.826617)
					(end 434.184806 -277.811738)
				)
				(arc
					(start 432.785266 -277.811738)
					(mid 432.749345 -277.826617)
					(end 432.734466 -277.862538)
				)
			)
		)
	)
	(zone
		(layers "In1.Cu" "In2.Cu")
		(hatch none 0.5)
		(connect_pads
			(clearance 0)
		)
		(min_thickness 0.25)
		(keepout
			(tracks not_allowed)
			(vias allowed)
			(pads allowed)
			(copperpour not_allowed)
			(footprints allowed)
		)
		(placement
			(enabled no)
			(sheetname "")
		)
		(fill yes
			(thermal_gap 0.5)
			(thermal_bridge_width 0.5)
			(island_removal_mode 0)
		)
		(polygon
			(pts
				(arc
					(start 447.822066 -291.021516)
					(mid 447.836945 -291.057437)
					(end 447.872866 -291.072316)
				)
				(arc
					(start 449.272406 -291.072316)
					(mid 449.308327 -291.057437)
					(end 449.323206 -291.021516)
				)
				(arc
					(start 449.323206 -290.612576)
					(mid 449.308327 -290.576655)
					(end 449.272406 -290.561776)
				)
				(arc
					(start 447.872866 -290.561776)
					(mid 447.836945 -290.576655)
					(end 447.822066 -290.612576)
				)
			)
		)
	)
	(zone
		(layers "In1.Cu" "In2.Cu")
		(hatch none 0.5)
		(connect_pads
			(clearance 0)
		)
		(min_thickness 0.25)
		(keepout
			(tracks not_allowed)
			(vias allowed)
			(pads allowed)
			(copperpour not_allowed)
			(footprints allowed)
		)
		(placement
			(enabled no)
			(sheetname "")
		)
		(fill yes
			(thermal_gap 0.5)
			(thermal_bridge_width 0.5)
			(island_removal_mode 0)
		)
		(polygon
			(pts
				(arc
					(start 188.23813 -243.421408)
					(mid 188.253009 -243.457329)
					(end 188.28893 -243.472208)
				)
				(arc
					(start 189.68847 -243.472208)
					(mid 189.724391 -243.457329)
					(end 189.73927 -243.421408)
				)
				(arc
					(start 189.73927 -243.012468)
					(mid 189.724391 -242.976547)
					(end 189.68847 -242.961668)
				)
				(arc
					(start 188.28893 -242.961668)
					(mid 188.253009 -242.976547)
					(end 188.23813 -243.012468)
				)
			)
		)
	)
	(zone
		(layers "In1.Cu" "In2.Cu")
		(hatch none 0.5)
		(connect_pads
			(clearance 0)
		)
		(min_thickness 0.25)
		(keepout
			(tracks not_allowed)
			(vias allowed)
			(pads allowed)
			(copperpour not_allowed)
			(footprints allowed)
		)
		(placement
			(enabled no)
			(sheetname "")
		)
		(fill yes
			(thermal_gap 0.5)
			(thermal_bridge_width 0.5)
			(island_removal_mode 0)
		)
		(polygon
			(pts
				(arc
					(start 162.162998 -203.471526)
					(mid 162.177877 -203.507447)
					(end 162.213798 -203.522326)
				)
				(arc
					(start 163.613338 -203.522326)
					(mid 163.649259 -203.507447)
					(end 163.664138 -203.471526)
				)
				(arc
					(start 163.664138 -203.062586)
					(mid 163.649259 -203.026665)
					(end 163.613338 -203.011786)
				)
				(arc
					(start 162.213798 -203.011786)
					(mid 162.177877 -203.026665)
					(end 162.162998 -203.062586)
				)
			)
		)
	)
	(zone
		(layers "In1.Cu" "In2.Cu")
		(hatch none 0.5)
		(connect_pads
			(clearance 0)
		)
		(min_thickness 0.25)
		(keepout
			(tracks not_allowed)
			(vias allowed)
			(pads allowed)
			(copperpour not_allowed)
			(footprints allowed)
		)
		(placement
			(enabled no)
			(sheetname "")
		)
		(fill yes
			(thermal_gap 0.5)
			(thermal_bridge_width 0.5)
			(island_removal_mode 0)
		)
		(polygon
			(pts
				(arc
					(start 169.706798 -270.621506)
					(mid 169.721677 -270.657427)
					(end 169.757598 -270.672306)
				)
				(arc
					(start 171.157138 -270.672306)
					(mid 171.193059 -270.657427)
					(end 171.207938 -270.621506)
				)
				(arc
					(start 171.207938 -270.212566)
					(mid 171.193059 -270.176645)
					(end 171.157138 -270.161766)
				)
				(arc
					(start 169.757598 -270.161766)
					(mid 169.721677 -270.176645)
					(end 169.706798 -270.212566)
				)
			)
		)
	)
	(zone
		(layers "In1.Cu" "In2.Cu")
		(hatch none 0.5)
		(connect_pads
			(clearance 0)
		)
		(min_thickness 0.25)
		(keepout
			(tracks not_allowed)
			(vias allowed)
			(pads allowed)
			(copperpour not_allowed)
			(footprints allowed)
		)
		(placement
			(enabled no)
			(sheetname "")
		)
		(fill yes
			(thermal_gap 0.5)
			(thermal_bridge_width 0.5)
			(island_removal_mode 0)
		)
		(polygon
			(pts
				(arc
					(start 308.136798 -207.721454)
					(mid 308.151677 -207.757375)
					(end 308.187598 -207.772254)
				)
				(arc
					(start 309.587138 -207.772254)
					(mid 309.623059 -207.757375)
					(end 309.637938 -207.721454)
				)
				(arc
					(start 309.637938 -207.312514)
					(mid 309.623059 -207.276593)
					(end 309.587138 -207.261714)
				)
				(arc
					(start 308.187598 -207.261714)
					(mid 308.151677 -207.276593)
					(end 308.136798 -207.312514)
				)
			)
		)
	)
	(zone
		(layers "In1.Cu" "In2.Cu")
		(hatch none 0.5)
		(connect_pads
			(clearance 0)
		)
		(min_thickness 0.25)
		(keepout
			(tracks not_allowed)
			(vias allowed)
			(pads allowed)
			(copperpour not_allowed)
			(footprints allowed)
		)
		(placement
			(enabled no)
			(sheetname "")
		)
		(fill yes
			(thermal_gap 0.5)
			(thermal_bridge_width 0.5)
			(island_removal_mode 0)
		)
		(polygon
			(pts
				(arc
					(start 410.103066 -274.871434)
					(mid 410.117945 -274.907355)
					(end 410.153866 -274.922234)
				)
				(arc
					(start 411.553406 -274.922234)
					(mid 411.589327 -274.907355)
					(end 411.604206 -274.871434)
				)
				(arc
					(start 411.604206 -274.462494)
					(mid 411.589327 -274.426573)
					(end 411.553406 -274.411694)
				)
				(arc
					(start 410.153866 -274.411694)
					(mid 410.117945 -274.426573)
					(end 410.103066 -274.462494)
				)
			)
		)
	)
	(zone
		(layers "In1.Cu" "In2.Cu")
		(hatch none 0.5)
		(connect_pads
			(clearance 0)
		)
		(min_thickness 0.25)
		(keepout
			(tracks not_allowed)
			(vias allowed)
			(pads allowed)
			(copperpour not_allowed)
			(footprints allowed)
		)
		(placement
			(enabled no)
			(sheetname "")
		)
		(fill yes
			(thermal_gap 0.5)
			(thermal_bridge_width 0.5)
			(island_removal_mode 0)
		)
		(polygon
			(pts
				(arc
					(start 440.278266 -267.221462)
					(mid 440.293145 -267.257383)
					(end 440.329066 -267.272262)
				)
				(arc
					(start 441.728606 -267.272262)
					(mid 441.764527 -267.257383)
					(end 441.779406 -267.221462)
				)
				(arc
					(start 441.779406 -266.812522)
					(mid 441.764527 -266.776601)
					(end 441.728606 -266.761722)
				)
				(arc
					(start 440.329066 -266.761722)
					(mid 440.293145 -266.776601)
					(end 440.278266 -266.812522)
				)
			)
		)
	)
	(zone
		(layers "In1.Cu" "In2.Cu")
		(hatch none 0.5)
		(connect_pads
			(clearance 0)
		)
		(min_thickness 0.25)
		(keepout
			(tracks not_allowed)
			(vias allowed)
			(pads allowed)
			(copperpour not_allowed)
			(footprints allowed)
		)
		(placement
			(enabled no)
			(sheetname "")
		)
		(fill yes
			(thermal_gap 0.5)
			(thermal_bridge_width 0.5)
			(island_removal_mode 0)
		)
		(polygon
			(pts
				(arc
					(start 436.178198 -228.121464)
					(mid 436.193077 -228.157385)
					(end 436.228998 -228.172264)
				)
				(arc
					(start 437.628538 -228.172264)
					(mid 437.664459 -228.157385)
					(end 437.679338 -228.121464)
				)
				(arc
					(start 437.679338 -227.712524)
					(mid 437.664459 -227.676603)
					(end 437.628538 -227.661724)
				)
				(arc
					(start 436.228998 -227.661724)
					(mid 436.193077 -227.676603)
					(end 436.178198 -227.712524)
				)
			)
		)
	)
	(zone
		(layers "In1.Cu" "In2.Cu")
		(hatch none 0.5)
		(connect_pads
			(clearance 0)
		)
		(min_thickness 0.25)
		(keepout
			(tracks not_allowed)
			(vias allowed)
			(pads allowed)
			(copperpour not_allowed)
			(footprints allowed)
		)
		(placement
			(enabled no)
			(sheetname "")
		)
		(fill yes
			(thermal_gap 0.5)
			(thermal_bridge_width 0.5)
			(island_removal_mode 0)
		)
		(polygon
			(pts
				(arc
					(start 436.178198 -200.071482)
					(mid 436.193077 -200.107403)
					(end 436.228998 -200.122282)
				)
				(arc
					(start 437.628538 -200.122282)
					(mid 437.664459 -200.107403)
					(end 437.679338 -200.071482)
				)
				(arc
					(start 437.679338 -199.662542)
					(mid 437.664459 -199.626621)
					(end 437.628538 -199.611742)
				)
				(arc
					(start 436.228998 -199.611742)
					(mid 436.193077 -199.626621)
					(end 436.178198 -199.662542)
				)
			)
		)
	)
	(zone
		(layers "In1.Cu" "In2.Cu")
		(hatch none 0.5)
		(connect_pads
			(clearance 0)
		)
		(min_thickness 0.25)
		(keepout
			(tracks not_allowed)
			(vias allowed)
			(pads allowed)
			(copperpour not_allowed)
			(footprints allowed)
		)
		(placement
			(enabled no)
			(sheetname "")
		)
		(fill yes
			(thermal_gap 0.5)
			(thermal_bridge_width 0.5)
			(island_removal_mode 0)
		)
		(polygon
			(pts
				(arc
					(start 458.809598 -223.021398)
					(mid 458.824477 -223.057319)
					(end 458.860398 -223.072198)
				)
				(arc
					(start 460.259938 -223.072198)
					(mid 460.295859 -223.057319)
					(end 460.310738 -223.021398)
				)
				(arc
					(start 460.310738 -222.612458)
					(mid 460.295859 -222.576537)
					(end 460.259938 -222.561658)
				)
				(arc
					(start 458.860398 -222.561658)
					(mid 458.824477 -222.576537)
					(end 458.809598 -222.612458)
				)
			)
		)
	)
	(zone
		(layers "In1.Cu" "In2.Cu")
		(hatch none 0.5)
		(connect_pads
			(clearance 0)
		)
		(min_thickness 0.25)
		(keepout
			(tracks not_allowed)
			(vias allowed)
			(pads allowed)
			(copperpour not_allowed)
			(footprints allowed)
		)
		(placement
			(enabled no)
			(sheetname "")
		)
		(fill yes
			(thermal_gap 0.5)
			(thermal_bridge_width 0.5)
			(island_removal_mode 0)
		)
		(polygon
			(pts
				(arc
					(start 417.646866 -220.471492)
					(mid 417.661745 -220.507413)
					(end 417.697666 -220.522292)
				)
				(arc
					(start 419.097206 -220.522292)
					(mid 419.133127 -220.507413)
					(end 419.148006 -220.471492)
				)
				(arc
					(start 419.148006 -220.062552)
					(mid 419.133127 -220.026631)
					(end 419.097206 -220.011752)
				)
				(arc
					(start 417.697666 -220.011752)
					(mid 417.661745 -220.026631)
					(end 417.646866 -220.062552)
				)
			)
		)
	)
	(zone
		(layers "In1.Cu" "In2.Cu")
		(hatch none 0.5)
		(connect_pads
			(clearance 0)
		)
		(min_thickness 0.25)
		(keepout
			(tracks not_allowed)
			(vias allowed)
			(pads allowed)
			(copperpour not_allowed)
			(footprints allowed)
		)
		(placement
			(enabled no)
			(sheetname "")
		)
		(fill yes
			(thermal_gap 0.5)
			(thermal_bridge_width 0.5)
			(island_removal_mode 0)
		)
		(polygon
			(pts
				(arc
					(start 45.10913 -234.071414)
					(mid 45.124009 -234.107335)
					(end 45.15993 -234.122214)
				)
				(arc
					(start 46.55947 -234.122214)
					(mid 46.595391 -234.107335)
					(end 46.61027 -234.071414)
				)
				(arc
					(start 46.61027 -233.662474)
					(mid 46.595391 -233.626553)
					(end 46.55947 -233.611674)
				)
				(arc
					(start 45.15993 -233.611674)
					(mid 45.124009 -233.626553)
					(end 45.10913 -233.662474)
				)
			)
		)
	)
	(zone
		(layers "In1.Cu" "In2.Cu")
		(hatch none 0.5)
		(connect_pads
			(clearance 0)
		)
		(min_thickness 0.25)
		(keepout
			(tracks not_allowed)
			(vias allowed)
			(pads allowed)
			(copperpour not_allowed)
			(footprints allowed)
		)
		(placement
			(enabled no)
			(sheetname "")
		)
		(fill yes
			(thermal_gap 0.5)
			(thermal_bridge_width 0.5)
			(island_removal_mode 0)
		)
		(polygon
			(pts
				(arc
					(start 11.490198 -265.52144)
					(mid 11.505077 -265.557361)
					(end 11.540998 -265.57224)
				)
				(arc
					(start 12.940538 -265.57224)
					(mid 12.976459 -265.557361)
					(end 12.991338 -265.52144)
				)
				(arc
					(start 12.991338 -265.1125)
					(mid 12.976459 -265.076579)
					(end 12.940538 -265.0617)
				)
				(arc
					(start 11.540998 -265.0617)
					(mid 11.505077 -265.076579)
					(end 11.490198 -265.1125)
				)
			)
		)
	)
	(zone
		(layers "In1.Cu" "In2.Cu")
		(hatch none 0.5)
		(connect_pads
			(clearance 0)
		)
		(min_thickness 0.25)
		(keepout
			(tracks not_allowed)
			(vias allowed)
			(pads allowed)
			(copperpour not_allowed)
			(footprints allowed)
		)
		(placement
			(enabled no)
			(sheetname "")
		)
		(fill yes
			(thermal_gap 0.5)
			(thermal_bridge_width 0.5)
			(island_removal_mode 0)
		)
		(polygon
			(pts
				(arc
					(start 203.32573 -307.171344)
					(mid 203.340609 -307.207265)
					(end 203.37653 -307.222144)
				)
				(arc
					(start 204.77607 -307.222144)
					(mid 204.811991 -307.207265)
					(end 204.82687 -307.171344)
				)
				(arc
					(start 204.82687 -306.762404)
					(mid 204.811991 -306.726483)
					(end 204.77607 -306.711604)
				)
				(arc
					(start 203.37653 -306.711604)
					(mid 203.340609 -306.726483)
					(end 203.32573 -306.762404)
				)
			)
		)
	)
	(zone
		(layers "In1.Cu" "In2.Cu")
		(hatch none 0.5)
		(connect_pads
			(clearance 0)
		)
		(min_thickness 0.25)
		(keepout
			(tracks not_allowed)
			(vias allowed)
			(pads allowed)
			(copperpour not_allowed)
			(footprints allowed)
		)
		(placement
			(enabled no)
			(sheetname "")
		)
		(fill yes
			(thermal_gap 0.5)
			(thermal_bridge_width 0.5)
			(island_removal_mode 0)
		)
		(polygon
			(pts
				(arc
					(start 455.365866 -281.671522)
					(mid 455.380745 -281.707443)
					(end 455.416666 -281.722322)
				)
				(arc
					(start 456.816206 -281.722322)
					(mid 456.852127 -281.707443)
					(end 456.867006 -281.671522)
				)
				(arc
					(start 456.867006 -281.262582)
					(mid 456.852127 -281.226661)
					(end 456.816206 -281.211782)
				)
				(arc
					(start 455.416666 -281.211782)
					(mid 455.380745 -281.226661)
					(end 455.365866 -281.262582)
				)
			)
		)
	)
	(zone
		(layers "In1.Cu" "In2.Cu")
		(hatch none 0.5)
		(connect_pads
			(clearance 0)
		)
		(min_thickness 0.25)
		(keepout
			(tracks not_allowed)
			(vias allowed)
			(pads allowed)
			(copperpour not_allowed)
			(footprints allowed)
		)
		(placement
			(enabled no)
			(sheetname "")
		)
		(fill yes
			(thermal_gap 0.5)
			(thermal_bridge_width 0.5)
			(island_removal_mode 0)
		)
		(polygon
			(pts
				(arc
					(start 41.665398 -309.721504)
					(mid 41.680277 -309.757425)
					(end 41.716198 -309.772304)
				)
				(arc
					(start 43.115738 -309.772304)
					(mid 43.151659 -309.757425)
					(end 43.166538 -309.721504)
				)
				(arc
					(start 43.166538 -309.312564)
					(mid 43.151659 -309.276643)
					(end 43.115738 -309.261764)
				)
				(arc
					(start 41.716198 -309.261764)
					(mid 41.680277 -309.276643)
					(end 41.665398 -309.312564)
				)
			)
		)
	)
	(zone
		(layers "In1.Cu" "In2.Cu")
		(hatch none 0.5)
		(connect_pads
			(clearance 0)
		)
		(min_thickness 0.25)
		(keepout
			(tracks not_allowed)
			(vias allowed)
			(pads allowed)
			(copperpour not_allowed)
			(footprints allowed)
		)
		(placement
			(enabled no)
			(sheetname "")
		)
		(fill yes
			(thermal_gap 0.5)
			(thermal_bridge_width 0.5)
			(island_removal_mode 0)
		)
		(polygon
			(pts
				(arc
					(start 52.65293 -259.57149)
					(mid 52.667809 -259.607411)
					(end 52.70373 -259.62229)
				)
				(arc
					(start 54.10327 -259.62229)
					(mid 54.139191 -259.607411)
					(end 54.15407 -259.57149)
				)
				(arc
					(start 54.15407 -259.16255)
					(mid 54.139191 -259.126629)
					(end 54.10327 -259.11175)
				)
				(arc
					(start 52.70373 -259.11175)
					(mid 52.667809 -259.126629)
					(end 52.65293 -259.16255)
				)
			)
		)
	)
	(zone
		(layers "In1.Cu" "In2.Cu")
		(hatch none 0.5)
		(connect_pads
			(clearance 0)
		)
		(min_thickness 0.25)
		(keepout
			(tracks not_allowed)
			(vias allowed)
			(pads allowed)
			(copperpour not_allowed)
			(footprints allowed)
		)
		(placement
			(enabled no)
			(sheetname "")
		)
		(fill yes
			(thermal_gap 0.5)
			(thermal_bridge_width 0.5)
			(island_removal_mode 0)
		)
		(polygon
			(pts
				(arc
					(start 56.752998 -203.471526)
					(mid 56.767877 -203.507447)
					(end 56.803798 -203.522326)
				)
				(arc
					(start 58.203338 -203.522326)
					(mid 58.239259 -203.507447)
					(end 58.254138 -203.471526)
				)
				(arc
					(start 58.254138 -203.062586)
					(mid 58.239259 -203.026665)
					(end 58.203338 -203.011786)
				)
				(arc
					(start 56.803798 -203.011786)
					(mid 56.767877 -203.026665)
					(end 56.752998 -203.062586)
				)
			)
		)
	)
	(zone
		(layers "In1.Cu" "In2.Cu")
		(hatch none 0.5)
		(connect_pads
			(clearance 0)
		)
		(min_thickness 0.25)
		(keepout
			(tracks not_allowed)
			(vias allowed)
			(pads allowed)
			(copperpour not_allowed)
			(footprints allowed)
		)
		(placement
			(enabled no)
			(sheetname "")
		)
		(fill yes
			(thermal_gap 0.5)
			(thermal_bridge_width 0.5)
			(island_removal_mode 0)
		)
		(polygon
			(pts
				(arc
					(start 289.605466 -304.621438)
					(mid 289.620345 -304.657359)
					(end 289.656266 -304.672238)
				)
				(arc
					(start 291.055806 -304.672238)
					(mid 291.091727 -304.657359)
					(end 291.106606 -304.621438)
				)
				(arc
					(start 291.106606 -304.212498)
					(mid 291.091727 -304.176577)
					(end 291.055806 -304.161698)
				)
				(arc
					(start 289.656266 -304.161698)
					(mid 289.620345 -304.176577)
					(end 289.605466 -304.212498)
				)
			)
		)
	)
	(zone
		(layers "In1.Cu" "In2.Cu")
		(hatch none 0.5)
		(connect_pads
			(clearance 0)
		)
		(min_thickness 0.25)
		(keepout
			(tracks not_allowed)
			(vias allowed)
			(pads allowed)
			(copperpour not_allowed)
			(footprints allowed)
		)
		(placement
			(enabled no)
			(sheetname "")
		)
		(fill yes
			(thermal_gap 0.5)
			(thermal_bridge_width 0.5)
			(island_removal_mode 0)
		)
		(polygon
			(pts
				(arc
					(start 165.60673 -202.621388)
					(mid 165.621609 -202.657309)
					(end 165.65753 -202.672188)
				)
				(arc
					(start 167.05707 -202.672188)
					(mid 167.092991 -202.657309)
					(end 167.10787 -202.621388)
				)
				(arc
					(start 167.10787 -202.212448)
					(mid 167.092991 -202.176527)
					(end 167.05707 -202.161648)
				)
				(arc
					(start 165.65753 -202.161648)
					(mid 165.621609 -202.176527)
					(end 165.60673 -202.212448)
				)
			)
		)
	)
	(zone
		(layers "In1.Cu" "In2.Cu")
		(hatch none 0.5)
		(connect_pads
			(clearance 0)
		)
		(min_thickness 0.25)
		(keepout
			(tracks not_allowed)
			(vias allowed)
			(pads allowed)
			(copperpour not_allowed)
			(footprints allowed)
		)
		(placement
			(enabled no)
			(sheetname "")
		)
		(fill yes
			(thermal_gap 0.5)
			(thermal_bridge_width 0.5)
			(island_removal_mode 0)
		)
		(polygon
			(pts
				(arc
					(start 45.10913 -244.271292)
					(mid 45.124009 -244.307213)
					(end 45.15993 -244.322092)
				)
				(arc
					(start 46.55947 -244.322092)
					(mid 46.595391 -244.307213)
					(end 46.61027 -244.271292)
				)
				(arc
					(start 46.61027 -243.862352)
					(mid 46.595391 -243.826431)
					(end 46.55947 -243.811552)
				)
				(arc
					(start 45.15993 -243.811552)
					(mid 45.124009 -243.826431)
					(end 45.10913 -243.862352)
				)
			)
		)
	)
	(zone
		(layers "In1.Cu" "In2.Cu")
		(hatch none 0.5)
		(connect_pads
			(clearance 0)
		)
		(min_thickness 0.25)
		(keepout
			(tracks not_allowed)
			(vias allowed)
			(pads allowed)
			(copperpour not_allowed)
			(footprints allowed)
		)
		(placement
			(enabled no)
			(sheetname "")
		)
		(fill yes
			(thermal_gap 0.5)
			(thermal_bridge_width 0.5)
			(island_removal_mode 0)
		)
		(polygon
			(pts
				(arc
					(start 199.881998 -270.621506)
					(mid 199.896877 -270.657427)
					(end 199.932798 -270.672306)
				)
				(arc
					(start 201.332338 -270.672306)
					(mid 201.368259 -270.657427)
					(end 201.383138 -270.621506)
				)
				(arc
					(start 201.383138 -270.212566)
					(mid 201.368259 -270.176645)
					(end 201.332338 -270.161766)
				)
				(arc
					(start 199.932798 -270.161766)
					(mid 199.896877 -270.176645)
					(end 199.881998 -270.212566)
				)
			)
		)
	)
	(zone
		(layers "In1.Cu" "In2.Cu")
		(hatch none 0.5)
		(connect_pads
			(clearance 0)
		)
		(min_thickness 0.25)
		(keepout
			(tracks not_allowed)
			(vias allowed)
			(pads allowed)
			(copperpour not_allowed)
			(footprints allowed)
		)
		(placement
			(enabled no)
			(sheetname "")
		)
		(fill yes
			(thermal_gap 0.5)
			(thermal_bridge_width 0.5)
			(island_removal_mode 0)
		)
		(polygon
			(pts
				(arc
					(start 443.721998 -288.471356)
					(mid 443.736877 -288.507277)
					(end 443.772798 -288.522156)
				)
				(arc
					(start 445.172338 -288.522156)
					(mid 445.208259 -288.507277)
					(end 445.223138 -288.471356)
				)
				(arc
					(start 445.223138 -288.062416)
					(mid 445.208259 -288.026495)
					(end 445.172338 -288.011616)
				)
				(arc
					(start 443.772798 -288.011616)
					(mid 443.736877 -288.026495)
					(end 443.721998 -288.062416)
				)
			)
		)
	)
	(zone
		(layers "In1.Cu" "In2.Cu")
		(hatch none 0.5)
		(connect_pads
			(clearance 0)
		)
		(min_thickness 0.25)
		(keepout
			(tracks not_allowed)
			(vias allowed)
			(pads allowed)
			(copperpour not_allowed)
			(footprints allowed)
		)
		(placement
			(enabled no)
			(sheetname "")
		)
		(fill yes
			(thermal_gap 0.5)
			(thermal_bridge_width 0.5)
			(island_removal_mode 0)
		)
		(polygon
			(pts
				(arc
					(start 443.721998 -240.021364)
					(mid 443.736877 -240.057285)
					(end 443.772798 -240.072164)
				)
				(arc
					(start 445.172338 -240.072164)
					(mid 445.208259 -240.057285)
					(end 445.223138 -240.021364)
				)
				(arc
					(start 445.223138 -239.612424)
					(mid 445.208259 -239.576503)
					(end 445.172338 -239.561624)
				)
				(arc
					(start 443.772798 -239.561624)
					(mid 443.736877 -239.576503)
					(end 443.721998 -239.612424)
				)
			)
		)
	)
	(zone
		(layers "In1.Cu" "In2.Cu")
		(hatch none 0.5)
		(connect_pads
			(clearance 0)
		)
		(min_thickness 0.25)
		(keepout
			(tracks not_allowed)
			(vias allowed)
			(pads allowed)
			(copperpour not_allowed)
			(footprints allowed)
		)
		(placement
			(enabled no)
			(sheetname "")
		)
		(fill yes
			(thermal_gap 0.5)
			(thermal_bridge_width 0.5)
			(island_removal_mode 0)
		)
		(polygon
			(pts
				(arc
					(start 165.60673 -247.671336)
					(mid 165.621609 -247.707257)
					(end 165.65753 -247.722136)
				)
				(arc
					(start 167.05707 -247.722136)
					(mid 167.092991 -247.707257)
					(end 167.10787 -247.671336)
				)
				(arc
					(start 167.10787 -247.262396)
					(mid 167.092991 -247.226475)
					(end 167.05707 -247.211596)
				)
				(arc
					(start 165.65753 -247.211596)
					(mid 165.621609 -247.226475)
					(end 165.60673 -247.262396)
				)
			)
		)
	)
	(zone
		(layers "In1.Cu" "In2.Cu")
		(hatch none 0.5)
		(connect_pads
			(clearance 0)
		)
		(min_thickness 0.25)
		(keepout
			(tracks not_allowed)
			(vias allowed)
			(pads allowed)
			(copperpour not_allowed)
			(footprints allowed)
		)
		(placement
			(enabled no)
			(sheetname "")
		)
		(fill yes
			(thermal_gap 0.5)
			(thermal_bridge_width 0.5)
			(island_removal_mode 0)
		)
		(polygon
			(pts
				(arc
					(start 14.93393 -294.421306)
					(mid 14.948809 -294.457227)
					(end 14.98473 -294.472106)
				)
				(arc
					(start 16.38427 -294.472106)
					(mid 16.420191 -294.457227)
					(end 16.43507 -294.421306)
				)
				(arc
					(start 16.43507 -294.012366)
					(mid 16.420191 -293.976445)
					(end 16.38427 -293.961566)
				)
				(arc
					(start 14.98473 -293.961566)
					(mid 14.948809 -293.976445)
					(end 14.93393 -294.012366)
				)
			)
		)
	)
	(zone
		(layers "In1.Cu" "In2.Cu")
		(hatch none 0.5)
		(connect_pads
			(clearance 0)
		)
		(min_thickness 0.25)
		(keepout
			(tracks not_allowed)
			(vias allowed)
			(pads allowed)
			(copperpour not_allowed)
			(footprints allowed)
		)
		(placement
			(enabled no)
			(sheetname "")
		)
		(fill yes
			(thermal_gap 0.5)
			(thermal_bridge_width 0.5)
			(island_removal_mode 0)
		)
		(polygon
			(pts
				(arc
					(start 49.209198 -272.321528)
					(mid 49.224077 -272.357449)
					(end 49.259998 -272.372328)
				)
				(arc
					(start 50.659538 -272.372328)
					(mid 50.695459 -272.357449)
					(end 50.710338 -272.321528)
				)
				(arc
					(start 50.710338 -271.912588)
					(mid 50.695459 -271.876667)
					(end 50.659538 -271.861788)
				)
				(arc
					(start 49.259998 -271.861788)
					(mid 49.224077 -271.876667)
					(end 49.209198 -271.912588)
				)
			)
		)
	)
	(zone
		(layers "In1.Cu" "In2.Cu")
		(hatch none 0.5)
		(connect_pads
			(clearance 0)
		)
		(min_thickness 0.25)
		(keepout
			(tracks not_allowed)
			(vias allowed)
			(pads allowed)
			(copperpour not_allowed)
			(footprints allowed)
		)
		(placement
			(enabled no)
			(sheetname "")
		)
		(fill yes
			(thermal_gap 0.5)
			(thermal_bridge_width 0.5)
			(island_removal_mode 0)
		)
		(polygon
			(pts
				(arc
					(start 192.338198 -302.071532)
					(mid 192.353077 -302.107453)
					(end 192.388998 -302.122332)
				)
				(arc
					(start 193.788538 -302.122332)
					(mid 193.824459 -302.107453)
					(end 193.839338 -302.071532)
				)
				(arc
					(start 193.839338 -301.662592)
					(mid 193.824459 -301.626671)
					(end 193.788538 -301.611792)
				)
				(arc
					(start 192.388998 -301.611792)
					(mid 192.353077 -301.626671)
					(end 192.338198 -301.662592)
				)
			)
		)
	)
	(zone
		(layers "In1.Cu" "In2.Cu")
		(hatch none 0.5)
		(connect_pads
			(clearance 0)
		)
		(min_thickness 0.25)
		(keepout
			(tracks not_allowed)
			(vias allowed)
			(pads allowed)
			(copperpour not_allowed)
			(footprints allowed)
		)
		(placement
			(enabled no)
			(sheetname "")
		)
		(fill yes
			(thermal_gap 0.5)
			(thermal_bridge_width 0.5)
			(island_removal_mode 0)
		)
		(polygon
			(pts
				(arc
					(start 262.873998 -234.071414)
					(mid 262.888877 -234.107335)
					(end 262.924798 -234.122214)
				)
				(arc
					(start 264.324338 -234.122214)
					(mid 264.360259 -234.107335)
					(end 264.375138 -234.071414)
				)
				(arc
					(start 264.375138 -233.662474)
					(mid 264.360259 -233.626553)
					(end 264.324338 -233.611674)
				)
				(arc
					(start 262.924798 -233.611674)
					(mid 262.888877 -233.626553)
					(end 262.873998 -233.662474)
				)
			)
		)
	)
	(zone
		(layers "In1.Cu" "In2.Cu")
		(hatch none 0.5)
		(connect_pads
			(clearance 0)
		)
		(min_thickness 0.25)
		(keepout
			(tracks not_allowed)
			(vias allowed)
			(pads allowed)
			(copperpour not_allowed)
			(footprints allowed)
		)
		(placement
			(enabled no)
			(sheetname "")
		)
		(fill yes
			(thermal_gap 0.5)
			(thermal_bridge_width 0.5)
			(island_removal_mode 0)
		)
		(polygon
			(pts
				(arc
					(start 37.56533 -219.621354)
					(mid 37.580209 -219.657275)
					(end 37.61613 -219.672154)
				)
				(arc
					(start 39.01567 -219.672154)
					(mid 39.051591 -219.657275)
					(end 39.06647 -219.621354)
				)
				(arc
					(start 39.06647 -219.212414)
					(mid 39.051591 -219.176493)
					(end 39.01567 -219.161614)
				)
				(arc
					(start 37.61613 -219.161614)
					(mid 37.580209 -219.176493)
					(end 37.56533 -219.212414)
				)
			)
		)
	)
	(zone
		(layers "In1.Cu" "In2.Cu")
		(hatch none 0.5)
		(connect_pads
			(clearance 0)
		)
		(min_thickness 0.25)
		(keepout
			(tracks not_allowed)
			(vias allowed)
			(pads allowed)
			(copperpour not_allowed)
			(footprints allowed)
		)
		(placement
			(enabled no)
			(sheetname "")
		)
		(fill yes
			(thermal_gap 0.5)
			(thermal_bridge_width 0.5)
			(island_removal_mode 0)
		)
		(polygon
			(pts
				(arc
					(start 277.961598 -196.671438)
					(mid 277.976477 -196.707359)
					(end 278.012398 -196.722238)
				)
				(arc
					(start 279.411938 -196.722238)
					(mid 279.447859 -196.707359)
					(end 279.462738 -196.671438)
				)
				(arc
					(start 279.462738 -196.262498)
					(mid 279.447859 -196.226577)
					(end 279.411938 -196.211698)
				)
				(arc
					(start 278.012398 -196.211698)
					(mid 277.976477 -196.226577)
					(end 277.961598 -196.262498)
				)
			)
		)
	)
	(zone
		(layers "In1.Cu" "In2.Cu")
		(hatch none 0.5)
		(connect_pads
			(clearance 0)
		)
		(min_thickness 0.25)
		(keepout
			(tracks not_allowed)
			(vias allowed)
			(pads allowed)
			(copperpour not_allowed)
			(footprints allowed)
		)
		(placement
			(enabled no)
			(sheetname "")
		)
		(fill yes
			(thermal_gap 0.5)
			(thermal_bridge_width 0.5)
			(island_removal_mode 0)
		)
		(polygon
			(pts
				(arc
					(start 158.06293 -211.971382)
					(mid 158.077809 -212.007303)
					(end 158.11373 -212.022182)
				)
				(arc
					(start 159.51327 -212.022182)
					(mid 159.549191 -212.007303)
					(end 159.56407 -211.971382)
				)
				(arc
					(start 159.56407 -211.562442)
					(mid 159.549191 -211.526521)
					(end 159.51327 -211.511642)
				)
				(arc
					(start 158.11373 -211.511642)
					(mid 158.077809 -211.526521)
					(end 158.06293 -211.562442)
				)
			)
		)
	)
	(zone
		(layers "In1.Cu" "In2.Cu")
		(hatch none 0.5)
		(connect_pads
			(clearance 0)
		)
		(min_thickness 0.25)
		(keepout
			(tracks not_allowed)
			(vias allowed)
			(pads allowed)
			(copperpour not_allowed)
			(footprints allowed)
		)
		(placement
			(enabled no)
			(sheetname "")
		)
		(fill yes
			(thermal_gap 0.5)
			(thermal_bridge_width 0.5)
			(island_removal_mode 0)
		)
		(polygon
			(pts
				(arc
					(start 289.605466 -197.521322)
					(mid 289.620345 -197.557243)
					(end 289.656266 -197.572122)
				)
				(arc
					(start 291.055806 -197.572122)
					(mid 291.091727 -197.557243)
					(end 291.106606 -197.521322)
				)
				(arc
					(start 291.106606 -197.112382)
					(mid 291.091727 -197.076461)
					(end 291.055806 -197.061582)
				)
				(arc
					(start 289.656266 -197.061582)
					(mid 289.620345 -197.076461)
					(end 289.605466 -197.112382)
				)
			)
		)
	)
	(zone
		(layers "In1.Cu" "In2.Cu")
		(hatch none 0.5)
		(connect_pads
			(clearance 0)
		)
		(min_thickness 0.25)
		(keepout
			(tracks not_allowed)
			(vias allowed)
			(pads allowed)
			(copperpour not_allowed)
			(footprints allowed)
		)
		(placement
			(enabled no)
			(sheetname "")
		)
		(fill yes
			(thermal_gap 0.5)
			(thermal_bridge_width 0.5)
			(island_removal_mode 0)
		)
		(polygon
			(pts
				(arc
					(start 195.78193 -226.421442)
					(mid 195.796809 -226.457363)
					(end 195.83273 -226.472242)
				)
				(arc
					(start 197.23227 -226.472242)
					(mid 197.268191 -226.457363)
					(end 197.28307 -226.421442)
				)
				(arc
					(start 197.28307 -226.012502)
					(mid 197.268191 -225.976581)
					(end 197.23227 -225.961702)
				)
				(arc
					(start 195.83273 -225.961702)
					(mid 195.796809 -225.976581)
					(end 195.78193 -226.012502)
				)
			)
		)
	)
	(zone
		(layers "In1.Cu" "In2.Cu")
		(hatch none 0.5)
		(connect_pads
			(clearance 0)
		)
		(min_thickness 0.25)
		(keepout
			(tracks not_allowed)
			(vias allowed)
			(pads allowed)
			(copperpour not_allowed)
			(footprints allowed)
		)
		(placement
			(enabled no)
			(sheetname "")
		)
		(fill yes
			(thermal_gap 0.5)
			(thermal_bridge_width 0.5)
			(island_removal_mode 0)
		)
		(polygon
			(pts
				(arc
					(start 64.296798 -298.671488)
					(mid 64.311677 -298.707409)
					(end 64.347598 -298.722288)
				)
				(arc
					(start 65.747138 -298.722288)
					(mid 65.783059 -298.707409)
					(end 65.797938 -298.671488)
				)
				(arc
					(start 65.797938 -298.262548)
					(mid 65.783059 -298.226627)
					(end 65.747138 -298.211748)
				)
				(arc
					(start 64.347598 -298.211748)
					(mid 64.311677 -298.226627)
					(end 64.296798 -298.262548)
				)
			)
		)
	)
	(zone
		(layers "In1.Cu" "In2.Cu")
		(hatch none 0.5)
		(connect_pads
			(clearance 0)
		)
		(min_thickness 0.25)
		(keepout
			(tracks not_allowed)
			(vias allowed)
			(pads allowed)
			(copperpour not_allowed)
			(footprints allowed)
		)
		(placement
			(enabled no)
			(sheetname "")
		)
		(fill yes
			(thermal_gap 0.5)
			(thermal_bridge_width 0.5)
			(island_removal_mode 0)
		)
		(polygon
			(pts
				(arc
					(start 440.278266 -263.821418)
					(mid 440.293145 -263.857339)
					(end 440.329066 -263.872218)
				)
				(arc
					(start 441.728606 -263.872218)
					(mid 441.764527 -263.857339)
					(end 441.779406 -263.821418)
				)
				(arc
					(start 441.779406 -263.412478)
					(mid 441.764527 -263.376557)
					(end 441.728606 -263.361678)
				)
				(arc
					(start 440.329066 -263.361678)
					(mid 440.293145 -263.376557)
					(end 440.278266 -263.412478)
				)
			)
		)
	)
	(zone
		(layers "In1.Cu" "In2.Cu")
		(hatch none 0.5)
		(connect_pads
			(clearance 0)
		)
		(min_thickness 0.25)
		(keepout
			(tracks not_allowed)
			(vias allowed)
			(pads allowed)
			(copperpour not_allowed)
			(footprints allowed)
		)
		(placement
			(enabled no)
			(sheetname "")
		)
		(fill yes
			(thermal_gap 0.5)
			(thermal_bridge_width 0.5)
			(island_removal_mode 0)
		)
		(polygon
			(pts
				(arc
					(start 26.577798 -292.721538)
					(mid 26.592677 -292.757459)
					(end 26.628598 -292.772338)
				)
				(arc
					(start 28.028138 -292.772338)
					(mid 28.064059 -292.757459)
					(end 28.078938 -292.721538)
				)
				(arc
					(start 28.078938 -292.312598)
					(mid 28.064059 -292.276677)
					(end 28.028138 -292.261798)
				)
				(arc
					(start 26.628598 -292.261798)
					(mid 26.592677 -292.276677)
					(end 26.577798 -292.312598)
				)
			)
		)
	)
	(zone
		(layers "In1.Cu" "In2.Cu")
		(hatch none 0.5)
		(connect_pads
			(clearance 0)
		)
		(min_thickness 0.25)
		(keepout
			(tracks not_allowed)
			(vias allowed)
			(pads allowed)
			(copperpour not_allowed)
			(footprints allowed)
		)
		(placement
			(enabled no)
			(sheetname "")
		)
		(fill yes
			(thermal_gap 0.5)
			(thermal_bridge_width 0.5)
			(island_removal_mode 0)
		)
		(polygon
			(pts
				(arc
					(start 22.47773 -226.421442)
					(mid 22.492609 -226.457363)
					(end 22.52853 -226.472242)
				)
				(arc
					(start 23.92807 -226.472242)
					(mid 23.963991 -226.457363)
					(end 23.97887 -226.421442)
				)
				(arc
					(start 23.97887 -226.012502)
					(mid 23.963991 -225.976581)
					(end 23.92807 -225.961702)
				)
				(arc
					(start 22.52853 -225.961702)
					(mid 22.492609 -225.976581)
					(end 22.47773 -226.012502)
				)
			)
		)
	)
	(zone
		(layers "In1.Cu" "In2.Cu")
		(hatch none 0.5)
		(connect_pads
			(clearance 0)
		)
		(min_thickness 0.25)
		(keepout
			(tracks not_allowed)
			(vias allowed)
			(pads allowed)
			(copperpour not_allowed)
			(footprints allowed)
		)
		(placement
			(enabled no)
			(sheetname "")
		)
		(fill yes
			(thermal_gap 0.5)
			(thermal_bridge_width 0.5)
			(island_removal_mode 0)
		)
		(polygon
			(pts
				(arc
					(start 436.178198 -219.621354)
					(mid 436.193077 -219.657275)
					(end 436.228998 -219.672154)
				)
				(arc
					(start 437.628538 -219.672154)
					(mid 437.664459 -219.657275)
					(end 437.679338 -219.621354)
				)
				(arc
					(start 437.679338 -219.212414)
					(mid 437.664459 -219.176493)
					(end 437.628538 -219.161614)
				)
				(arc
					(start 436.228998 -219.161614)
					(mid 436.193077 -219.176493)
					(end 436.178198 -219.212414)
				)
			)
		)
	)
	(zone
		(layers "In1.Cu" "In2.Cu")
		(hatch none 0.5)
		(connect_pads
			(clearance 0)
		)
		(min_thickness 0.25)
		(keepout
			(tracks not_allowed)
			(vias allowed)
			(pads allowed)
			(copperpour not_allowed)
			(footprints allowed)
		)
		(placement
			(enabled no)
			(sheetname "")
		)
		(fill yes
			(thermal_gap 0.5)
			(thermal_bridge_width 0.5)
			(island_removal_mode 0)
		)
		(polygon
			(pts
				(arc
					(start 60.19673 -244.271292)
					(mid 60.211609 -244.307213)
					(end 60.24753 -244.322092)
				)
				(arc
					(start 61.64707 -244.322092)
					(mid 61.682991 -244.307213)
					(end 61.69787 -244.271292)
				)
				(arc
					(start 61.69787 -243.862352)
					(mid 61.682991 -243.826431)
					(end 61.64707 -243.811552)
				)
				(arc
					(start 60.24753 -243.811552)
					(mid 60.211609 -243.826431)
					(end 60.19673 -243.862352)
				)
			)
		)
	)
	(zone
		(layers "In1.Cu" "In2.Cu")
		(hatch none 0.5)
		(connect_pads
			(clearance 0)
		)
		(min_thickness 0.25)
		(keepout
			(tracks not_allowed)
			(vias allowed)
			(pads allowed)
			(copperpour not_allowed)
			(footprints allowed)
		)
		(placement
			(enabled no)
			(sheetname "")
		)
		(fill yes
			(thermal_gap 0.5)
			(thermal_bridge_width 0.5)
			(island_removal_mode 0)
		)
		(polygon
			(pts
				(arc
					(start 165.60673 -269.771368)
					(mid 165.621609 -269.807289)
					(end 165.65753 -269.822168)
				)
				(arc
					(start 167.05707 -269.822168)
					(mid 167.092991 -269.807289)
					(end 167.10787 -269.771368)
				)
				(arc
					(start 167.10787 -269.362428)
					(mid 167.092991 -269.326507)
					(end 167.05707 -269.311628)
				)
				(arc
					(start 165.65753 -269.311628)
					(mid 165.621609 -269.326507)
					(end 165.60673 -269.362428)
				)
			)
		)
	)
	(zone
		(layers "In1.Cu" "In2.Cu")
		(hatch none 0.5)
		(connect_pads
			(clearance 0)
		)
		(min_thickness 0.25)
		(keepout
			(tracks not_allowed)
			(vias allowed)
			(pads allowed)
			(copperpour not_allowed)
			(footprints allowed)
		)
		(placement
			(enabled no)
			(sheetname "")
		)
		(fill yes
			(thermal_gap 0.5)
			(thermal_bridge_width 0.5)
			(island_removal_mode 0)
		)
		(polygon
			(pts
				(arc
					(start 406.002998 -316.521338)
					(mid 406.017877 -316.557259)
					(end 406.053798 -316.572138)
				)
				(arc
					(start 407.453338 -316.572138)
					(mid 407.489259 -316.557259)
					(end 407.504138 -316.521338)
				)
				(arc
					(start 407.504138 -316.112398)
					(mid 407.489259 -316.076477)
					(end 407.453338 -316.061598)
				)
				(arc
					(start 406.053798 -316.061598)
					(mid 406.017877 -316.076477)
					(end 406.002998 -316.112398)
				)
			)
		)
	)
	(zone
		(layers "In1.Cu" "In2.Cu")
		(hatch none 0.5)
		(connect_pads
			(clearance 0)
		)
		(min_thickness 0.25)
		(keepout
			(tracks not_allowed)
			(vias allowed)
			(pads allowed)
			(copperpour not_allowed)
			(footprints allowed)
		)
		(placement
			(enabled no)
			(sheetname "")
		)
		(fill yes
			(thermal_gap 0.5)
			(thermal_bridge_width 0.5)
			(island_removal_mode 0)
		)
		(polygon
			(pts
				(arc
					(start 443.721998 -252.771402)
					(mid 443.736877 -252.807323)
					(end 443.772798 -252.822202)
				)
				(arc
					(start 445.172338 -252.822202)
					(mid 445.208259 -252.807323)
					(end 445.223138 -252.771402)
				)
				(arc
					(start 445.223138 -252.362462)
					(mid 445.208259 -252.326541)
					(end 445.172338 -252.311662)
				)
				(arc
					(start 443.772798 -252.311662)
					(mid 443.736877 -252.326541)
					(end 443.721998 -252.362462)
				)
			)
		)
	)
	(zone
		(layers "In1.Cu" "In2.Cu")
		(hatch none 0.5)
		(connect_pads
			(clearance 0)
		)
		(min_thickness 0.25)
		(keepout
			(tracks not_allowed)
			(vias allowed)
			(pads allowed)
			(copperpour not_allowed)
			(footprints allowed)
		)
		(placement
			(enabled no)
			(sheetname "")
		)
		(fill yes
			(thermal_gap 0.5)
			(thermal_bridge_width 0.5)
			(island_removal_mode 0)
		)
		(polygon
			(pts
				(arc
					(start 312.236866 -289.321494)
					(mid 312.251745 -289.357415)
					(end 312.287666 -289.372294)
				)
				(arc
					(start 313.687206 -289.372294)
					(mid 313.723127 -289.357415)
					(end 313.738006 -289.321494)
				)
				(arc
					(start 313.738006 -288.912554)
					(mid 313.723127 -288.876633)
					(end 313.687206 -288.861754)
				)
				(arc
					(start 312.287666 -288.861754)
					(mid 312.251745 -288.876633)
					(end 312.236866 -288.912554)
				)
			)
		)
	)
	(zone
		(layers "In1.Cu" "In2.Cu")
		(hatch none 0.5)
		(connect_pads
			(clearance 0)
		)
		(min_thickness 0.25)
		(keepout
			(tracks not_allowed)
			(vias allowed)
			(pads allowed)
			(copperpour not_allowed)
			(footprints allowed)
		)
		(placement
			(enabled no)
			(sheetname "")
		)
		(fill yes
			(thermal_gap 0.5)
			(thermal_bridge_width 0.5)
			(island_removal_mode 0)
		)
		(polygon
			(pts
				(arc
					(start 34.121598 -239.17148)
					(mid 34.136477 -239.207401)
					(end 34.172398 -239.22228)
				)
				(arc
					(start 35.571938 -239.22228)
					(mid 35.607859 -239.207401)
					(end 35.622738 -239.17148)
				)
				(arc
					(start 35.622738 -238.76254)
					(mid 35.607859 -238.726619)
					(end 35.571938 -238.71174)
				)
				(arc
					(start 34.172398 -238.71174)
					(mid 34.136477 -238.726619)
					(end 34.121598 -238.76254)
				)
			)
		)
	)
	(zone
		(layers "In1.Cu" "In2.Cu")
		(hatch none 0.5)
		(connect_pads
			(clearance 0)
		)
		(min_thickness 0.25)
		(keepout
			(tracks not_allowed)
			(vias allowed)
			(pads allowed)
			(copperpour not_allowed)
			(footprints allowed)
		)
		(placement
			(enabled no)
			(sheetname "")
		)
		(fill yes
			(thermal_gap 0.5)
			(thermal_bridge_width 0.5)
			(island_removal_mode 0)
		)
		(polygon
			(pts
				(arc
					(start 34.121598 -248.521474)
					(mid 34.136477 -248.557395)
					(end 34.172398 -248.572274)
				)
				(arc
					(start 35.571938 -248.572274)
					(mid 35.607859 -248.557395)
					(end 35.622738 -248.521474)
				)
				(arc
					(start 35.622738 -248.112534)
					(mid 35.607859 -248.076613)
					(end 35.571938 -248.061734)
				)
				(arc
					(start 34.172398 -248.061734)
					(mid 34.136477 -248.076613)
					(end 34.121598 -248.112534)
				)
			)
		)
	)
	(zone
		(layers "In1.Cu" "In2.Cu")
		(hatch none 0.5)
		(connect_pads
			(clearance 0)
		)
		(min_thickness 0.25)
		(keepout
			(tracks not_allowed)
			(vias allowed)
			(pads allowed)
			(copperpour not_allowed)
			(footprints allowed)
		)
		(placement
			(enabled no)
			(sheetname "")
		)
		(fill yes
			(thermal_gap 0.5)
			(thermal_bridge_width 0.5)
			(island_removal_mode 0)
		)
		(polygon
			(pts
				(arc
					(start 455.365866 -233.22153)
					(mid 455.380745 -233.257451)
					(end 455.416666 -233.27233)
				)
				(arc
					(start 456.816206 -233.27233)
					(mid 456.852127 -233.257451)
					(end 456.867006 -233.22153)
				)
				(arc
					(start 456.867006 -232.81259)
					(mid 456.852127 -232.776669)
					(end 456.816206 -232.76179)
				)
				(arc
					(start 455.416666 -232.76179)
					(mid 455.380745 -232.776669)
					(end 455.365866 -232.81259)
				)
			)
		)
	)
	(zone
		(layers "In1.Cu" "In2.Cu")
		(hatch none 0.5)
		(connect_pads
			(clearance 0)
		)
		(min_thickness 0.25)
		(keepout
			(tracks not_allowed)
			(vias allowed)
			(pads allowed)
			(copperpour not_allowed)
			(footprints allowed)
		)
		(placement
			(enabled no)
			(sheetname "")
		)
		(fill yes
			(thermal_gap 0.5)
			(thermal_bridge_width 0.5)
			(island_removal_mode 0)
		)
		(polygon
			(pts
				(arc
					(start 277.961598 -207.721454)
					(mid 277.976477 -207.757375)
					(end 278.012398 -207.772254)
				)
				(arc
					(start 279.411938 -207.772254)
					(mid 279.447859 -207.757375)
					(end 279.462738 -207.721454)
				)
				(arc
					(start 279.462738 -207.312514)
					(mid 279.447859 -207.276593)
					(end 279.411938 -207.261714)
				)
				(arc
					(start 278.012398 -207.261714)
					(mid 277.976477 -207.276593)
					(end 277.961598 -207.312514)
				)
			)
		)
	)
	(zone
		(layers "In1.Cu" "In2.Cu")
		(hatch none 0.5)
		(connect_pads
			(clearance 0)
		)
		(min_thickness 0.25)
		(keepout
			(tracks not_allowed)
			(vias allowed)
			(pads allowed)
			(copperpour not_allowed)
			(footprints allowed)
		)
		(placement
			(enabled no)
			(sheetname "")
		)
		(fill yes
			(thermal_gap 0.5)
			(thermal_bridge_width 0.5)
			(island_removal_mode 0)
		)
		(polygon
			(pts
				(arc
					(start 255.330198 -313.121294)
					(mid 255.345077 -313.157215)
					(end 255.380998 -313.172094)
				)
				(arc
					(start 256.780538 -313.172094)
					(mid 256.816459 -313.157215)
					(end 256.831338 -313.121294)
				)
				(arc
					(start 256.831338 -312.712354)
					(mid 256.816459 -312.676433)
					(end 256.780538 -312.661554)
				)
				(arc
					(start 255.380998 -312.661554)
					(mid 255.345077 -312.676433)
					(end 255.330198 -312.712354)
				)
			)
		)
	)
	(zone
		(layers "In1.Cu" "In2.Cu")
		(hatch none 0.5)
		(connect_pads
			(clearance 0)
		)
		(min_thickness 0.25)
		(keepout
			(tracks not_allowed)
			(vias allowed)
			(pads allowed)
			(copperpour not_allowed)
			(footprints allowed)
		)
		(placement
			(enabled no)
			(sheetname "")
		)
		(fill yes
			(thermal_gap 0.5)
			(thermal_bridge_width 0.5)
			(island_removal_mode 0)
		)
		(polygon
			(pts
				(arc
					(start 41.665398 -296.971466)
					(mid 41.680277 -297.007387)
					(end 41.716198 -297.022266)
				)
				(arc
					(start 43.115738 -297.022266)
					(mid 43.151659 -297.007387)
					(end 43.166538 -296.971466)
				)
				(arc
					(start 43.166538 -296.562526)
					(mid 43.151659 -296.526605)
					(end 43.115738 -296.511726)
				)
				(arc
					(start 41.716198 -296.511726)
					(mid 41.680277 -296.526605)
					(end 41.665398 -296.562526)
				)
			)
		)
	)
	(zone
		(layers "In1.Cu" "In2.Cu")
		(hatch none 0.5)
		(connect_pads
			(clearance 0)
		)
		(min_thickness 0.25)
		(keepout
			(tracks not_allowed)
			(vias allowed)
			(pads allowed)
			(copperpour not_allowed)
			(footprints allowed)
		)
		(placement
			(enabled no)
			(sheetname "")
		)
		(fill yes
			(thermal_gap 0.5)
			(thermal_bridge_width 0.5)
			(island_removal_mode 0)
		)
		(polygon
			(pts
				(arc
					(start 162.162998 -237.471458)
					(mid 162.177877 -237.507379)
					(end 162.213798 -237.522258)
				)
				(arc
					(start 163.613338 -237.522258)
					(mid 163.649259 -237.507379)
					(end 163.664138 -237.471458)
				)
				(arc
					(start 163.664138 -237.062518)
					(mid 163.649259 -237.026597)
					(end 163.613338 -237.011718)
				)
				(arc
					(start 162.213798 -237.011718)
					(mid 162.177877 -237.026597)
					(end 162.162998 -237.062518)
				)
			)
		)
	)
	(zone
		(layers "In1.Cu" "In2.Cu")
		(hatch none 0.5)
		(connect_pads
			(clearance 0)
		)
		(min_thickness 0.25)
		(keepout
			(tracks not_allowed)
			(vias allowed)
			(pads allowed)
			(copperpour not_allowed)
			(footprints allowed)
		)
		(placement
			(enabled no)
			(sheetname "")
		)
		(fill yes
			(thermal_gap 0.5)
			(thermal_bridge_width 0.5)
			(island_removal_mode 0)
		)
		(polygon
			(pts
				(arc
					(start 14.93393 -223.021398)
					(mid 14.948809 -223.057319)
					(end 14.98473 -223.072198)
				)
				(arc
					(start 16.38427 -223.072198)
					(mid 16.420191 -223.057319)
					(end 16.43507 -223.021398)
				)
				(arc
					(start 16.43507 -222.612458)
					(mid 16.420191 -222.576537)
					(end 16.38427 -222.561658)
				)
				(arc
					(start 14.98473 -222.561658)
					(mid 14.948809 -222.576537)
					(end 14.93393 -222.612458)
				)
			)
		)
	)
	(zone
		(layers "In1.Cu" "In2.Cu")
		(hatch none 0.5)
		(connect_pads
			(clearance 0)
		)
		(min_thickness 0.25)
		(keepout
			(tracks not_allowed)
			(vias allowed)
			(pads allowed)
			(copperpour not_allowed)
			(footprints allowed)
		)
		(placement
			(enabled no)
			(sheetname "")
		)
		(fill yes
			(thermal_gap 0.5)
			(thermal_bridge_width 0.5)
			(island_removal_mode 0)
		)
		(polygon
			(pts
				(arc
					(start 312.236866 -279.9715)
					(mid 312.251745 -280.007421)
					(end 312.287666 -280.0223)
				)
				(arc
					(start 313.687206 -280.0223)
					(mid 313.723127 -280.007421)
					(end 313.738006 -279.9715)
				)
				(arc
					(start 313.738006 -279.56256)
					(mid 313.723127 -279.526639)
					(end 313.687206 -279.51176)
				)
				(arc
					(start 312.287666 -279.51176)
					(mid 312.251745 -279.526639)
					(end 312.236866 -279.56256)
				)
			)
		)
	)
	(zone
		(layers "In1.Cu" "In2.Cu")
		(hatch none 0.5)
		(connect_pads
			(clearance 0)
		)
		(min_thickness 0.25)
		(keepout
			(tracks not_allowed)
			(vias allowed)
			(pads allowed)
			(copperpour not_allowed)
			(footprints allowed)
		)
		(placement
			(enabled no)
			(sheetname "")
		)
		(fill yes
			(thermal_gap 0.5)
			(thermal_bridge_width 0.5)
			(island_removal_mode 0)
		)
		(polygon
			(pts
				(arc
					(start 210.86953 -285.071312)
					(mid 210.884409 -285.107233)
					(end 210.92033 -285.122112)
				)
				(arc
					(start 212.31987 -285.122112)
					(mid 212.355791 -285.107233)
					(end 212.37067 -285.071312)
				)
				(arc
					(start 212.37067 -284.662372)
					(mid 212.355791 -284.626451)
					(end 212.31987 -284.611572)
				)
				(arc
					(start 210.92033 -284.611572)
					(mid 210.884409 -284.626451)
					(end 210.86953 -284.662372)
				)
			)
		)
	)
	(zone
		(layers "In1.Cu" "In2.Cu")
		(hatch none 0.5)
		(connect_pads
			(clearance 0)
		)
		(min_thickness 0.25)
		(keepout
			(tracks not_allowed)
			(vias allowed)
			(pads allowed)
			(copperpour not_allowed)
			(footprints allowed)
		)
		(placement
			(enabled no)
			(sheetname "")
		)
		(fill yes
			(thermal_gap 0.5)
			(thermal_bridge_width 0.5)
			(island_removal_mode 0)
		)
		(polygon
			(pts
				(arc
					(start 64.296798 -250.221496)
					(mid 64.311677 -250.257417)
					(end 64.347598 -250.272296)
				)
				(arc
					(start 65.747138 -250.272296)
					(mid 65.783059 -250.257417)
					(end 65.797938 -250.221496)
				)
				(arc
					(start 65.797938 -249.812556)
					(mid 65.783059 -249.776635)
					(end 65.747138 -249.761756)
				)
				(arc
					(start 64.347598 -249.761756)
					(mid 64.311677 -249.776635)
					(end 64.296798 -249.812556)
				)
			)
		)
	)
	(zone
		(layers "In1.Cu" "In2.Cu")
		(hatch none 0.5)
		(connect_pads
			(clearance 0)
		)
		(min_thickness 0.25)
		(keepout
			(tracks not_allowed)
			(vias allowed)
			(pads allowed)
			(copperpour not_allowed)
			(footprints allowed)
		)
		(placement
			(enabled no)
			(sheetname "")
		)
		(fill yes
			(thermal_gap 0.5)
			(thermal_bridge_width 0.5)
			(island_removal_mode 0)
		)
		(polygon
			(pts
				(arc
					(start 259.430266 -265.52144)
					(mid 259.445145 -265.557361)
					(end 259.481066 -265.57224)
				)
				(arc
					(start 260.880606 -265.57224)
					(mid 260.916527 -265.557361)
					(end 260.931406 -265.52144)
				)
				(arc
					(start 260.931406 -265.1125)
					(mid 260.916527 -265.076579)
					(end 260.880606 -265.0617)
				)
				(arc
					(start 259.481066 -265.0617)
					(mid 259.445145 -265.076579)
					(end 259.430266 -265.1125)
				)
			)
		)
	)
	(zone
		(layers "In1.Cu" "In2.Cu")
		(hatch none 0.5)
		(connect_pads
			(clearance 0)
		)
		(min_thickness 0.25)
		(keepout
			(tracks not_allowed)
			(vias allowed)
			(pads allowed)
			(copperpour not_allowed)
			(footprints allowed)
		)
		(placement
			(enabled no)
			(sheetname "")
		)
		(fill yes
			(thermal_gap 0.5)
			(thermal_bridge_width 0.5)
			(island_removal_mode 0)
		)
		(polygon
			(pts
				(arc
					(start 37.56533 -305.471322)
					(mid 37.580209 -305.507243)
					(end 37.61613 -305.522122)
				)
				(arc
					(start 39.01567 -305.522122)
					(mid 39.051591 -305.507243)
					(end 39.06647 -305.471322)
				)
				(arc
					(start 39.06647 -305.062382)
					(mid 39.051591 -305.026461)
					(end 39.01567 -305.011582)
				)
				(arc
					(start 37.61613 -305.011582)
					(mid 37.580209 -305.026461)
					(end 37.56533 -305.062382)
				)
			)
		)
	)
	(zone
		(layers "In1.Cu" "In2.Cu")
		(hatch none 0.5)
		(connect_pads
			(clearance 0)
		)
		(min_thickness 0.25)
		(keepout
			(tracks not_allowed)
			(vias allowed)
			(pads allowed)
			(copperpour not_allowed)
			(footprints allowed)
		)
		(placement
			(enabled no)
			(sheetname "")
		)
		(fill yes
			(thermal_gap 0.5)
			(thermal_bridge_width 0.5)
			(island_removal_mode 0)
		)
		(polygon
			(pts
				(arc
					(start 297.149266 -229.821486)
					(mid 297.164145 -229.857407)
					(end 297.200066 -229.872286)
				)
				(arc
					(start 298.599606 -229.872286)
					(mid 298.635527 -229.857407)
					(end 298.650406 -229.821486)
				)
				(arc
					(start 298.650406 -229.412546)
					(mid 298.635527 -229.376625)
					(end 298.599606 -229.361746)
				)
				(arc
					(start 297.200066 -229.361746)
					(mid 297.164145 -229.376625)
					(end 297.149266 -229.412546)
				)
			)
		)
	)
	(zone
		(layers "In1.Cu" "In2.Cu")
		(hatch none 0.5)
		(connect_pads
			(clearance 0)
		)
		(min_thickness 0.25)
		(keepout
			(tracks not_allowed)
			(vias allowed)
			(pads allowed)
			(copperpour not_allowed)
			(footprints allowed)
		)
		(placement
			(enabled no)
			(sheetname "")
		)
		(fill yes
			(thermal_gap 0.5)
			(thermal_bridge_width 0.5)
			(island_removal_mode 0)
		)
		(polygon
			(pts
				(arc
					(start 462.909666 -263.821418)
					(mid 462.924545 -263.857339)
					(end 462.960466 -263.872218)
				)
				(arc
					(start 464.360006 -263.872218)
					(mid 464.395927 -263.857339)
					(end 464.410806 -263.821418)
				)
				(arc
					(start 464.410806 -263.412478)
					(mid 464.395927 -263.376557)
					(end 464.360006 -263.361678)
				)
				(arc
					(start 462.960466 -263.361678)
					(mid 462.924545 -263.376557)
					(end 462.909666 -263.412478)
				)
			)
		)
	)
	(zone
		(layers "In1.Cu" "In2.Cu")
		(hatch none 0.5)
		(connect_pads
			(clearance 0)
		)
		(min_thickness 0.25)
		(keepout
			(tracks not_allowed)
			(vias allowed)
			(pads allowed)
			(copperpour not_allowed)
			(footprints allowed)
		)
		(placement
			(enabled no)
			(sheetname "")
		)
		(fill yes
			(thermal_gap 0.5)
			(thermal_bridge_width 0.5)
			(island_removal_mode 0)
		)
		(polygon
			(pts
				(arc
					(start 413.546798 -200.071482)
					(mid 413.561677 -200.107403)
					(end 413.597598 -200.122282)
				)
				(arc
					(start 414.997138 -200.122282)
					(mid 415.033059 -200.107403)
					(end 415.047938 -200.071482)
				)
				(arc
					(start 415.047938 -199.662542)
					(mid 415.033059 -199.626621)
					(end 414.997138 -199.611742)
				)
				(arc
					(start 413.597598 -199.611742)
					(mid 413.561677 -199.626621)
					(end 413.546798 -199.662542)
				)
			)
		)
	)
	(zone
		(layers "In1.Cu" "In2.Cu")
		(hatch none 0.5)
		(connect_pads
			(clearance 0)
		)
		(min_thickness 0.25)
		(keepout
			(tracks not_allowed)
			(vias allowed)
			(pads allowed)
			(copperpour not_allowed)
			(footprints allowed)
		)
		(placement
			(enabled no)
			(sheetname "")
		)
		(fill yes
			(thermal_gap 0.5)
			(thermal_bridge_width 0.5)
			(island_removal_mode 0)
		)
		(polygon
			(pts
				(arc
					(start 56.752998 -248.521474)
					(mid 56.767877 -248.557395)
					(end 56.803798 -248.572274)
				)
				(arc
					(start 58.203338 -248.572274)
					(mid 58.239259 -248.557395)
					(end 58.254138 -248.521474)
				)
				(arc
					(start 58.254138 -248.112534)
					(mid 58.239259 -248.076613)
					(end 58.203338 -248.061734)
				)
				(arc
					(start 56.803798 -248.061734)
					(mid 56.767877 -248.076613)
					(end 56.752998 -248.112534)
				)
			)
		)
	)
	(zone
		(layers "In1.Cu" "In2.Cu")
		(hatch none 0.5)
		(connect_pads
			(clearance 0)
		)
		(min_thickness 0.25)
		(keepout
			(tracks not_allowed)
			(vias allowed)
			(pads allowed)
			(copperpour not_allowed)
			(footprints allowed)
		)
		(placement
			(enabled no)
			(sheetname "")
		)
		(fill yes
			(thermal_gap 0.5)
			(thermal_bridge_width 0.5)
			(island_removal_mode 0)
		)
		(polygon
			(pts
				(arc
					(start 293.049198 -243.421408)
					(mid 293.064077 -243.457329)
					(end 293.099998 -243.472208)
				)
				(arc
					(start 294.499538 -243.472208)
					(mid 294.535459 -243.457329)
					(end 294.550338 -243.421408)
				)
				(arc
					(start 294.550338 -243.012468)
					(mid 294.535459 -242.976547)
					(end 294.499538 -242.961668)
				)
				(arc
					(start 293.099998 -242.961668)
					(mid 293.064077 -242.976547)
					(end 293.049198 -243.012468)
				)
			)
		)
	)
	(zone
		(layers "In1.Cu" "In2.Cu")
		(hatch none 0.5)
		(connect_pads
			(clearance 0)
		)
		(min_thickness 0.25)
		(keepout
			(tracks not_allowed)
			(vias allowed)
			(pads allowed)
			(copperpour not_allowed)
			(footprints allowed)
		)
		(placement
			(enabled no)
			(sheetname "")
		)
		(fill yes
			(thermal_gap 0.5)
			(thermal_bridge_width 0.5)
			(island_removal_mode 0)
		)
		(polygon
			(pts
				(arc
					(start 270.417798 -200.921366)
					(mid 270.432677 -200.957287)
					(end 270.468598 -200.972166)
				)
				(arc
					(start 271.868138 -200.972166)
					(mid 271.904059 -200.957287)
					(end 271.918938 -200.921366)
				)
				(arc
					(start 271.918938 -200.512426)
					(mid 271.904059 -200.476505)
					(end 271.868138 -200.461626)
				)
				(arc
					(start 270.468598 -200.461626)
					(mid 270.432677 -200.476505)
					(end 270.417798 -200.512426)
				)
			)
		)
	)
	(zone
		(layers "In1.Cu" "In2.Cu")
		(hatch none 0.5)
		(connect_pads
			(clearance 0)
		)
		(min_thickness 0.25)
		(keepout
			(tracks not_allowed)
			(vias allowed)
			(pads allowed)
			(copperpour not_allowed)
			(footprints allowed)
		)
		(placement
			(enabled no)
			(sheetname "")
		)
		(fill yes
			(thermal_gap 0.5)
			(thermal_bridge_width 0.5)
			(island_removal_mode 0)
		)
		(polygon
			(pts
				(arc
					(start 162.162998 -312.27141)
					(mid 162.177877 -312.307331)
					(end 162.213798 -312.32221)
				)
				(arc
					(start 163.613338 -312.32221)
					(mid 163.649259 -312.307331)
					(end 163.664138 -312.27141)
				)
				(arc
					(start 163.664138 -311.86247)
					(mid 163.649259 -311.826549)
					(end 163.613338 -311.81167)
				)
				(arc
					(start 162.213798 -311.81167)
					(mid 162.177877 -311.826549)
					(end 162.162998 -311.86247)
				)
			)
		)
	)
	(zone
		(layers "In1.Cu" "In2.Cu")
		(hatch none 0.5)
		(connect_pads
			(clearance 0)
		)
		(min_thickness 0.25)
		(keepout
			(tracks not_allowed)
			(vias allowed)
			(pads allowed)
			(copperpour not_allowed)
			(footprints allowed)
		)
		(placement
			(enabled no)
			(sheetname "")
		)
		(fill yes
			(thermal_gap 0.5)
			(thermal_bridge_width 0.5)
			(island_removal_mode 0)
		)
		(polygon
			(pts
				(arc
					(start 421.090598 -280.821384)
					(mid 421.105477 -280.857305)
					(end 421.141398 -280.872184)
				)
				(arc
					(start 422.540938 -280.872184)
					(mid 422.576859 -280.857305)
					(end 422.591738 -280.821384)
				)
				(arc
					(start 422.591738 -280.412444)
					(mid 422.576859 -280.376523)
					(end 422.540938 -280.361644)
				)
				(arc
					(start 421.141398 -280.361644)
					(mid 421.105477 -280.376523)
					(end 421.090598 -280.412444)
				)
			)
		)
	)
	(zone
		(layers "In1.Cu" "In2.Cu")
		(hatch none 0.5)
		(connect_pads
			(clearance 0)
		)
		(min_thickness 0.25)
		(keepout
			(tracks not_allowed)
			(vias allowed)
			(pads allowed)
			(copperpour not_allowed)
			(footprints allowed)
		)
		(placement
			(enabled no)
			(sheetname "")
		)
		(fill yes
			(thermal_gap 0.5)
			(thermal_bridge_width 0.5)
			(island_removal_mode 0)
		)
		(polygon
			(pts
				(arc
					(start 41.665398 -227.271326)
					(mid 41.680277 -227.307247)
					(end 41.716198 -227.322126)
				)
				(arc
					(start 43.115738 -227.322126)
					(mid 43.151659 -227.307247)
					(end 43.166538 -227.271326)
				)
				(arc
					(start 43.166538 -226.862386)
					(mid 43.151659 -226.826465)
					(end 43.115738 -226.811586)
				)
				(arc
					(start 41.716198 -226.811586)
					(mid 41.680277 -226.826465)
					(end 41.665398 -226.862386)
				)
			)
		)
	)
	(zone
		(layers "In1.Cu" "In2.Cu")
		(hatch none 0.5)
		(connect_pads
			(clearance 0)
		)
		(min_thickness 0.25)
		(keepout
			(tracks not_allowed)
			(vias allowed)
			(pads allowed)
			(copperpour not_allowed)
			(footprints allowed)
		)
		(placement
			(enabled no)
			(sheetname "")
		)
		(fill yes
			(thermal_gap 0.5)
			(thermal_bridge_width 0.5)
			(island_removal_mode 0)
		)
		(polygon
			(pts
				(arc
					(start 300.592998 -198.37146)
					(mid 300.607877 -198.407381)
					(end 300.643798 -198.42226)
				)
				(arc
					(start 302.043338 -198.42226)
					(mid 302.079259 -198.407381)
					(end 302.094138 -198.37146)
				)
				(arc
					(start 302.094138 -197.96252)
					(mid 302.079259 -197.926599)
					(end 302.043338 -197.91172)
				)
				(arc
					(start 300.643798 -197.91172)
					(mid 300.607877 -197.926599)
					(end 300.592998 -197.96252)
				)
			)
		)
	)
	(zone
		(layers "In1.Cu" "In2.Cu")
		(hatch none 0.5)
		(connect_pads
			(clearance 0)
		)
		(min_thickness 0.25)
		(keepout
			(tracks not_allowed)
			(vias allowed)
			(pads allowed)
			(copperpour not_allowed)
			(footprints allowed)
		)
		(placement
			(enabled no)
			(sheetname "")
		)
		(fill yes
			(thermal_gap 0.5)
			(thermal_bridge_width 0.5)
			(island_removal_mode 0)
		)
		(polygon
			(pts
				(arc
					(start 30.02153 -240.021364)
					(mid 30.036409 -240.057285)
					(end 30.07233 -240.072164)
				)
				(arc
					(start 31.47187 -240.072164)
					(mid 31.507791 -240.057285)
					(end 31.52267 -240.021364)
				)
				(arc
					(start 31.52267 -239.612424)
					(mid 31.507791 -239.576503)
					(end 31.47187 -239.561624)
				)
				(arc
					(start 30.07233 -239.561624)
					(mid 30.036409 -239.576503)
					(end 30.02153 -239.612424)
				)
			)
		)
	)
	(zone
		(layers "In1.Cu" "In2.Cu")
		(hatch none 0.5)
		(connect_pads
			(clearance 0)
		)
		(min_thickness 0.25)
		(keepout
			(tracks not_allowed)
			(vias allowed)
			(pads allowed)
			(copperpour not_allowed)
			(footprints allowed)
		)
		(placement
			(enabled no)
			(sheetname "")
		)
		(fill yes
			(thermal_gap 0.5)
			(thermal_bridge_width 0.5)
			(island_removal_mode 0)
		)
		(polygon
			(pts
				(arc
					(start 207.425798 -200.071482)
					(mid 207.440677 -200.107403)
					(end 207.476598 -200.122282)
				)
				(arc
					(start 208.876138 -200.122282)
					(mid 208.912059 -200.107403)
					(end 208.926938 -200.071482)
				)
				(arc
					(start 208.926938 -199.662542)
					(mid 208.912059 -199.626621)
					(end 208.876138 -199.611742)
				)
				(arc
					(start 207.476598 -199.611742)
					(mid 207.440677 -199.626621)
					(end 207.425798 -199.662542)
				)
			)
		)
	)
	(zone
		(layers "In1.Cu" "In2.Cu")
		(hatch none 0.5)
		(connect_pads
			(clearance 0)
		)
		(min_thickness 0.25)
		(keepout
			(tracks not_allowed)
			(vias allowed)
			(pads allowed)
			(copperpour not_allowed)
			(footprints allowed)
		)
		(placement
			(enabled no)
			(sheetname "")
		)
		(fill yes
			(thermal_gap 0.5)
			(thermal_bridge_width 0.5)
			(island_removal_mode 0)
		)
		(polygon
			(pts
				(arc
					(start 277.961598 -224.72142)
					(mid 277.976477 -224.757341)
					(end 278.012398 -224.77222)
				)
				(arc
					(start 279.411938 -224.77222)
					(mid 279.447859 -224.757341)
					(end 279.462738 -224.72142)
				)
				(arc
					(start 279.462738 -224.31248)
					(mid 279.447859 -224.276559)
					(end 279.411938 -224.26168)
				)
				(arc
					(start 278.012398 -224.26168)
					(mid 277.976477 -224.276559)
					(end 277.961598 -224.31248)
				)
			)
		)
	)
	(zone
		(layers "In1.Cu" "In2.Cu")
		(hatch none 0.5)
		(connect_pads
			(clearance 0)
		)
		(min_thickness 0.25)
		(keepout
			(tracks not_allowed)
			(vias allowed)
			(pads allowed)
			(copperpour not_allowed)
			(footprints allowed)
		)
		(placement
			(enabled no)
			(sheetname "")
		)
		(fill yes
			(thermal_gap 0.5)
			(thermal_bridge_width 0.5)
			(island_removal_mode 0)
		)
		(polygon
			(pts
				(arc
					(start 11.490198 -263.821418)
					(mid 11.505077 -263.857339)
					(end 11.540998 -263.872218)
				)
				(arc
					(start 12.940538 -263.872218)
					(mid 12.976459 -263.857339)
					(end 12.991338 -263.821418)
				)
				(arc
					(start 12.991338 -263.412478)
					(mid 12.976459 -263.376557)
					(end 12.940538 -263.361678)
				)
				(arc
					(start 11.540998 -263.361678)
					(mid 11.505077 -263.376557)
					(end 11.490198 -263.412478)
				)
			)
		)
	)
	(zone
		(layers "In1.Cu" "In2.Cu")
		(hatch none 0.5)
		(connect_pads
			(clearance 0)
		)
		(min_thickness 0.25)
		(keepout
			(tracks not_allowed)
			(vias allowed)
			(pads allowed)
			(copperpour not_allowed)
			(footprints allowed)
		)
		(placement
			(enabled no)
			(sheetname "")
		)
		(fill yes
			(thermal_gap 0.5)
			(thermal_bridge_width 0.5)
			(island_removal_mode 0)
		)
		(polygon
			(pts
				(arc
					(start 7.39013 -303.7713)
					(mid 7.405009 -303.807221)
					(end 7.44093 -303.8221)
				)
				(arc
					(start 8.84047 -303.8221)
					(mid 8.876391 -303.807221)
					(end 8.89127 -303.7713)
				)
				(arc
					(start 8.89127 -303.36236)
					(mid 8.876391 -303.326439)
					(end 8.84047 -303.31156)
				)
				(arc
					(start 7.44093 -303.31156)
					(mid 7.405009 -303.326439)
					(end 7.39013 -303.36236)
				)
			)
		)
	)
	(zone
		(layers "In1.Cu" "In2.Cu")
		(hatch none 0.5)
		(connect_pads
			(clearance 0)
		)
		(min_thickness 0.25)
		(keepout
			(tracks not_allowed)
			(vias allowed)
			(pads allowed)
			(copperpour not_allowed)
			(footprints allowed)
		)
		(placement
			(enabled no)
			(sheetname "")
		)
		(fill yes
			(thermal_gap 0.5)
			(thermal_bridge_width 0.5)
			(island_removal_mode 0)
		)
		(polygon
			(pts
				(arc
					(start 277.961598 -238.321342)
					(mid 277.976477 -238.357263)
					(end 278.012398 -238.372142)
				)
				(arc
					(start 279.411938 -238.372142)
					(mid 279.447859 -238.357263)
					(end 279.462738 -238.321342)
				)
				(arc
					(start 279.462738 -237.912402)
					(mid 279.447859 -237.876481)
					(end 279.411938 -237.861602)
				)
				(arc
					(start 278.012398 -237.861602)
					(mid 277.976477 -237.876481)
					(end 277.961598 -237.912402)
				)
			)
		)
	)
	(zone
		(layers "In1.Cu" "In2.Cu")
		(hatch none 0.5)
		(connect_pads
			(clearance 0)
		)
		(min_thickness 0.25)
		(keepout
			(tracks not_allowed)
			(vias allowed)
			(pads allowed)
			(copperpour not_allowed)
			(footprints allowed)
		)
		(placement
			(enabled no)
			(sheetname "")
		)
		(fill yes
			(thermal_gap 0.5)
			(thermal_bridge_width 0.5)
			(island_removal_mode 0)
		)
		(polygon
			(pts
				(arc
					(start 410.103066 -199.221344)
					(mid 410.117945 -199.257265)
					(end 410.153866 -199.272144)
				)
				(arc
					(start 411.553406 -199.272144)
					(mid 411.589327 -199.257265)
					(end 411.604206 -199.221344)
				)
				(arc
					(start 411.604206 -198.812404)
					(mid 411.589327 -198.776483)
					(end 411.553406 -198.761604)
				)
				(arc
					(start 410.153866 -198.761604)
					(mid 410.117945 -198.776483)
					(end 410.103066 -198.812404)
				)
			)
		)
	)
	(zone
		(layers "In1.Cu" "In2.Cu")
		(hatch none 0.5)
		(connect_pads
			(clearance 0)
		)
		(min_thickness 0.25)
		(keepout
			(tracks not_allowed)
			(vias allowed)
			(pads allowed)
			(copperpour not_allowed)
			(footprints allowed)
		)
		(placement
			(enabled no)
			(sheetname "")
		)
		(fill yes
			(thermal_gap 0.5)
			(thermal_bridge_width 0.5)
			(island_removal_mode 0)
		)
		(polygon
			(pts
				(arc
					(start 312.236866 -265.52144)
					(mid 312.251745 -265.557361)
					(end 312.287666 -265.57224)
				)
				(arc
					(start 313.687206 -265.57224)
					(mid 313.723127 -265.557361)
					(end 313.738006 -265.52144)
				)
				(arc
					(start 313.738006 -265.1125)
					(mid 313.723127 -265.076579)
					(end 313.687206 -265.0617)
				)
				(arc
					(start 312.287666 -265.0617)
					(mid 312.251745 -265.076579)
					(end 312.236866 -265.1125)
				)
			)
		)
	)
	(zone
		(layers "In1.Cu" "In2.Cu")
		(hatch none 0.5)
		(connect_pads
			(clearance 0)
		)
		(min_thickness 0.25)
		(keepout
			(tracks not_allowed)
			(vias allowed)
			(pads allowed)
			(copperpour not_allowed)
			(footprints allowed)
		)
		(placement
			(enabled no)
			(sheetname "")
		)
		(fill yes
			(thermal_gap 0.5)
			(thermal_bridge_width 0.5)
			(island_removal_mode 0)
		)
		(polygon
			(pts
				(arc
					(start 417.646866 -218.77147)
					(mid 417.661745 -218.807391)
					(end 417.697666 -218.82227)
				)
				(arc
					(start 419.097206 -218.82227)
					(mid 419.133127 -218.807391)
					(end 419.148006 -218.77147)
				)
				(arc
					(start 419.148006 -218.36253)
					(mid 419.133127 -218.326609)
					(end 419.097206 -218.31173)
				)
				(arc
					(start 417.697666 -218.31173)
					(mid 417.661745 -218.326609)
					(end 417.646866 -218.36253)
				)
			)
		)
	)
	(zone
		(layers "In1.Cu" "In2.Cu")
		(hatch none 0.5)
		(connect_pads
			(clearance 0)
		)
		(min_thickness 0.25)
		(keepout
			(tracks not_allowed)
			(vias allowed)
			(pads allowed)
			(copperpour not_allowed)
			(footprints allowed)
		)
		(placement
			(enabled no)
			(sheetname "")
		)
		(fill yes
			(thermal_gap 0.5)
			(thermal_bridge_width 0.5)
			(island_removal_mode 0)
		)
		(polygon
			(pts
				(arc
					(start 34.121598 -212.82152)
					(mid 34.136477 -212.857441)
					(end 34.172398 -212.87232)
				)
				(arc
					(start 35.571938 -212.87232)
					(mid 35.607859 -212.857441)
					(end 35.622738 -212.82152)
				)
				(arc
					(start 35.622738 -212.41258)
					(mid 35.607859 -212.376659)
					(end 35.571938 -212.36178)
				)
				(arc
					(start 34.172398 -212.36178)
					(mid 34.136477 -212.376659)
					(end 34.121598 -212.41258)
				)
			)
		)
	)
	(zone
		(layers "In1.Cu" "In2.Cu")
		(hatch none 0.5)
		(connect_pads
			(clearance 0)
		)
		(min_thickness 0.25)
		(keepout
			(tracks not_allowed)
			(vias allowed)
			(pads allowed)
			(copperpour not_allowed)
			(footprints allowed)
		)
		(placement
			(enabled no)
			(sheetname "")
		)
		(fill yes
			(thermal_gap 0.5)
			(thermal_bridge_width 0.5)
			(island_removal_mode 0)
		)
		(polygon
			(pts
				(arc
					(start 19.033998 -263.821418)
					(mid 19.048877 -263.857339)
					(end 19.084798 -263.872218)
				)
				(arc
					(start 20.484338 -263.872218)
					(mid 20.520259 -263.857339)
					(end 20.535138 -263.821418)
				)
				(arc
					(start 20.535138 -263.412478)
					(mid 20.520259 -263.376557)
					(end 20.484338 -263.361678)
				)
				(arc
					(start 19.084798 -263.361678)
					(mid 19.048877 -263.376557)
					(end 19.033998 -263.412478)
				)
			)
		)
	)
	(zone
		(layers "In1.Cu" "In2.Cu")
		(hatch none 0.5)
		(connect_pads
			(clearance 0)
		)
		(min_thickness 0.25)
		(keepout
			(tracks not_allowed)
			(vias allowed)
			(pads allowed)
			(copperpour not_allowed)
			(footprints allowed)
		)
		(placement
			(enabled no)
			(sheetname "")
		)
		(fill yes
			(thermal_gap 0.5)
			(thermal_bridge_width 0.5)
			(island_removal_mode 0)
		)
		(polygon
			(pts
				(arc
					(start 30.02153 -224.72142)
					(mid 30.036409 -224.757341)
					(end 30.07233 -224.77222)
				)
				(arc
					(start 31.47187 -224.77222)
					(mid 31.507791 -224.757341)
					(end 31.52267 -224.72142)
				)
				(arc
					(start 31.52267 -224.31248)
					(mid 31.507791 -224.276559)
					(end 31.47187 -224.26168)
				)
				(arc
					(start 30.07233 -224.26168)
					(mid 30.036409 -224.276559)
					(end 30.02153 -224.31248)
				)
			)
		)
	)
	(zone
		(layers "In1.Cu" "In2.Cu")
		(hatch none 0.5)
		(connect_pads
			(clearance 0)
		)
		(min_thickness 0.25)
		(keepout
			(tracks not_allowed)
			(vias allowed)
			(pads allowed)
			(copperpour not_allowed)
			(footprints allowed)
		)
		(placement
			(enabled no)
			(sheetname "")
		)
		(fill yes
			(thermal_gap 0.5)
			(thermal_bridge_width 0.5)
			(island_removal_mode 0)
		)
		(polygon
			(pts
				(arc
					(start 22.47773 -218.77147)
					(mid 22.492609 -218.807391)
					(end 22.52853 -218.82227)
				)
				(arc
					(start 23.92807 -218.82227)
					(mid 23.963991 -218.807391)
					(end 23.97887 -218.77147)
				)
				(arc
					(start 23.97887 -218.36253)
					(mid 23.963991 -218.326609)
					(end 23.92807 -218.31173)
				)
				(arc
					(start 22.52853 -218.31173)
					(mid 22.492609 -218.326609)
					(end 22.47773 -218.36253)
				)
			)
		)
	)
	(zone
		(layers "In1.Cu" "In2.Cu")
		(hatch none 0.5)
		(connect_pads
			(clearance 0)
		)
		(min_thickness 0.25)
		(keepout
			(tracks not_allowed)
			(vias allowed)
			(pads allowed)
			(copperpour not_allowed)
			(footprints allowed)
		)
		(placement
			(enabled no)
			(sheetname "")
		)
		(fill yes
			(thermal_gap 0.5)
			(thermal_bridge_width 0.5)
			(island_removal_mode 0)
		)
		(polygon
			(pts
				(arc
					(start 266.974066 -203.471526)
					(mid 266.988945 -203.507447)
					(end 267.024866 -203.522326)
				)
				(arc
					(start 268.424406 -203.522326)
					(mid 268.460327 -203.507447)
					(end 268.475206 -203.471526)
				)
				(arc
					(start 268.475206 -203.062586)
					(mid 268.460327 -203.026665)
					(end 268.424406 -203.011786)
				)
				(arc
					(start 267.024866 -203.011786)
					(mid 266.988945 -203.026665)
					(end 266.974066 -203.062586)
				)
			)
		)
	)
	(zone
		(layers "In1.Cu" "In2.Cu")
		(hatch none 0.5)
		(connect_pads
			(clearance 0)
		)
		(min_thickness 0.25)
		(keepout
			(tracks not_allowed)
			(vias allowed)
			(pads allowed)
			(copperpour not_allowed)
			(footprints allowed)
		)
		(placement
			(enabled no)
			(sheetname "")
		)
		(fill yes
			(thermal_gap 0.5)
			(thermal_bridge_width 0.5)
			(island_removal_mode 0)
		)
		(polygon
			(pts
				(arc
					(start 199.881998 -220.471492)
					(mid 199.896877 -220.507413)
					(end 199.932798 -220.522292)
				)
				(arc
					(start 201.332338 -220.522292)
					(mid 201.368259 -220.507413)
					(end 201.383138 -220.471492)
				)
				(arc
					(start 201.383138 -220.062552)
					(mid 201.368259 -220.026631)
					(end 201.332338 -220.011752)
				)
				(arc
					(start 199.932798 -220.011752)
					(mid 199.896877 -220.026631)
					(end 199.881998 -220.062552)
				)
			)
		)
	)
	(zone
		(layers "In1.Cu" "In2.Cu")
		(hatch none 0.5)
		(connect_pads
			(clearance 0)
		)
		(min_thickness 0.25)
		(keepout
			(tracks not_allowed)
			(vias allowed)
			(pads allowed)
			(copperpour not_allowed)
			(footprints allowed)
		)
		(placement
			(enabled no)
			(sheetname "")
		)
		(fill yes
			(thermal_gap 0.5)
			(thermal_bridge_width 0.5)
			(island_removal_mode 0)
		)
		(polygon
			(pts
				(arc
					(start 184.794398 -287.621472)
					(mid 184.809277 -287.657393)
					(end 184.845198 -287.672272)
				)
				(arc
					(start 186.244738 -287.672272)
					(mid 186.280659 -287.657393)
					(end 186.295538 -287.621472)
				)
				(arc
					(start 186.295538 -287.212532)
					(mid 186.280659 -287.176611)
					(end 186.244738 -287.161732)
				)
				(arc
					(start 184.845198 -287.161732)
					(mid 184.809277 -287.176611)
					(end 184.794398 -287.212532)
				)
			)
		)
	)
	(zone
		(layers "In1.Cu" "In2.Cu")
		(hatch none 0.5)
		(connect_pads
			(clearance 0)
		)
		(min_thickness 0.25)
		(keepout
			(tracks not_allowed)
			(vias allowed)
			(pads allowed)
			(copperpour not_allowed)
			(footprints allowed)
		)
		(placement
			(enabled no)
			(sheetname "")
		)
		(fill yes
			(thermal_gap 0.5)
			(thermal_bridge_width 0.5)
			(island_removal_mode 0)
		)
		(polygon
			(pts
				(arc
					(start 262.873998 -297.82135)
					(mid 262.888877 -297.857271)
					(end 262.924798 -297.87215)
				)
				(arc
					(start 264.324338 -297.87215)
					(mid 264.360259 -297.857271)
					(end 264.375138 -297.82135)
				)
				(arc
					(start 264.375138 -297.41241)
					(mid 264.360259 -297.376489)
					(end 264.324338 -297.36161)
				)
				(arc
					(start 262.924798 -297.36161)
					(mid 262.888877 -297.376489)
					(end 262.873998 -297.41241)
				)
			)
		)
	)
	(zone
		(layers "In1.Cu" "In2.Cu")
		(hatch none 0.5)
		(connect_pads
			(clearance 0)
		)
		(min_thickness 0.25)
		(keepout
			(tracks not_allowed)
			(vias allowed)
			(pads allowed)
			(copperpour not_allowed)
			(footprints allowed)
		)
		(placement
			(enabled no)
			(sheetname "")
		)
		(fill yes
			(thermal_gap 0.5)
			(thermal_bridge_width 0.5)
			(island_removal_mode 0)
		)
		(polygon
			(pts
				(arc
					(start 7.39013 -273.171412)
					(mid 7.405009 -273.207333)
					(end 7.44093 -273.222212)
				)
				(arc
					(start 8.84047 -273.222212)
					(mid 8.876391 -273.207333)
					(end 8.89127 -273.171412)
				)
				(arc
					(start 8.89127 -272.762472)
					(mid 8.876391 -272.726551)
					(end 8.84047 -272.711672)
				)
				(arc
					(start 7.44093 -272.711672)
					(mid 7.405009 -272.726551)
					(end 7.39013 -272.762472)
				)
			)
		)
	)
	(zone
		(layers "In1.Cu" "In2.Cu")
		(hatch none 0.5)
		(connect_pads
			(clearance 0)
		)
		(min_thickness 0.25)
		(keepout
			(tracks not_allowed)
			(vias allowed)
			(pads allowed)
			(copperpour not_allowed)
			(footprints allowed)
		)
		(placement
			(enabled no)
			(sheetname "")
		)
		(fill yes
			(thermal_gap 0.5)
			(thermal_bridge_width 0.5)
			(island_removal_mode 0)
		)
		(polygon
			(pts
				(arc
					(start 425.190666 -274.871434)
					(mid 425.205545 -274.907355)
					(end 425.241466 -274.922234)
				)
				(arc
					(start 426.641006 -274.922234)
					(mid 426.676927 -274.907355)
					(end 426.691806 -274.871434)
				)
				(arc
					(start 426.691806 -274.462494)
					(mid 426.676927 -274.426573)
					(end 426.641006 -274.411694)
				)
				(arc
					(start 425.241466 -274.411694)
					(mid 425.205545 -274.426573)
					(end 425.190666 -274.462494)
				)
			)
		)
	)
	(zone
		(layers "In1.Cu" "In2.Cu")
		(hatch none 0.5)
		(connect_pads
			(clearance 0)
		)
		(min_thickness 0.25)
		(keepout
			(tracks not_allowed)
			(vias allowed)
			(pads allowed)
			(copperpour not_allowed)
			(footprints allowed)
		)
		(placement
			(enabled no)
			(sheetname "")
		)
		(fill yes
			(thermal_gap 0.5)
			(thermal_bridge_width 0.5)
			(island_removal_mode 0)
		)
		(polygon
			(pts
				(arc
					(start 203.32573 -215.371426)
					(mid 203.340609 -215.407347)
					(end 203.37653 -215.422226)
				)
				(arc
					(start 204.77607 -215.422226)
					(mid 204.811991 -215.407347)
					(end 204.82687 -215.371426)
				)
				(arc
					(start 204.82687 -214.962486)
					(mid 204.811991 -214.926565)
					(end 204.77607 -214.911686)
				)
				(arc
					(start 203.37653 -214.911686)
					(mid 203.340609 -214.926565)
					(end 203.32573 -214.962486)
				)
			)
		)
	)
	(zone
		(layers "In1.Cu" "In2.Cu")
		(hatch none 0.5)
		(connect_pads
			(clearance 0)
		)
		(min_thickness 0.25)
		(keepout
			(tracks not_allowed)
			(vias allowed)
			(pads allowed)
			(copperpour not_allowed)
			(footprints allowed)
		)
		(placement
			(enabled no)
			(sheetname "")
		)
		(fill yes
			(thermal_gap 0.5)
			(thermal_bridge_width 0.5)
			(island_removal_mode 0)
		)
		(polygon
			(pts
				(arc
					(start 207.425798 -309.721504)
					(mid 207.440677 -309.757425)
					(end 207.476598 -309.772304)
				)
				(arc
					(start 208.876138 -309.772304)
					(mid 208.912059 -309.757425)
					(end 208.926938 -309.721504)
				)
				(arc
					(start 208.926938 -309.312564)
					(mid 208.912059 -309.276643)
					(end 208.876138 -309.261764)
				)
				(arc
					(start 207.476598 -309.261764)
					(mid 207.440677 -309.276643)
					(end 207.425798 -309.312564)
				)
			)
		)
	)
	(zone
		(layers "In1.Cu" "In2.Cu")
		(hatch none 0.5)
		(connect_pads
			(clearance 0)
		)
		(min_thickness 0.25)
		(keepout
			(tracks not_allowed)
			(vias allowed)
			(pads allowed)
			(copperpour not_allowed)
			(footprints allowed)
		)
		(placement
			(enabled no)
			(sheetname "")
		)
		(fill yes
			(thermal_gap 0.5)
			(thermal_bridge_width 0.5)
			(island_removal_mode 0)
		)
		(polygon
			(pts
				(arc
					(start 11.490198 -300.37151)
					(mid 11.505077 -300.407431)
					(end 11.540998 -300.42231)
				)
				(arc
					(start 12.940538 -300.42231)
					(mid 12.976459 -300.407431)
					(end 12.991338 -300.37151)
				)
				(arc
					(start 12.991338 -299.96257)
					(mid 12.976459 -299.926649)
					(end 12.940538 -299.91177)
				)
				(arc
					(start 11.540998 -299.91177)
					(mid 11.505077 -299.926649)
					(end 11.490198 -299.96257)
				)
			)
		)
	)
	(zone
		(layers "In1.Cu" "In2.Cu")
		(hatch none 0.5)
		(connect_pads
			(clearance 0)
		)
		(min_thickness 0.25)
		(keepout
			(tracks not_allowed)
			(vias allowed)
			(pads allowed)
			(copperpour not_allowed)
			(footprints allowed)
		)
		(placement
			(enabled no)
			(sheetname "")
		)
		(fill yes
			(thermal_gap 0.5)
			(thermal_bridge_width 0.5)
			(island_removal_mode 0)
		)
		(polygon
			(pts
				(arc
					(start 270.417798 -285.071312)
					(mid 270.432677 -285.107233)
					(end 270.468598 -285.122112)
				)
				(arc
					(start 271.868138 -285.122112)
					(mid 271.904059 -285.107233)
					(end 271.918938 -285.071312)
				)
				(arc
					(start 271.918938 -284.662372)
					(mid 271.904059 -284.626451)
					(end 271.868138 -284.611572)
				)
				(arc
					(start 270.468598 -284.611572)
					(mid 270.432677 -284.626451)
					(end 270.417798 -284.662372)
				)
			)
		)
	)
	(zone
		(layers "In1.Cu" "In2.Cu")
		(hatch none 0.5)
		(connect_pads
			(clearance 0)
		)
		(min_thickness 0.25)
		(keepout
			(tracks not_allowed)
			(vias allowed)
			(pads allowed)
			(copperpour not_allowed)
			(footprints allowed)
		)
		(placement
			(enabled no)
			(sheetname "")
		)
		(fill yes
			(thermal_gap 0.5)
			(thermal_bridge_width 0.5)
			(island_removal_mode 0)
		)
		(polygon
			(pts
				(arc
					(start 447.822066 -298.671488)
					(mid 447.836945 -298.707409)
					(end 447.872866 -298.722288)
				)
				(arc
					(start 449.272406 -298.722288)
					(mid 449.308327 -298.707409)
					(end 449.323206 -298.671488)
				)
				(arc
					(start 449.323206 -298.262548)
					(mid 449.308327 -298.226627)
					(end 449.272406 -298.211748)
				)
				(arc
					(start 447.872866 -298.211748)
					(mid 447.836945 -298.226627)
					(end 447.822066 -298.262548)
				)
			)
		)
	)
	(zone
		(layers "In1.Cu" "In2.Cu")
		(hatch none 0.5)
		(connect_pads
			(clearance 0)
		)
		(min_thickness 0.25)
		(keepout
			(tracks not_allowed)
			(vias allowed)
			(pads allowed)
			(copperpour not_allowed)
			(footprints allowed)
		)
		(placement
			(enabled no)
			(sheetname "")
		)
		(fill yes
			(thermal_gap 0.5)
			(thermal_bridge_width 0.5)
			(island_removal_mode 0)
		)
		(polygon
			(pts
				(arc
					(start 11.490198 -311.421526)
					(mid 11.505077 -311.457447)
					(end 11.540998 -311.472326)
				)
				(arc
					(start 12.940538 -311.472326)
					(mid 12.976459 -311.457447)
					(end 12.991338 -311.421526)
				)
				(arc
					(start 12.991338 -311.012586)
					(mid 12.976459 -310.976665)
					(end 12.940538 -310.961786)
				)
				(arc
					(start 11.540998 -310.961786)
					(mid 11.505077 -310.976665)
					(end 11.490198 -311.012586)
				)
			)
		)
	)
	(zone
		(layers "In1.Cu" "In2.Cu")
		(hatch none 0.5)
		(connect_pads
			(clearance 0)
		)
		(min_thickness 0.25)
		(keepout
			(tracks not_allowed)
			(vias allowed)
			(pads allowed)
			(copperpour not_allowed)
			(footprints allowed)
		)
		(placement
			(enabled no)
			(sheetname "")
		)
		(fill yes
			(thermal_gap 0.5)
			(thermal_bridge_width 0.5)
			(island_removal_mode 0)
		)
		(polygon
			(pts
				(arc
					(start 56.752998 -270.621506)
					(mid 56.767877 -270.657427)
					(end 56.803798 -270.672306)
				)
				(arc
					(start 58.203338 -270.672306)
					(mid 58.239259 -270.657427)
					(end 58.254138 -270.621506)
				)
				(arc
					(start 58.254138 -270.212566)
					(mid 58.239259 -270.176645)
					(end 58.203338 -270.161766)
				)
				(arc
					(start 56.803798 -270.161766)
					(mid 56.767877 -270.176645)
					(end 56.752998 -270.212566)
				)
			)
		)
	)
	(zone
		(layers "In1.Cu" "In2.Cu")
		(hatch none 0.5)
		(connect_pads
			(clearance 0)
		)
		(min_thickness 0.25)
		(keepout
			(tracks not_allowed)
			(vias allowed)
			(pads allowed)
			(copperpour not_allowed)
			(footprints allowed)
		)
		(placement
			(enabled no)
			(sheetname "")
		)
		(fill yes
			(thermal_gap 0.5)
			(thermal_bridge_width 0.5)
			(island_removal_mode 0)
		)
		(polygon
			(pts
				(arc
					(start 443.721998 -303.7713)
					(mid 443.736877 -303.807221)
					(end 443.772798 -303.8221)
				)
				(arc
					(start 445.172338 -303.8221)
					(mid 445.208259 -303.807221)
					(end 445.223138 -303.7713)
				)
				(arc
					(start 445.223138 -303.36236)
					(mid 445.208259 -303.326439)
					(end 445.172338 -303.31156)
				)
				(arc
					(start 443.772798 -303.31156)
					(mid 443.736877 -303.326439)
					(end 443.721998 -303.36236)
				)
			)
		)
	)
	(zone
		(layers "In1.Cu" "In2.Cu")
		(hatch none 0.5)
		(connect_pads
			(clearance 0)
		)
		(min_thickness 0.25)
		(keepout
			(tracks not_allowed)
			(vias allowed)
			(pads allowed)
			(copperpour not_allowed)
			(footprints allowed)
		)
		(placement
			(enabled no)
			(sheetname "")
		)
		(fill yes
			(thermal_gap 0.5)
			(thermal_bridge_width 0.5)
			(island_removal_mode 0)
		)
		(polygon
			(pts
				(arc
					(start 455.365866 -211.121498)
					(mid 455.380745 -211.157419)
					(end 455.416666 -211.172298)
				)
				(arc
					(start 456.816206 -211.172298)
					(mid 456.852127 -211.157419)
					(end 456.867006 -211.121498)
				)
				(arc
					(start 456.867006 -210.712558)
					(mid 456.852127 -210.676637)
					(end 456.816206 -210.661758)
				)
				(arc
					(start 455.416666 -210.661758)
					(mid 455.380745 -210.676637)
					(end 455.365866 -210.712558)
				)
			)
		)
	)
	(zone
		(layers "In1.Cu" "In2.Cu")
		(hatch none 0.5)
		(connect_pads
			(clearance 0)
		)
		(min_thickness 0.25)
		(keepout
			(tracks not_allowed)
			(vias allowed)
			(pads allowed)
			(copperpour not_allowed)
			(footprints allowed)
		)
		(placement
			(enabled no)
			(sheetname "")
		)
		(fill yes
			(thermal_gap 0.5)
			(thermal_bridge_width 0.5)
			(island_removal_mode 0)
		)
		(polygon
			(pts
				(arc
					(start 443.721998 -299.521372)
					(mid 443.736877 -299.557293)
					(end 443.772798 -299.572172)
				)
				(arc
					(start 445.172338 -299.572172)
					(mid 445.208259 -299.557293)
					(end 445.223138 -299.521372)
				)
				(arc
					(start 445.223138 -299.112432)
					(mid 445.208259 -299.076511)
					(end 445.172338 -299.061632)
				)
				(arc
					(start 443.772798 -299.061632)
					(mid 443.736877 -299.076511)
					(end 443.721998 -299.112432)
				)
			)
		)
	)
	(zone
		(layers "In1.Cu" "In2.Cu")
		(hatch none 0.5)
		(connect_pads
			(clearance 0)
		)
		(min_thickness 0.25)
		(keepout
			(tracks not_allowed)
			(vias allowed)
			(pads allowed)
			(copperpour not_allowed)
			(footprints allowed)
		)
		(placement
			(enabled no)
			(sheetname "")
		)
		(fill yes
			(thermal_gap 0.5)
			(thermal_bridge_width 0.5)
			(island_removal_mode 0)
		)
		(polygon
			(pts
				(arc
					(start 26.577798 -195.821554)
					(mid 26.592677 -195.857475)
					(end 26.628598 -195.872354)
				)
				(arc
					(start 28.028138 -195.872354)
					(mid 28.064059 -195.857475)
					(end 28.078938 -195.821554)
				)
				(arc
					(start 28.078938 -195.412614)
					(mid 28.064059 -195.376693)
					(end 28.028138 -195.361814)
				)
				(arc
					(start 26.628598 -195.361814)
					(mid 26.592677 -195.376693)
					(end 26.577798 -195.412614)
				)
			)
		)
	)
	(zone
		(layers "In1.Cu" "In2.Cu")
		(hatch none 0.5)
		(connect_pads
			(clearance 0)
		)
		(min_thickness 0.25)
		(keepout
			(tracks not_allowed)
			(vias allowed)
			(pads allowed)
			(copperpour not_allowed)
			(footprints allowed)
		)
		(placement
			(enabled no)
			(sheetname "")
		)
		(fill yes
			(thermal_gap 0.5)
			(thermal_bridge_width 0.5)
			(island_removal_mode 0)
		)
		(polygon
			(pts
				(arc
					(start 56.752998 -218.77147)
					(mid 56.767877 -218.807391)
					(end 56.803798 -218.82227)
				)
				(arc
					(start 58.203338 -218.82227)
					(mid 58.239259 -218.807391)
					(end 58.254138 -218.77147)
				)
				(arc
					(start 58.254138 -218.36253)
					(mid 58.239259 -218.326609)
					(end 58.203338 -218.31173)
				)
				(arc
					(start 56.803798 -218.31173)
					(mid 56.767877 -218.326609)
					(end 56.752998 -218.36253)
				)
			)
		)
	)
	(zone
		(layers "In1.Cu" "In2.Cu")
		(hatch none 0.5)
		(connect_pads
			(clearance 0)
		)
		(min_thickness 0.25)
		(keepout
			(tracks not_allowed)
			(vias allowed)
			(pads allowed)
			(copperpour not_allowed)
			(footprints allowed)
		)
		(placement
			(enabled no)
			(sheetname "")
		)
		(fill yes
			(thermal_gap 0.5)
			(thermal_bridge_width 0.5)
			(island_removal_mode 0)
		)
		(polygon
			(pts
				(arc
					(start 188.23813 -316.521338)
					(mid 188.253009 -316.557259)
					(end 188.28893 -316.572138)
				)
				(arc
					(start 189.68847 -316.572138)
					(mid 189.724391 -316.557259)
					(end 189.73927 -316.521338)
				)
				(arc
					(start 189.73927 -316.112398)
					(mid 189.724391 -316.076477)
					(end 189.68847 -316.061598)
				)
				(arc
					(start 188.28893 -316.061598)
					(mid 188.253009 -316.076477)
					(end 188.23813 -316.112398)
				)
			)
		)
	)
	(zone
		(layers "In1.Cu" "In2.Cu")
		(hatch none 0.5)
		(connect_pads
			(clearance 0)
		)
		(min_thickness 0.25)
		(keepout
			(tracks not_allowed)
			(vias allowed)
			(pads allowed)
			(copperpour not_allowed)
			(footprints allowed)
		)
		(placement
			(enabled no)
			(sheetname "")
		)
		(fill yes
			(thermal_gap 0.5)
			(thermal_bridge_width 0.5)
			(island_removal_mode 0)
		)
		(polygon
			(pts
				(arc
					(start 432.734466 -313.971432)
					(mid 432.749345 -314.007353)
					(end 432.785266 -314.022232)
				)
				(arc
					(start 434.184806 -314.022232)
					(mid 434.220727 -314.007353)
					(end 434.235606 -313.971432)
				)
				(arc
					(start 434.235606 -313.562492)
					(mid 434.220727 -313.526571)
					(end 434.184806 -313.511692)
				)
				(arc
					(start 432.785266 -313.511692)
					(mid 432.749345 -313.526571)
					(end 432.734466 -313.562492)
				)
			)
		)
	)
	(zone
		(layers "In1.Cu" "In2.Cu")
		(hatch none 0.5)
		(connect_pads
			(clearance 0)
		)
		(min_thickness 0.25)
		(keepout
			(tracks not_allowed)
			(vias allowed)
			(pads allowed)
			(copperpour not_allowed)
			(footprints allowed)
		)
		(placement
			(enabled no)
			(sheetname "")
		)
		(fill yes
			(thermal_gap 0.5)
			(thermal_bridge_width 0.5)
			(island_removal_mode 0)
		)
		(polygon
			(pts
				(arc
					(start 436.178198 -198.37146)
					(mid 436.193077 -198.407381)
					(end 436.228998 -198.42226)
				)
				(arc
					(start 437.628538 -198.42226)
					(mid 437.664459 -198.407381)
					(end 437.679338 -198.37146)
				)
				(arc
					(start 437.679338 -197.96252)
					(mid 437.664459 -197.926599)
					(end 437.628538 -197.91172)
				)
				(arc
					(start 436.228998 -197.91172)
					(mid 436.193077 -197.926599)
					(end 436.178198 -197.96252)
				)
			)
		)
	)
	(zone
		(layers "In1.Cu" "In2.Cu")
		(hatch none 0.5)
		(connect_pads
			(clearance 0)
		)
		(min_thickness 0.25)
		(keepout
			(tracks not_allowed)
			(vias allowed)
			(pads allowed)
			(copperpour not_allowed)
			(footprints allowed)
		)
		(placement
			(enabled no)
			(sheetname "")
		)
		(fill yes
			(thermal_gap 0.5)
			(thermal_bridge_width 0.5)
			(island_removal_mode 0)
		)
		(polygon
			(pts
				(arc
					(start 304.693066 -300.37151)
					(mid 304.707945 -300.407431)
					(end 304.743866 -300.42231)
				)
				(arc
					(start 306.143406 -300.42231)
					(mid 306.179327 -300.407431)
					(end 306.194206 -300.37151)
				)
				(arc
					(start 306.194206 -299.96257)
					(mid 306.179327 -299.926649)
					(end 306.143406 -299.91177)
				)
				(arc
					(start 304.743866 -299.91177)
					(mid 304.707945 -299.926649)
					(end 304.693066 -299.96257)
				)
			)
		)
	)
	(zone
		(layers "In1.Cu" "In2.Cu")
		(hatch none 0.5)
		(connect_pads
			(clearance 0)
		)
		(min_thickness 0.25)
		(keepout
			(tracks not_allowed)
			(vias allowed)
			(pads allowed)
			(copperpour not_allowed)
			(footprints allowed)
		)
		(placement
			(enabled no)
			(sheetname "")
		)
		(fill yes
			(thermal_gap 0.5)
			(thermal_bridge_width 0.5)
			(island_removal_mode 0)
		)
		(polygon
			(pts
				(arc
					(start 64.296798 -289.321494)
					(mid 64.311677 -289.357415)
					(end 64.347598 -289.372294)
				)
				(arc
					(start 65.747138 -289.372294)
					(mid 65.783059 -289.357415)
					(end 65.797938 -289.321494)
				)
				(arc
					(start 65.797938 -288.912554)
					(mid 65.783059 -288.876633)
					(end 65.747138 -288.861754)
				)
				(arc
					(start 64.347598 -288.861754)
					(mid 64.311677 -288.876633)
					(end 64.296798 -288.912554)
				)
			)
		)
	)
	(zone
		(layers "In1.Cu" "In2.Cu")
		(hatch none 0.5)
		(connect_pads
			(clearance 0)
		)
		(min_thickness 0.25)
		(keepout
			(tracks not_allowed)
			(vias allowed)
			(pads allowed)
			(copperpour not_allowed)
			(footprints allowed)
		)
		(placement
			(enabled no)
			(sheetname "")
		)
		(fill yes
			(thermal_gap 0.5)
			(thermal_bridge_width 0.5)
			(island_removal_mode 0)
		)
		(polygon
			(pts
				(arc
					(start 443.721998 -251.07138)
					(mid 443.736877 -251.107301)
					(end 443.772798 -251.12218)
				)
				(arc
					(start 445.172338 -251.12218)
					(mid 445.208259 -251.107301)
					(end 445.223138 -251.07138)
				)
				(arc
					(start 445.223138 -250.66244)
					(mid 445.208259 -250.626519)
					(end 445.172338 -250.61164)
				)
				(arc
					(start 443.772798 -250.61164)
					(mid 443.736877 -250.626519)
					(end 443.721998 -250.66244)
				)
			)
		)
	)
	(zone
		(layers "In1.Cu" "In2.Cu")
		(hatch none 0.5)
		(connect_pads
			(clearance 0)
		)
		(min_thickness 0.25)
		(keepout
			(tracks not_allowed)
			(vias allowed)
			(pads allowed)
			(copperpour not_allowed)
			(footprints allowed)
		)
		(placement
			(enabled no)
			(sheetname "")
		)
		(fill yes
			(thermal_gap 0.5)
			(thermal_bridge_width 0.5)
			(island_removal_mode 0)
		)
		(polygon
			(pts
				(arc
					(start 300.592998 -217.071448)
					(mid 300.607877 -217.107369)
					(end 300.643798 -217.122248)
				)
				(arc
					(start 302.043338 -217.122248)
					(mid 302.079259 -217.107369)
					(end 302.094138 -217.071448)
				)
				(arc
					(start 302.094138 -216.662508)
					(mid 302.079259 -216.626587)
					(end 302.043338 -216.611708)
				)
				(arc
					(start 300.643798 -216.611708)
					(mid 300.607877 -216.626587)
					(end 300.592998 -216.662508)
				)
			)
		)
	)
	(zone
		(layers "In1.Cu" "In2.Cu")
		(hatch none 0.5)
		(connect_pads
			(clearance 0)
		)
		(min_thickness 0.25)
		(keepout
			(tracks not_allowed)
			(vias allowed)
			(pads allowed)
			(copperpour not_allowed)
			(footprints allowed)
		)
		(placement
			(enabled no)
			(sheetname "")
		)
		(fill yes
			(thermal_gap 0.5)
			(thermal_bridge_width 0.5)
			(island_removal_mode 0)
		)
		(polygon
			(pts
				(arc
					(start 428.634398 -204.32141)
					(mid 428.649277 -204.357331)
					(end 428.685198 -204.37221)
				)
				(arc
					(start 430.084738 -204.37221)
					(mid 430.120659 -204.357331)
					(end 430.135538 -204.32141)
				)
				(arc
					(start 430.135538 -203.91247)
					(mid 430.120659 -203.876549)
					(end 430.084738 -203.86167)
				)
				(arc
					(start 428.685198 -203.86167)
					(mid 428.649277 -203.876549)
					(end 428.634398 -203.91247)
				)
			)
		)
	)
	(zone
		(layers "In1.Cu" "In2.Cu")
		(hatch none 0.5)
		(connect_pads
			(clearance 0)
		)
		(min_thickness 0.25)
		(keepout
			(tracks not_allowed)
			(vias allowed)
			(pads allowed)
			(copperpour not_allowed)
			(footprints allowed)
		)
		(placement
			(enabled no)
			(sheetname "")
		)
		(fill yes
			(thermal_gap 0.5)
			(thermal_bridge_width 0.5)
			(island_removal_mode 0)
		)
		(polygon
			(pts
				(arc
					(start 7.39013 -282.521406)
					(mid 7.405009 -282.557327)
					(end 7.44093 -282.572206)
				)
				(arc
					(start 8.84047 -282.572206)
					(mid 8.876391 -282.557327)
					(end 8.89127 -282.521406)
				)
				(arc
					(start 8.89127 -282.112466)
					(mid 8.876391 -282.076545)
					(end 8.84047 -282.061666)
				)
				(arc
					(start 7.44093 -282.061666)
					(mid 7.405009 -282.076545)
					(end 7.39013 -282.112466)
				)
			)
		)
	)
	(zone
		(layers "In1.Cu" "In2.Cu")
		(hatch none 0.5)
		(connect_pads
			(clearance 0)
		)
		(min_thickness 0.25)
		(keepout
			(tracks not_allowed)
			(vias allowed)
			(pads allowed)
			(copperpour not_allowed)
			(footprints allowed)
		)
		(placement
			(enabled no)
			(sheetname "")
		)
		(fill yes
			(thermal_gap 0.5)
			(thermal_bridge_width 0.5)
			(island_removal_mode 0)
		)
		(polygon
			(pts
				(arc
					(start 169.706798 -262.121396)
					(mid 169.721677 -262.157317)
					(end 169.757598 -262.172196)
				)
				(arc
					(start 171.157138 -262.172196)
					(mid 171.193059 -262.157317)
					(end 171.207938 -262.121396)
				)
				(arc
					(start 171.207938 -261.712456)
					(mid 171.193059 -261.676535)
					(end 171.157138 -261.661656)
				)
				(arc
					(start 169.757598 -261.661656)
					(mid 169.721677 -261.676535)
					(end 169.706798 -261.712456)
				)
			)
		)
	)
	(zone
		(layers "In1.Cu" "In2.Cu")
		(hatch none 0.5)
		(connect_pads
			(clearance 0)
		)
		(min_thickness 0.25)
		(keepout
			(tracks not_allowed)
			(vias allowed)
			(pads allowed)
			(copperpour not_allowed)
			(footprints allowed)
		)
		(placement
			(enabled no)
			(sheetname "")
		)
		(fill yes
			(thermal_gap 0.5)
			(thermal_bridge_width 0.5)
			(island_removal_mode 0)
		)
		(polygon
			(pts
				(arc
					(start 266.974066 -315.671454)
					(mid 266.988945 -315.707375)
					(end 267.024866 -315.722254)
				)
				(arc
					(start 268.424406 -315.722254)
					(mid 268.460327 -315.707375)
					(end 268.475206 -315.671454)
				)
				(arc
					(start 268.475206 -315.262514)
					(mid 268.460327 -315.226593)
					(end 268.424406 -315.211714)
				)
				(arc
					(start 267.024866 -315.211714)
					(mid 266.988945 -315.226593)
					(end 266.974066 -315.262514)
				)
			)
		)
	)
	(zone
		(layers "In1.Cu" "In2.Cu")
		(hatch none 0.5)
		(connect_pads
			(clearance 0)
		)
		(min_thickness 0.25)
		(keepout
			(tracks not_allowed)
			(vias allowed)
			(pads allowed)
			(copperpour not_allowed)
			(footprints allowed)
		)
		(placement
			(enabled no)
			(sheetname "")
		)
		(fill yes
			(thermal_gap 0.5)
			(thermal_bridge_width 0.5)
			(island_removal_mode 0)
		)
		(polygon
			(pts
				(arc
					(start 255.330198 -196.671438)
					(mid 255.345077 -196.707359)
					(end 255.380998 -196.722238)
				)
				(arc
					(start 256.780538 -196.722238)
					(mid 256.816459 -196.707359)
					(end 256.831338 -196.671438)
				)
				(arc
					(start 256.831338 -196.262498)
					(mid 256.816459 -196.226577)
					(end 256.780538 -196.211698)
				)
				(arc
					(start 255.380998 -196.211698)
					(mid 255.345077 -196.226577)
					(end 255.330198 -196.262498)
				)
			)
		)
	)
	(zone
		(layers "In1.Cu" "In2.Cu")
		(hatch none 0.5)
		(connect_pads
			(clearance 0)
		)
		(min_thickness 0.25)
		(keepout
			(tracks not_allowed)
			(vias allowed)
			(pads allowed)
			(copperpour not_allowed)
			(footprints allowed)
		)
		(placement
			(enabled no)
			(sheetname "")
		)
		(fill yes
			(thermal_gap 0.5)
			(thermal_bridge_width 0.5)
			(island_removal_mode 0)
		)
		(polygon
			(pts
				(arc
					(start 192.338198 -300.37151)
					(mid 192.353077 -300.407431)
					(end 192.388998 -300.42231)
				)
				(arc
					(start 193.788538 -300.42231)
					(mid 193.824459 -300.407431)
					(end 193.839338 -300.37151)
				)
				(arc
					(start 193.839338 -299.96257)
					(mid 193.824459 -299.926649)
					(end 193.788538 -299.91177)
				)
				(arc
					(start 192.388998 -299.91177)
					(mid 192.353077 -299.926649)
					(end 192.338198 -299.96257)
				)
			)
		)
	)
	(zone
		(layers "In1.Cu" "In2.Cu")
		(hatch none 0.5)
		(connect_pads
			(clearance 0)
		)
		(min_thickness 0.25)
		(keepout
			(tracks not_allowed)
			(vias allowed)
			(pads allowed)
			(copperpour not_allowed)
			(footprints allowed)
		)
		(placement
			(enabled no)
			(sheetname "")
		)
		(fill yes
			(thermal_gap 0.5)
			(thermal_bridge_width 0.5)
			(island_removal_mode 0)
		)
		(polygon
			(pts
				(arc
					(start 413.546798 -293.571422)
					(mid 413.561677 -293.607343)
					(end 413.597598 -293.622222)
				)
				(arc
					(start 414.997138 -293.622222)
					(mid 415.033059 -293.607343)
					(end 415.047938 -293.571422)
				)
				(arc
					(start 415.047938 -293.162482)
					(mid 415.033059 -293.126561)
					(end 414.997138 -293.111682)
				)
				(arc
					(start 413.597598 -293.111682)
					(mid 413.561677 -293.126561)
					(end 413.546798 -293.162482)
				)
			)
		)
	)
	(zone
		(layers "In1.Cu" "In2.Cu")
		(hatch none 0.5)
		(connect_pads
			(clearance 0)
		)
		(min_thickness 0.25)
		(keepout
			(tracks not_allowed)
			(vias allowed)
			(pads allowed)
			(copperpour not_allowed)
			(footprints allowed)
		)
		(placement
			(enabled no)
			(sheetname "")
		)
		(fill yes
			(thermal_gap 0.5)
			(thermal_bridge_width 0.5)
			(island_removal_mode 0)
		)
		(polygon
			(pts
				(arc
					(start 34.121598 -251.921518)
					(mid 34.136477 -251.957439)
					(end 34.172398 -251.972318)
				)
				(arc
					(start 35.571938 -251.972318)
					(mid 35.607859 -251.957439)
					(end 35.622738 -251.921518)
				)
				(arc
					(start 35.622738 -251.512578)
					(mid 35.607859 -251.476657)
					(end 35.571938 -251.461778)
				)
				(arc
					(start 34.172398 -251.461778)
					(mid 34.136477 -251.476657)
					(end 34.121598 -251.512578)
				)
			)
		)
	)
	(zone
		(layers "In1.Cu" "In2.Cu")
		(hatch none 0.5)
		(connect_pads
			(clearance 0)
		)
		(min_thickness 0.25)
		(keepout
			(tracks not_allowed)
			(vias allowed)
			(pads allowed)
			(copperpour not_allowed)
			(footprints allowed)
		)
		(placement
			(enabled no)
			(sheetname "")
		)
		(fill yes
			(thermal_gap 0.5)
			(thermal_bridge_width 0.5)
			(island_removal_mode 0)
		)
		(polygon
			(pts
				(arc
					(start 192.338198 -279.9715)
					(mid 192.353077 -280.007421)
					(end 192.388998 -280.0223)
				)
				(arc
					(start 193.788538 -280.0223)
					(mid 193.824459 -280.007421)
					(end 193.839338 -279.9715)
				)
				(arc
					(start 193.839338 -279.56256)
					(mid 193.824459 -279.526639)
					(end 193.788538 -279.51176)
				)
				(arc
					(start 192.388998 -279.51176)
					(mid 192.353077 -279.526639)
					(end 192.338198 -279.56256)
				)
			)
		)
	)
	(zone
		(layers "In1.Cu" "In2.Cu")
		(hatch none 0.5)
		(connect_pads
			(clearance 0)
		)
		(min_thickness 0.25)
		(keepout
			(tracks not_allowed)
			(vias allowed)
			(pads allowed)
			(copperpour not_allowed)
			(footprints allowed)
		)
		(placement
			(enabled no)
			(sheetname "")
		)
		(fill yes
			(thermal_gap 0.5)
			(thermal_bridge_width 0.5)
			(island_removal_mode 0)
		)
		(polygon
			(pts
				(arc
					(start 289.605466 -300.37151)
					(mid 289.620345 -300.407431)
					(end 289.656266 -300.42231)
				)
				(arc
					(start 291.055806 -300.42231)
					(mid 291.091727 -300.407431)
					(end 291.106606 -300.37151)
				)
				(arc
					(start 291.106606 -299.96257)
					(mid 291.091727 -299.926649)
					(end 291.055806 -299.91177)
				)
				(arc
					(start 289.656266 -299.91177)
					(mid 289.620345 -299.926649)
					(end 289.605466 -299.96257)
				)
			)
		)
	)
	(zone
		(layers "In1.Cu" "In2.Cu")
		(hatch none 0.5)
		(connect_pads
			(clearance 0)
		)
		(min_thickness 0.25)
		(keepout
			(tracks not_allowed)
			(vias allowed)
			(pads allowed)
			(copperpour not_allowed)
			(footprints allowed)
		)
		(placement
			(enabled no)
			(sheetname "")
		)
		(fill yes
			(thermal_gap 0.5)
			(thermal_bridge_width 0.5)
			(island_removal_mode 0)
		)
		(polygon
			(pts
				(arc
					(start 417.646866 -250.221496)
					(mid 417.661745 -250.257417)
					(end 417.697666 -250.272296)
				)
				(arc
					(start 419.097206 -250.272296)
					(mid 419.133127 -250.257417)
					(end 419.148006 -250.221496)
				)
				(arc
					(start 419.148006 -249.812556)
					(mid 419.133127 -249.776635)
					(end 419.097206 -249.761756)
				)
				(arc
					(start 417.697666 -249.761756)
					(mid 417.661745 -249.776635)
					(end 417.646866 -249.812556)
				)
			)
		)
	)
	(zone
		(layers "In1.Cu" "In2.Cu")
		(hatch none 0.5)
		(connect_pads
			(clearance 0)
		)
		(min_thickness 0.25)
		(keepout
			(tracks not_allowed)
			(vias allowed)
			(pads allowed)
			(copperpour not_allowed)
			(footprints allowed)
		)
		(placement
			(enabled no)
			(sheetname "")
		)
		(fill yes
			(thermal_gap 0.5)
			(thermal_bridge_width 0.5)
			(island_removal_mode 0)
		)
		(polygon
			(pts
				(arc
					(start 192.338198 -270.621506)
					(mid 192.353077 -270.657427)
					(end 192.388998 -270.672306)
				)
				(arc
					(start 193.788538 -270.672306)
					(mid 193.824459 -270.657427)
					(end 193.839338 -270.621506)
				)
				(arc
					(start 193.839338 -270.212566)
					(mid 193.824459 -270.176645)
					(end 193.788538 -270.161766)
				)
				(arc
					(start 192.388998 -270.161766)
					(mid 192.353077 -270.176645)
					(end 192.338198 -270.212566)
				)
			)
		)
	)
	(zone
		(layers "In1.Cu" "In2.Cu")
		(hatch none 0.5)
		(connect_pads
			(clearance 0)
		)
		(min_thickness 0.25)
		(keepout
			(tracks not_allowed)
			(vias allowed)
			(pads allowed)
			(copperpour not_allowed)
			(footprints allowed)
		)
		(placement
			(enabled no)
			(sheetname "")
		)
		(fill yes
			(thermal_gap 0.5)
			(thermal_bridge_width 0.5)
			(island_removal_mode 0)
		)
		(polygon
			(pts
				(arc
					(start 255.330198 -218.77147)
					(mid 255.345077 -218.807391)
					(end 255.380998 -218.82227)
				)
				(arc
					(start 256.780538 -218.82227)
					(mid 256.816459 -218.807391)
					(end 256.831338 -218.77147)
				)
				(arc
					(start 256.831338 -218.36253)
					(mid 256.816459 -218.326609)
					(end 256.780538 -218.31173)
				)
				(arc
					(start 255.380998 -218.31173)
					(mid 255.345077 -218.326609)
					(end 255.330198 -218.36253)
				)
			)
		)
	)
	(zone
		(layers "In1.Cu" "In2.Cu")
		(hatch none 0.5)
		(connect_pads
			(clearance 0)
		)
		(min_thickness 0.25)
		(keepout
			(tracks not_allowed)
			(vias allowed)
			(pads allowed)
			(copperpour not_allowed)
			(footprints allowed)
		)
		(placement
			(enabled no)
			(sheetname "")
		)
		(fill yes
			(thermal_gap 0.5)
			(thermal_bridge_width 0.5)
			(island_removal_mode 0)
		)
		(polygon
			(pts
				(arc
					(start 406.002998 -249.371358)
					(mid 406.017877 -249.407279)
					(end 406.053798 -249.422158)
				)
				(arc
					(start 407.453338 -249.422158)
					(mid 407.489259 -249.407279)
					(end 407.504138 -249.371358)
				)
				(arc
					(start 407.504138 -248.962418)
					(mid 407.489259 -248.926497)
					(end 407.453338 -248.911618)
				)
				(arc
					(start 406.053798 -248.911618)
					(mid 406.017877 -248.926497)
					(end 406.002998 -248.962418)
				)
			)
		)
	)
	(zone
		(layers "In1.Cu" "In2.Cu")
		(hatch none 0.5)
		(connect_pads
			(clearance 0)
		)
		(min_thickness 0.25)
		(keepout
			(tracks not_allowed)
			(vias allowed)
			(pads allowed)
			(copperpour not_allowed)
			(footprints allowed)
		)
		(placement
			(enabled no)
			(sheetname "")
		)
		(fill yes
			(thermal_gap 0.5)
			(thermal_bridge_width 0.5)
			(island_removal_mode 0)
		)
		(polygon
			(pts
				(arc
					(start 162.162998 -268.921484)
					(mid 162.177877 -268.957405)
					(end 162.213798 -268.972284)
				)
				(arc
					(start 163.613338 -268.972284)
					(mid 163.649259 -268.957405)
					(end 163.664138 -268.921484)
				)
				(arc
					(start 163.664138 -268.512544)
					(mid 163.649259 -268.476623)
					(end 163.613338 -268.461744)
				)
				(arc
					(start 162.213798 -268.461744)
					(mid 162.177877 -268.476623)
					(end 162.162998 -268.512544)
				)
			)
		)
	)
	(zone
		(layers "In1.Cu" "In2.Cu")
		(hatch none 0.5)
		(connect_pads
			(clearance 0)
		)
		(min_thickness 0.25)
		(keepout
			(tracks not_allowed)
			(vias allowed)
			(pads allowed)
			(copperpour not_allowed)
			(footprints allowed)
		)
		(placement
			(enabled no)
			(sheetname "")
		)
		(fill yes
			(thermal_gap 0.5)
			(thermal_bridge_width 0.5)
			(island_removal_mode 0)
		)
		(polygon
			(pts
				(arc
					(start 277.961598 -312.27141)
					(mid 277.976477 -312.307331)
					(end 278.012398 -312.32221)
				)
				(arc
					(start 279.411938 -312.32221)
					(mid 279.447859 -312.307331)
					(end 279.462738 -312.27141)
				)
				(arc
					(start 279.462738 -311.86247)
					(mid 279.447859 -311.826549)
					(end 279.411938 -311.81167)
				)
				(arc
					(start 278.012398 -311.81167)
					(mid 277.976477 -311.826549)
					(end 277.961598 -311.86247)
				)
			)
		)
	)
	(zone
		(layers "In1.Cu" "In2.Cu")
		(hatch none 0.5)
		(connect_pads
			(clearance 0)
		)
		(min_thickness 0.25)
		(keepout
			(tracks not_allowed)
			(vias allowed)
			(pads allowed)
			(copperpour not_allowed)
			(footprints allowed)
		)
		(placement
			(enabled no)
			(sheetname "")
		)
		(fill yes
			(thermal_gap 0.5)
			(thermal_bridge_width 0.5)
			(island_removal_mode 0)
		)
		(polygon
			(pts
				(arc
					(start 297.149266 -281.671522)
					(mid 297.164145 -281.707443)
					(end 297.200066 -281.722322)
				)
				(arc
					(start 298.599606 -281.722322)
					(mid 298.635527 -281.707443)
					(end 298.650406 -281.671522)
				)
				(arc
					(start 298.650406 -281.262582)
					(mid 298.635527 -281.226661)
					(end 298.599606 -281.211782)
				)
				(arc
					(start 297.200066 -281.211782)
					(mid 297.164145 -281.226661)
					(end 297.149266 -281.262582)
				)
			)
		)
	)
	(zone
		(layers "In1.Cu" "In2.Cu")
		(hatch none 0.5)
		(connect_pads
			(clearance 0)
		)
		(min_thickness 0.25)
		(keepout
			(tracks not_allowed)
			(vias allowed)
			(pads allowed)
			(copperpour not_allowed)
			(footprints allowed)
		)
		(placement
			(enabled no)
			(sheetname "")
		)
		(fill yes
			(thermal_gap 0.5)
			(thermal_bridge_width 0.5)
			(island_removal_mode 0)
		)
		(polygon
			(pts
				(arc
					(start 297.149266 -201.771504)
					(mid 297.164145 -201.807425)
					(end 297.200066 -201.822304)
				)
				(arc
					(start 298.599606 -201.822304)
					(mid 298.635527 -201.807425)
					(end 298.650406 -201.771504)
				)
				(arc
					(start 298.650406 -201.362564)
					(mid 298.635527 -201.326643)
					(end 298.599606 -201.311764)
				)
				(arc
					(start 297.200066 -201.311764)
					(mid 297.164145 -201.326643)
					(end 297.149266 -201.362564)
				)
			)
		)
	)
	(zone
		(layers "In1.Cu" "In2.Cu")
		(hatch none 0.5)
		(connect_pads
			(clearance 0)
		)
		(min_thickness 0.25)
		(keepout
			(tracks not_allowed)
			(vias allowed)
			(pads allowed)
			(copperpour not_allowed)
			(footprints allowed)
		)
		(placement
			(enabled no)
			(sheetname "")
		)
		(fill yes
			(thermal_gap 0.5)
			(thermal_bridge_width 0.5)
			(island_removal_mode 0)
		)
		(polygon
			(pts
				(arc
					(start 451.265798 -200.071482)
					(mid 451.280677 -200.107403)
					(end 451.316598 -200.122282)
				)
				(arc
					(start 452.716138 -200.122282)
					(mid 452.752059 -200.107403)
					(end 452.766938 -200.071482)
				)
				(arc
					(start 452.766938 -199.662542)
					(mid 452.752059 -199.626621)
					(end 452.716138 -199.611742)
				)
				(arc
					(start 451.316598 -199.611742)
					(mid 451.280677 -199.626621)
					(end 451.265798 -199.662542)
				)
			)
		)
	)
	(zone
		(layers "In1.Cu" "In2.Cu")
		(hatch none 0.5)
		(connect_pads
			(clearance 0)
		)
		(min_thickness 0.25)
		(keepout
			(tracks not_allowed)
			(vias allowed)
			(pads allowed)
			(copperpour not_allowed)
			(footprints allowed)
		)
		(placement
			(enabled no)
			(sheetname "")
		)
		(fill yes
			(thermal_gap 0.5)
			(thermal_bridge_width 0.5)
			(island_removal_mode 0)
		)
		(polygon
			(pts
				(arc
					(start 274.517866 -229.821486)
					(mid 274.532745 -229.857407)
					(end 274.568666 -229.872286)
				)
				(arc
					(start 275.968206 -229.872286)
					(mid 276.004127 -229.857407)
					(end 276.019006 -229.821486)
				)
				(arc
					(start 276.019006 -229.412546)
					(mid 276.004127 -229.376625)
					(end 275.968206 -229.361746)
				)
				(arc
					(start 274.568666 -229.361746)
					(mid 274.532745 -229.376625)
					(end 274.517866 -229.412546)
				)
			)
		)
	)
	(zone
		(layers "In1.Cu" "In2.Cu")
		(hatch none 0.5)
		(connect_pads
			(clearance 0)
		)
		(min_thickness 0.25)
		(keepout
			(tracks not_allowed)
			(vias allowed)
			(pads allowed)
			(copperpour not_allowed)
			(footprints allowed)
		)
		(placement
			(enabled no)
			(sheetname "")
		)
		(fill yes
			(thermal_gap 0.5)
			(thermal_bridge_width 0.5)
			(island_removal_mode 0)
		)
		(polygon
			(pts
				(arc
					(start 22.47773 -293.571422)
					(mid 22.492609 -293.607343)
					(end 22.52853 -293.622222)
				)
				(arc
					(start 23.92807 -293.622222)
					(mid 23.963991 -293.607343)
					(end 23.97887 -293.571422)
				)
				(arc
					(start 23.97887 -293.162482)
					(mid 23.963991 -293.126561)
					(end 23.92807 -293.111682)
				)
				(arc
					(start 22.52853 -293.111682)
					(mid 22.492609 -293.126561)
					(end 22.47773 -293.162482)
				)
			)
		)
	)
	(zone
		(layers "In1.Cu" "In2.Cu")
		(hatch none 0.5)
		(connect_pads
			(clearance 0)
		)
		(min_thickness 0.25)
		(keepout
			(tracks not_allowed)
			(vias allowed)
			(pads allowed)
			(copperpour not_allowed)
			(footprints allowed)
		)
		(placement
			(enabled no)
			(sheetname "")
		)
		(fill yes
			(thermal_gap 0.5)
			(thermal_bridge_width 0.5)
			(island_removal_mode 0)
		)
		(polygon
			(pts
				(arc
					(start 451.265798 -210.27136)
					(mid 451.280677 -210.307281)
					(end 451.316598 -210.32216)
				)
				(arc
					(start 452.716138 -210.32216)
					(mid 452.752059 -210.307281)
					(end 452.766938 -210.27136)
				)
				(arc
					(start 452.766938 -209.86242)
					(mid 452.752059 -209.826499)
					(end 452.716138 -209.81162)
				)
				(arc
					(start 451.316598 -209.81162)
					(mid 451.280677 -209.826499)
					(end 451.265798 -209.86242)
				)
			)
		)
	)
	(zone
		(layers "In1.Cu" "In2.Cu")
		(hatch none 0.5)
		(connect_pads
			(clearance 0)
		)
		(min_thickness 0.25)
		(keepout
			(tracks not_allowed)
			(vias allowed)
			(pads allowed)
			(copperpour not_allowed)
			(footprints allowed)
		)
		(placement
			(enabled no)
			(sheetname "")
		)
		(fill yes
			(thermal_gap 0.5)
			(thermal_bridge_width 0.5)
			(island_removal_mode 0)
		)
		(polygon
			(pts
				(arc
					(start 270.417798 -313.121294)
					(mid 270.432677 -313.157215)
					(end 270.468598 -313.172094)
				)
				(arc
					(start 271.868138 -313.172094)
					(mid 271.904059 -313.157215)
					(end 271.918938 -313.121294)
				)
				(arc
					(start 271.918938 -312.712354)
					(mid 271.904059 -312.676433)
					(end 271.868138 -312.661554)
				)
				(arc
					(start 270.468598 -312.661554)
					(mid 270.432677 -312.676433)
					(end 270.417798 -312.712354)
				)
			)
		)
	)
	(zone
		(layers "In1.Cu" "In2.Cu")
		(hatch none 0.5)
		(connect_pads
			(clearance 0)
		)
		(min_thickness 0.25)
		(keepout
			(tracks not_allowed)
			(vias allowed)
			(pads allowed)
			(copperpour not_allowed)
			(footprints allowed)
		)
		(placement
			(enabled no)
			(sheetname "")
		)
		(fill yes
			(thermal_gap 0.5)
			(thermal_bridge_width 0.5)
			(island_removal_mode 0)
		)
		(polygon
			(pts
				(arc
					(start 447.822066 -267.221462)
					(mid 447.836945 -267.257383)
					(end 447.872866 -267.272262)
				)
				(arc
					(start 449.272406 -267.272262)
					(mid 449.308327 -267.257383)
					(end 449.323206 -267.221462)
				)
				(arc
					(start 449.323206 -266.812522)
					(mid 449.308327 -266.776601)
					(end 449.272406 -266.761722)
				)
				(arc
					(start 447.872866 -266.761722)
					(mid 447.836945 -266.776601)
					(end 447.822066 -266.812522)
				)
			)
		)
	)
	(zone
		(layers "In1.Cu" "In2.Cu")
		(hatch none 0.5)
		(connect_pads
			(clearance 0)
		)
		(min_thickness 0.25)
		(keepout
			(tracks not_allowed)
			(vias allowed)
			(pads allowed)
			(copperpour not_allowed)
			(footprints allowed)
		)
		(placement
			(enabled no)
			(sheetname "")
		)
		(fill yes
			(thermal_gap 0.5)
			(thermal_bridge_width 0.5)
			(island_removal_mode 0)
		)
		(polygon
			(pts
				(arc
					(start 210.86953 -245.971314)
					(mid 210.884409 -246.007235)
					(end 210.92033 -246.022114)
				)
				(arc
					(start 212.31987 -246.022114)
					(mid 212.355791 -246.007235)
					(end 212.37067 -245.971314)
				)
				(arc
					(start 212.37067 -245.562374)
					(mid 212.355791 -245.526453)
					(end 212.31987 -245.511574)
				)
				(arc
					(start 210.92033 -245.511574)
					(mid 210.884409 -245.526453)
					(end 210.86953 -245.562374)
				)
			)
		)
	)
	(zone
		(layers "In1.Cu" "In2.Cu")
		(hatch none 0.5)
		(connect_pads
			(clearance 0)
		)
		(min_thickness 0.25)
		(keepout
			(tracks not_allowed)
			(vias allowed)
			(pads allowed)
			(copperpour not_allowed)
			(footprints allowed)
		)
		(placement
			(enabled no)
			(sheetname "")
		)
		(fill yes
			(thermal_gap 0.5)
			(thermal_bridge_width 0.5)
			(island_removal_mode 0)
		)
		(polygon
			(pts
				(arc
					(start 45.10913 -204.32141)
					(mid 45.124009 -204.357331)
					(end 45.15993 -204.37221)
				)
				(arc
					(start 46.55947 -204.37221)
					(mid 46.595391 -204.357331)
					(end 46.61027 -204.32141)
				)
				(arc
					(start 46.61027 -203.91247)
					(mid 46.595391 -203.876549)
					(end 46.55947 -203.86167)
				)
				(arc
					(start 45.15993 -203.86167)
					(mid 45.124009 -203.876549)
					(end 45.10913 -203.91247)
				)
			)
		)
	)
	(zone
		(layers "In1.Cu" "In2.Cu")
		(hatch none 0.5)
		(connect_pads
			(clearance 0)
		)
		(min_thickness 0.25)
		(keepout
			(tracks not_allowed)
			(vias allowed)
			(pads allowed)
			(copperpour not_allowed)
			(footprints allowed)
		)
		(placement
			(enabled no)
			(sheetname "")
		)
		(fill yes
			(thermal_gap 0.5)
			(thermal_bridge_width 0.5)
			(island_removal_mode 0)
		)
		(polygon
			(pts
				(arc
					(start 49.209198 -283.371544)
					(mid 49.224077 -283.407465)
					(end 49.259998 -283.422344)
				)
				(arc
					(start 50.659538 -283.422344)
					(mid 50.695459 -283.407465)
					(end 50.710338 -283.371544)
				)
				(arc
					(start 50.710338 -282.962604)
					(mid 50.695459 -282.926683)
					(end 50.659538 -282.911804)
				)
				(arc
					(start 49.259998 -282.911804)
					(mid 49.224077 -282.926683)
					(end 49.209198 -282.962604)
				)
			)
		)
	)
	(zone
		(layers "In1.Cu" "In2.Cu")
		(hatch none 0.5)
		(connect_pads
			(clearance 0)
		)
		(min_thickness 0.25)
		(keepout
			(tracks not_allowed)
			(vias allowed)
			(pads allowed)
			(copperpour not_allowed)
			(footprints allowed)
		)
		(placement
			(enabled no)
			(sheetname "")
		)
		(fill yes
			(thermal_gap 0.5)
			(thermal_bridge_width 0.5)
			(island_removal_mode 0)
		)
		(polygon
			(pts
				(arc
					(start 462.909666 -298.671488)
					(mid 462.924545 -298.707409)
					(end 462.960466 -298.722288)
				)
				(arc
					(start 464.360006 -298.722288)
					(mid 464.395927 -298.707409)
					(end 464.410806 -298.671488)
				)
				(arc
					(start 464.410806 -298.262548)
					(mid 464.395927 -298.226627)
					(end 464.360006 -298.211748)
				)
				(arc
					(start 462.960466 -298.211748)
					(mid 462.924545 -298.226627)
					(end 462.909666 -298.262548)
				)
			)
		)
	)
	(zone
		(layers "In1.Cu" "In2.Cu")
		(hatch none 0.5)
		(connect_pads
			(clearance 0)
		)
		(min_thickness 0.25)
		(keepout
			(tracks not_allowed)
			(vias allowed)
			(pads allowed)
			(copperpour not_allowed)
			(footprints allowed)
		)
		(placement
			(enabled no)
			(sheetname "")
		)
		(fill yes
			(thermal_gap 0.5)
			(thermal_bridge_width 0.5)
			(island_removal_mode 0)
		)
		(polygon
			(pts
				(arc
					(start 45.10913 -275.721318)
					(mid 45.124009 -275.757239)
					(end 45.15993 -275.772118)
				)
				(arc
					(start 46.55947 -275.772118)
					(mid 46.595391 -275.757239)
					(end 46.61027 -275.721318)
				)
				(arc
					(start 46.61027 -275.312378)
					(mid 46.595391 -275.276457)
					(end 46.55947 -275.261578)
				)
				(arc
					(start 45.15993 -275.261578)
					(mid 45.124009 -275.276457)
					(end 45.10913 -275.312378)
				)
			)
		)
	)
	(zone
		(layers "In1.Cu" "In2.Cu")
		(hatch none 0.5)
		(connect_pads
			(clearance 0)
		)
		(min_thickness 0.25)
		(keepout
			(tracks not_allowed)
			(vias allowed)
			(pads allowed)
			(copperpour not_allowed)
			(footprints allowed)
		)
		(placement
			(enabled no)
			(sheetname "")
		)
		(fill yes
			(thermal_gap 0.5)
			(thermal_bridge_width 0.5)
			(island_removal_mode 0)
		)
		(polygon
			(pts
				(arc
					(start 297.149266 -259.57149)
					(mid 297.164145 -259.607411)
					(end 297.200066 -259.62229)
				)
				(arc
					(start 298.599606 -259.62229)
					(mid 298.635527 -259.607411)
					(end 298.650406 -259.57149)
				)
				(arc
					(start 298.650406 -259.16255)
					(mid 298.635527 -259.126629)
					(end 298.599606 -259.11175)
				)
				(arc
					(start 297.200066 -259.11175)
					(mid 297.164145 -259.126629)
					(end 297.149266 -259.16255)
				)
			)
		)
	)
	(zone
		(layers "In1.Cu" "In2.Cu")
		(hatch none 0.5)
		(connect_pads
			(clearance 0)
		)
		(min_thickness 0.25)
		(keepout
			(tracks not_allowed)
			(vias allowed)
			(pads allowed)
			(copperpour not_allowed)
			(footprints allowed)
		)
		(placement
			(enabled no)
			(sheetname "")
		)
		(fill yes
			(thermal_gap 0.5)
			(thermal_bridge_width 0.5)
			(island_removal_mode 0)
		)
		(polygon
			(pts
				(arc
					(start 451.265798 -228.121464)
					(mid 451.280677 -228.157385)
					(end 451.316598 -228.172264)
				)
				(arc
					(start 452.716138 -228.172264)
					(mid 452.752059 -228.157385)
					(end 452.766938 -228.121464)
				)
				(arc
					(start 452.766938 -227.712524)
					(mid 452.752059 -227.676603)
					(end 452.716138 -227.661724)
				)
				(arc
					(start 451.316598 -227.661724)
					(mid 451.280677 -227.676603)
					(end 451.265798 -227.712524)
				)
			)
		)
	)
	(zone
		(layers "In1.Cu" "In2.Cu")
		(hatch none 0.5)
		(connect_pads
			(clearance 0)
		)
		(min_thickness 0.25)
		(keepout
			(tracks not_allowed)
			(vias allowed)
			(pads allowed)
			(copperpour not_allowed)
			(footprints allowed)
		)
		(placement
			(enabled no)
			(sheetname "")
		)
		(fill yes
			(thermal_gap 0.5)
			(thermal_bridge_width 0.5)
			(island_removal_mode 0)
		)
		(polygon
			(pts
				(arc
					(start 440.278266 -259.57149)
					(mid 440.293145 -259.607411)
					(end 440.329066 -259.62229)
				)
				(arc
					(start 441.728606 -259.62229)
					(mid 441.764527 -259.607411)
					(end 441.779406 -259.57149)
				)
				(arc
					(start 441.779406 -259.16255)
					(mid 441.764527 -259.126629)
					(end 441.728606 -259.11175)
				)
				(arc
					(start 440.329066 -259.11175)
					(mid 440.293145 -259.126629)
					(end 440.278266 -259.16255)
				)
			)
		)
	)
	(zone
		(layers "In1.Cu" "In2.Cu")
		(hatch none 0.5)
		(connect_pads
			(clearance 0)
		)
		(min_thickness 0.25)
		(keepout
			(tracks not_allowed)
			(vias allowed)
			(pads allowed)
			(copperpour not_allowed)
			(footprints allowed)
		)
		(placement
			(enabled no)
			(sheetname "")
		)
		(fill yes
			(thermal_gap 0.5)
			(thermal_bridge_width 0.5)
			(island_removal_mode 0)
		)
		(polygon
			(pts
				(arc
					(start 37.56533 -240.021364)
					(mid 37.580209 -240.057285)
					(end 37.61613 -240.072164)
				)
				(arc
					(start 39.01567 -240.072164)
					(mid 39.051591 -240.057285)
					(end 39.06647 -240.021364)
				)
				(arc
					(start 39.06647 -239.612424)
					(mid 39.051591 -239.576503)
					(end 39.01567 -239.561624)
				)
				(arc
					(start 37.61613 -239.561624)
					(mid 37.580209 -239.576503)
					(end 37.56533 -239.612424)
				)
			)
		)
	)
	(zone
		(layers "In1.Cu" "In2.Cu")
		(hatch none 0.5)
		(connect_pads
			(clearance 0)
		)
		(min_thickness 0.25)
		(keepout
			(tracks not_allowed)
			(vias allowed)
			(pads allowed)
			(copperpour not_allowed)
			(footprints allowed)
		)
		(placement
			(enabled no)
			(sheetname "")
		)
		(fill yes
			(thermal_gap 0.5)
			(thermal_bridge_width 0.5)
			(island_removal_mode 0)
		)
		(polygon
			(pts
				(arc
					(start 259.430266 -291.021516)
					(mid 259.445145 -291.057437)
					(end 259.481066 -291.072316)
				)
				(arc
					(start 260.880606 -291.072316)
					(mid 260.916527 -291.057437)
					(end 260.931406 -291.021516)
				)
				(arc
					(start 260.931406 -290.612576)
					(mid 260.916527 -290.576655)
					(end 260.880606 -290.561776)
				)
				(arc
					(start 259.481066 -290.561776)
					(mid 259.445145 -290.576655)
					(end 259.430266 -290.612576)
				)
			)
		)
	)
	(zone
		(layers "In1.Cu" "In2.Cu")
		(hatch none 0.5)
		(connect_pads
			(clearance 0)
		)
		(min_thickness 0.25)
		(keepout
			(tracks not_allowed)
			(vias allowed)
			(pads allowed)
			(copperpour not_allowed)
			(footprints allowed)
		)
		(placement
			(enabled no)
			(sheetname "")
		)
		(fill yes
			(thermal_gap 0.5)
			(thermal_bridge_width 0.5)
			(island_removal_mode 0)
		)
		(polygon
			(pts
				(arc
					(start 210.86953 -293.571422)
					(mid 210.884409 -293.607343)
					(end 210.92033 -293.622222)
				)
				(arc
					(start 212.31987 -293.622222)
					(mid 212.355791 -293.607343)
					(end 212.37067 -293.571422)
				)
				(arc
					(start 212.37067 -293.162482)
					(mid 212.355791 -293.126561)
					(end 212.31987 -293.111682)
				)
				(arc
					(start 210.92033 -293.111682)
					(mid 210.884409 -293.126561)
					(end 210.86953 -293.162482)
				)
			)
		)
	)
	(zone
		(layers "In1.Cu" "In2.Cu")
		(hatch none 0.5)
		(connect_pads
			(clearance 0)
		)
		(min_thickness 0.25)
		(keepout
			(tracks not_allowed)
			(vias allowed)
			(pads allowed)
			(copperpour not_allowed)
			(footprints allowed)
		)
		(placement
			(enabled no)
			(sheetname "")
		)
		(fill yes
			(thermal_gap 0.5)
			(thermal_bridge_width 0.5)
			(island_removal_mode 0)
		)
		(polygon
			(pts
				(arc
					(start 262.873998 -235.771436)
					(mid 262.888877 -235.807357)
					(end 262.924798 -235.822236)
				)
				(arc
					(start 264.324338 -235.822236)
					(mid 264.360259 -235.807357)
					(end 264.375138 -235.771436)
				)
				(arc
					(start 264.375138 -235.362496)
					(mid 264.360259 -235.326575)
					(end 264.324338 -235.311696)
				)
				(arc
					(start 262.924798 -235.311696)
					(mid 262.888877 -235.326575)
					(end 262.873998 -235.362496)
				)
			)
		)
	)
	(zone
		(layers "In1.Cu" "In2.Cu")
		(hatch none 0.5)
		(connect_pads
			(clearance 0)
		)
		(min_thickness 0.25)
		(keepout
			(tracks not_allowed)
			(vias allowed)
			(pads allowed)
			(copperpour not_allowed)
			(footprints allowed)
		)
		(placement
			(enabled no)
			(sheetname "")
		)
		(fill yes
			(thermal_gap 0.5)
			(thermal_bridge_width 0.5)
			(island_removal_mode 0)
		)
		(polygon
			(pts
				(arc
					(start 165.60673 -224.72142)
					(mid 165.621609 -224.757341)
					(end 165.65753 -224.77222)
				)
				(arc
					(start 167.05707 -224.77222)
					(mid 167.092991 -224.757341)
					(end 167.10787 -224.72142)
				)
				(arc
					(start 167.10787 -224.31248)
					(mid 167.092991 -224.276559)
					(end 167.05707 -224.26168)
				)
				(arc
					(start 165.65753 -224.26168)
					(mid 165.621609 -224.276559)
					(end 165.60673 -224.31248)
				)
			)
		)
	)
	(zone
		(layers "In1.Cu" "In2.Cu")
		(hatch none 0.5)
		(connect_pads
			(clearance 0)
		)
		(min_thickness 0.25)
		(keepout
			(tracks not_allowed)
			(vias allowed)
			(pads allowed)
			(copperpour not_allowed)
			(footprints allowed)
		)
		(placement
			(enabled no)
			(sheetname "")
		)
		(fill yes
			(thermal_gap 0.5)
			(thermal_bridge_width 0.5)
			(island_removal_mode 0)
		)
		(polygon
			(pts
				(arc
					(start 417.646866 -216.22131)
					(mid 417.661745 -216.257231)
					(end 417.697666 -216.27211)
				)
				(arc
					(start 419.097206 -216.27211)
					(mid 419.133127 -216.257231)
					(end 419.148006 -216.22131)
				)
				(arc
					(start 419.148006 -215.81237)
					(mid 419.133127 -215.776449)
					(end 419.097206 -215.76157)
				)
				(arc
					(start 417.697666 -215.76157)
					(mid 417.661745 -215.776449)
					(end 417.646866 -215.81237)
				)
			)
		)
	)
	(zone
		(layers "In1.Cu" "In2.Cu")
		(hatch none 0.5)
		(connect_pads
			(clearance 0)
		)
		(min_thickness 0.25)
		(keepout
			(tracks not_allowed)
			(vias allowed)
			(pads allowed)
			(copperpour not_allowed)
			(footprints allowed)
		)
		(placement
			(enabled no)
			(sheetname "")
		)
		(fill yes
			(thermal_gap 0.5)
			(thermal_bridge_width 0.5)
			(island_removal_mode 0)
		)
		(polygon
			(pts
				(arc
					(start 19.033998 -306.32146)
					(mid 19.048877 -306.357381)
					(end 19.084798 -306.37226)
				)
				(arc
					(start 20.484338 -306.37226)
					(mid 20.520259 -306.357381)
					(end 20.535138 -306.32146)
				)
				(arc
					(start 20.535138 -305.91252)
					(mid 20.520259 -305.876599)
					(end 20.484338 -305.86172)
				)
				(arc
					(start 19.084798 -305.86172)
					(mid 19.048877 -305.876599)
					(end 19.033998 -305.91252)
				)
			)
		)
	)
	(zone
		(layers "In1.Cu" "In2.Cu")
		(hatch none 0.5)
		(connect_pads
			(clearance 0)
		)
		(min_thickness 0.25)
		(keepout
			(tracks not_allowed)
			(vias allowed)
			(pads allowed)
			(copperpour not_allowed)
			(footprints allowed)
		)
		(placement
			(enabled no)
			(sheetname "")
		)
		(fill yes
			(thermal_gap 0.5)
			(thermal_bridge_width 0.5)
			(island_removal_mode 0)
		)
		(polygon
			(pts
				(arc
					(start 199.881998 -217.921332)
					(mid 199.896877 -217.957253)
					(end 199.932798 -217.972132)
				)
				(arc
					(start 201.332338 -217.972132)
					(mid 201.368259 -217.957253)
					(end 201.383138 -217.921332)
				)
				(arc
					(start 201.383138 -217.512392)
					(mid 201.368259 -217.476471)
					(end 201.332338 -217.461592)
				)
				(arc
					(start 199.932798 -217.461592)
					(mid 199.896877 -217.476471)
					(end 199.881998 -217.512392)
				)
			)
		)
	)
	(zone
		(layers "In1.Cu" "In2.Cu")
		(hatch none 0.5)
		(connect_pads
			(clearance 0)
		)
		(min_thickness 0.25)
		(keepout
			(tracks not_allowed)
			(vias allowed)
			(pads allowed)
			(copperpour not_allowed)
			(footprints allowed)
		)
		(placement
			(enabled no)
			(sheetname "")
		)
		(fill yes
			(thermal_gap 0.5)
			(thermal_bridge_width 0.5)
			(island_removal_mode 0)
		)
		(polygon
			(pts
				(arc
					(start 428.634398 -308.871366)
					(mid 428.649277 -308.907287)
					(end 428.685198 -308.922166)
				)
				(arc
					(start 430.084738 -308.922166)
					(mid 430.120659 -308.907287)
					(end 430.135538 -308.871366)
				)
				(arc
					(start 430.135538 -308.462426)
					(mid 430.120659 -308.426505)
					(end 430.084738 -308.411626)
				)
				(arc
					(start 428.685198 -308.411626)
					(mid 428.649277 -308.426505)
					(end 428.634398 -308.462426)
				)
			)
		)
	)
	(zone
		(layers "In1.Cu" "In2.Cu")
		(hatch none 0.5)
		(connect_pads
			(clearance 0)
		)
		(min_thickness 0.25)
		(keepout
			(tracks not_allowed)
			(vias allowed)
			(pads allowed)
			(copperpour not_allowed)
			(footprints allowed)
		)
		(placement
			(enabled no)
			(sheetname "")
		)
		(fill yes
			(thermal_gap 0.5)
			(thermal_bridge_width 0.5)
			(island_removal_mode 0)
		)
		(polygon
			(pts
				(arc
					(start 203.32573 -296.121328)
					(mid 203.340609 -296.157249)
					(end 203.37653 -296.172128)
				)
				(arc
					(start 204.77607 -296.172128)
					(mid 204.811991 -296.157249)
					(end 204.82687 -296.121328)
				)
				(arc
					(start 204.82687 -295.712388)
					(mid 204.811991 -295.676467)
					(end 204.77607 -295.661588)
				)
				(arc
					(start 203.37653 -295.661588)
					(mid 203.340609 -295.676467)
					(end 203.32573 -295.712388)
				)
			)
		)
	)
	(zone
		(layers "In1.Cu" "In2.Cu")
		(hatch none 0.5)
		(connect_pads
			(clearance 0)
		)
		(min_thickness 0.25)
		(keepout
			(tracks not_allowed)
			(vias allowed)
			(pads allowed)
			(copperpour not_allowed)
			(footprints allowed)
		)
		(placement
			(enabled no)
			(sheetname "")
		)
		(fill yes
			(thermal_gap 0.5)
			(thermal_bridge_width 0.5)
			(island_removal_mode 0)
		)
		(polygon
			(pts
				(arc
					(start 7.39013 -284.221428)
					(mid 7.405009 -284.257349)
					(end 7.44093 -284.272228)
				)
				(arc
					(start 8.84047 -284.272228)
					(mid 8.876391 -284.257349)
					(end 8.89127 -284.221428)
				)
				(arc
					(start 8.89127 -283.812488)
					(mid 8.876391 -283.776567)
					(end 8.84047 -283.761688)
				)
				(arc
					(start 7.44093 -283.761688)
					(mid 7.405009 -283.776567)
					(end 7.39013 -283.812488)
				)
			)
		)
	)
	(zone
		(layers "In1.Cu" "In2.Cu")
		(hatch none 0.5)
		(connect_pads
			(clearance 0)
		)
		(min_thickness 0.25)
		(keepout
			(tracks not_allowed)
			(vias allowed)
			(pads allowed)
			(copperpour not_allowed)
			(footprints allowed)
		)
		(placement
			(enabled no)
			(sheetname "")
		)
		(fill yes
			(thermal_gap 0.5)
			(thermal_bridge_width 0.5)
			(island_removal_mode 0)
		)
		(polygon
			(pts
				(arc
					(start 60.19673 -224.72142)
					(mid 60.211609 -224.757341)
					(end 60.24753 -224.77222)
				)
				(arc
					(start 61.64707 -224.77222)
					(mid 61.682991 -224.757341)
					(end 61.69787 -224.72142)
				)
				(arc
					(start 61.69787 -224.31248)
					(mid 61.682991 -224.276559)
					(end 61.64707 -224.26168)
				)
				(arc
					(start 60.24753 -224.26168)
					(mid 60.211609 -224.276559)
					(end 60.19673 -224.31248)
				)
			)
		)
	)
	(zone
		(layers "In1.Cu" "In2.Cu")
		(hatch none 0.5)
		(connect_pads
			(clearance 0)
		)
		(min_thickness 0.25)
		(keepout
			(tracks not_allowed)
			(vias allowed)
			(pads allowed)
			(copperpour not_allowed)
			(footprints allowed)
		)
		(placement
			(enabled no)
			(sheetname "")
		)
		(fill yes
			(thermal_gap 0.5)
			(thermal_bridge_width 0.5)
			(island_removal_mode 0)
		)
		(polygon
			(pts
				(arc
					(start 52.65293 -251.07138)
					(mid 52.667809 -251.107301)
					(end 52.70373 -251.12218)
				)
				(arc
					(start 54.10327 -251.12218)
					(mid 54.139191 -251.107301)
					(end 54.15407 -251.07138)
				)
				(arc
					(start 54.15407 -250.66244)
					(mid 54.139191 -250.626519)
					(end 54.10327 -250.61164)
				)
				(arc
					(start 52.70373 -250.61164)
					(mid 52.667809 -250.626519)
					(end 52.65293 -250.66244)
				)
			)
		)
	)
	(zone
		(layers "In1.Cu" "In2.Cu")
		(hatch none 0.5)
		(connect_pads
			(clearance 0)
		)
		(min_thickness 0.25)
		(keepout
			(tracks not_allowed)
			(vias allowed)
			(pads allowed)
			(copperpour not_allowed)
			(footprints allowed)
		)
		(placement
			(enabled no)
			(sheetname "")
		)
		(fill yes
			(thermal_gap 0.5)
			(thermal_bridge_width 0.5)
			(island_removal_mode 0)
		)
		(polygon
			(pts
				(arc
					(start 165.60673 -252.771402)
					(mid 165.621609 -252.807323)
					(end 165.65753 -252.822202)
				)
				(arc
					(start 167.05707 -252.822202)
					(mid 167.092991 -252.807323)
					(end 167.10787 -252.771402)
				)
				(arc
					(start 167.10787 -252.362462)
					(mid 167.092991 -252.326541)
					(end 167.05707 -252.311662)
				)
				(arc
					(start 165.65753 -252.311662)
					(mid 165.621609 -252.326541)
					(end 165.60673 -252.362462)
				)
			)
		)
	)
	(zone
		(layers "In1.Cu" "In2.Cu")
		(hatch none 0.5)
		(connect_pads
			(clearance 0)
		)
		(min_thickness 0.25)
		(keepout
			(tracks not_allowed)
			(vias allowed)
			(pads allowed)
			(copperpour not_allowed)
			(footprints allowed)
		)
		(placement
			(enabled no)
			(sheetname "")
		)
		(fill yes
			(thermal_gap 0.5)
			(thermal_bridge_width 0.5)
			(island_removal_mode 0)
		)
		(polygon
			(pts
				(arc
					(start 56.752998 -220.471492)
					(mid 56.767877 -220.507413)
					(end 56.803798 -220.522292)
				)
				(arc
					(start 58.203338 -220.522292)
					(mid 58.239259 -220.507413)
					(end 58.254138 -220.471492)
				)
				(arc
					(start 58.254138 -220.062552)
					(mid 58.239259 -220.026631)
					(end 58.203338 -220.011752)
				)
				(arc
					(start 56.803798 -220.011752)
					(mid 56.767877 -220.026631)
					(end 56.752998 -220.062552)
				)
			)
		)
	)
	(zone
		(layers "In1.Cu" "In2.Cu")
		(hatch none 0.5)
		(connect_pads
			(clearance 0)
		)
		(min_thickness 0.25)
		(keepout
			(tracks not_allowed)
			(vias allowed)
			(pads allowed)
			(copperpour not_allowed)
			(footprints allowed)
		)
		(placement
			(enabled no)
			(sheetname "")
		)
		(fill yes
			(thermal_gap 0.5)
			(thermal_bridge_width 0.5)
			(island_removal_mode 0)
		)
		(polygon
			(pts
				(arc
					(start 285.505398 -271.47139)
					(mid 285.520277 -271.507311)
					(end 285.556198 -271.52219)
				)
				(arc
					(start 286.955738 -271.52219)
					(mid 286.991659 -271.507311)
					(end 287.006538 -271.47139)
				)
				(arc
					(start 287.006538 -271.06245)
					(mid 286.991659 -271.026529)
					(end 286.955738 -271.01165)
				)
				(arc
					(start 285.556198 -271.01165)
					(mid 285.520277 -271.026529)
					(end 285.505398 -271.06245)
				)
			)
		)
	)
	(zone
		(layers "In1.Cu" "In2.Cu")
		(hatch none 0.5)
		(connect_pads
			(clearance 0)
		)
		(min_thickness 0.25)
		(keepout
			(tracks not_allowed)
			(vias allowed)
			(pads allowed)
			(copperpour not_allowed)
			(footprints allowed)
		)
		(placement
			(enabled no)
			(sheetname "")
		)
		(fill yes
			(thermal_gap 0.5)
			(thermal_bridge_width 0.5)
			(island_removal_mode 0)
		)
		(polygon
			(pts
				(arc
					(start 26.577798 -270.621506)
					(mid 26.592677 -270.657427)
					(end 26.628598 -270.672306)
				)
				(arc
					(start 28.028138 -270.672306)
					(mid 28.064059 -270.657427)
					(end 28.078938 -270.621506)
				)
				(arc
					(start 28.078938 -270.212566)
					(mid 28.064059 -270.176645)
					(end 28.028138 -270.161766)
				)
				(arc
					(start 26.628598 -270.161766)
					(mid 26.592677 -270.176645)
					(end 26.577798 -270.212566)
				)
			)
		)
	)
	(zone
		(layers "In1.Cu" "In2.Cu")
		(hatch none 0.5)
		(connect_pads
			(clearance 0)
		)
		(min_thickness 0.25)
		(keepout
			(tracks not_allowed)
			(vias allowed)
			(pads allowed)
			(copperpour not_allowed)
			(footprints allowed)
		)
		(placement
			(enabled no)
			(sheetname "")
		)
		(fill yes
			(thermal_gap 0.5)
			(thermal_bridge_width 0.5)
			(island_removal_mode 0)
		)
		(polygon
			(pts
				(arc
					(start 14.93393 -209.421476)
					(mid 14.948809 -209.457397)
					(end 14.98473 -209.472276)
				)
				(arc
					(start 16.38427 -209.472276)
					(mid 16.420191 -209.457397)
					(end 16.43507 -209.421476)
				)
				(arc
					(start 16.43507 -209.012536)
					(mid 16.420191 -208.976615)
					(end 16.38427 -208.961736)
				)
				(arc
					(start 14.98473 -208.961736)
					(mid 14.948809 -208.976615)
					(end 14.93393 -209.012536)
				)
			)
		)
	)
	(zone
		(layers "In1.Cu" "In2.Cu")
		(hatch none 0.5)
		(connect_pads
			(clearance 0)
		)
		(min_thickness 0.25)
		(keepout
			(tracks not_allowed)
			(vias allowed)
			(pads allowed)
			(copperpour not_allowed)
			(footprints allowed)
		)
		(placement
			(enabled no)
			(sheetname "")
		)
		(fill yes
			(thermal_gap 0.5)
			(thermal_bridge_width 0.5)
			(island_removal_mode 0)
		)
		(polygon
			(pts
				(arc
					(start 64.296798 -311.421526)
					(mid 64.311677 -311.457447)
					(end 64.347598 -311.472326)
				)
				(arc
					(start 65.747138 -311.472326)
					(mid 65.783059 -311.457447)
					(end 65.797938 -311.421526)
				)
				(arc
					(start 65.797938 -311.012586)
					(mid 65.783059 -310.976665)
					(end 65.747138 -310.961786)
				)
				(arc
					(start 64.347598 -310.961786)
					(mid 64.311677 -310.976665)
					(end 64.296798 -311.012586)
				)
			)
		)
	)
	(zone
		(layers "In1.Cu" "In2.Cu")
		(hatch none 0.5)
		(connect_pads
			(clearance 0)
		)
		(min_thickness 0.25)
		(keepout
			(tracks not_allowed)
			(vias allowed)
			(pads allowed)
			(copperpour not_allowed)
			(footprints allowed)
		)
		(placement
			(enabled no)
			(sheetname "")
		)
		(fill yes
			(thermal_gap 0.5)
			(thermal_bridge_width 0.5)
			(island_removal_mode 0)
		)
		(polygon
			(pts
				(arc
					(start 203.32573 -251.07138)
					(mid 203.340609 -251.107301)
					(end 203.37653 -251.12218)
				)
				(arc
					(start 204.77607 -251.12218)
					(mid 204.811991 -251.107301)
					(end 204.82687 -251.07138)
				)
				(arc
					(start 204.82687 -250.66244)
					(mid 204.811991 -250.626519)
					(end 204.77607 -250.61164)
				)
				(arc
					(start 203.37653 -250.61164)
					(mid 203.340609 -250.626519)
					(end 203.32573 -250.66244)
				)
			)
		)
	)
	(zone
		(layers "In1.Cu" "In2.Cu")
		(hatch none 0.5)
		(connect_pads
			(clearance 0)
		)
		(min_thickness 0.25)
		(keepout
			(tracks not_allowed)
			(vias allowed)
			(pads allowed)
			(copperpour not_allowed)
			(footprints allowed)
		)
		(placement
			(enabled no)
			(sheetname "")
		)
		(fill yes
			(thermal_gap 0.5)
			(thermal_bridge_width 0.5)
			(island_removal_mode 0)
		)
		(polygon
			(pts
				(arc
					(start 455.365866 -201.771504)
					(mid 455.380745 -201.807425)
					(end 455.416666 -201.822304)
				)
				(arc
					(start 456.816206 -201.822304)
					(mid 456.852127 -201.807425)
					(end 456.867006 -201.771504)
				)
				(arc
					(start 456.867006 -201.362564)
					(mid 456.852127 -201.326643)
					(end 456.816206 -201.311764)
				)
				(arc
					(start 455.416666 -201.311764)
					(mid 455.380745 -201.326643)
					(end 455.365866 -201.362564)
				)
			)
		)
	)
	(zone
		(layers "In1.Cu" "In2.Cu")
		(hatch none 0.5)
		(connect_pads
			(clearance 0)
		)
		(min_thickness 0.25)
		(keepout
			(tracks not_allowed)
			(vias allowed)
			(pads allowed)
			(copperpour not_allowed)
			(footprints allowed)
		)
		(placement
			(enabled no)
			(sheetname "")
		)
		(fill yes
			(thermal_gap 0.5)
			(thermal_bridge_width 0.5)
			(island_removal_mode 0)
		)
		(polygon
			(pts
				(arc
					(start 266.974066 -195.821554)
					(mid 266.988945 -195.857475)
					(end 267.024866 -195.872354)
				)
				(arc
					(start 268.424406 -195.872354)
					(mid 268.460327 -195.857475)
					(end 268.475206 -195.821554)
				)
				(arc
					(start 268.475206 -195.412614)
					(mid 268.460327 -195.376693)
					(end 268.424406 -195.361814)
				)
				(arc
					(start 267.024866 -195.361814)
					(mid 266.988945 -195.376693)
					(end 266.974066 -195.412614)
				)
			)
		)
	)
	(zone
		(layers "In1.Cu" "In2.Cu")
		(hatch none 0.5)
		(connect_pads
			(clearance 0)
		)
		(min_thickness 0.25)
		(keepout
			(tracks not_allowed)
			(vias allowed)
			(pads allowed)
			(copperpour not_allowed)
			(footprints allowed)
		)
		(placement
			(enabled no)
			(sheetname "")
		)
		(fill yes
			(thermal_gap 0.5)
			(thermal_bridge_width 0.5)
			(island_removal_mode 0)
		)
		(polygon
			(pts
				(arc
					(start 165.60673 -312.27141)
					(mid 165.621609 -312.307331)
					(end 165.65753 -312.32221)
				)
				(arc
					(start 167.05707 -312.32221)
					(mid 167.092991 -312.307331)
					(end 167.10787 -312.27141)
				)
				(arc
					(start 167.10787 -311.86247)
					(mid 167.092991 -311.826549)
					(end 167.05707 -311.81167)
				)
				(arc
					(start 165.65753 -311.81167)
					(mid 165.621609 -311.826549)
					(end 165.60673 -311.86247)
				)
			)
		)
	)
	(zone
		(layers "In1.Cu" "In2.Cu")
		(hatch none 0.5)
		(connect_pads
			(clearance 0)
		)
		(min_thickness 0.25)
		(keepout
			(tracks not_allowed)
			(vias allowed)
			(pads allowed)
			(copperpour not_allowed)
			(footprints allowed)
		)
		(placement
			(enabled no)
			(sheetname "")
		)
		(fill yes
			(thermal_gap 0.5)
			(thermal_bridge_width 0.5)
			(island_removal_mode 0)
		)
		(polygon
			(pts
				(arc
					(start 282.061666 -233.22153)
					(mid 282.076545 -233.257451)
					(end 282.112466 -233.27233)
				)
				(arc
					(start 283.512006 -233.27233)
					(mid 283.547927 -233.257451)
					(end 283.562806 -233.22153)
				)
				(arc
					(start 283.562806 -232.81259)
					(mid 283.547927 -232.776669)
					(end 283.512006 -232.76179)
				)
				(arc
					(start 282.112466 -232.76179)
					(mid 282.076545 -232.776669)
					(end 282.061666 -232.81259)
				)
			)
		)
	)
	(zone
		(layers "In1.Cu" "In2.Cu")
		(hatch none 0.5)
		(connect_pads
			(clearance 0)
		)
		(min_thickness 0.25)
		(keepout
			(tracks not_allowed)
			(vias allowed)
			(pads allowed)
			(copperpour not_allowed)
			(footprints allowed)
		)
		(placement
			(enabled no)
			(sheetname "")
		)
		(fill yes
			(thermal_gap 0.5)
			(thermal_bridge_width 0.5)
			(island_removal_mode 0)
		)
		(polygon
			(pts
				(arc
					(start 52.65293 -206.021432)
					(mid 52.667809 -206.057353)
					(end 52.70373 -206.072232)
				)
				(arc
					(start 54.10327 -206.072232)
					(mid 54.139191 -206.057353)
					(end 54.15407 -206.021432)
				)
				(arc
					(start 54.15407 -205.612492)
					(mid 54.139191 -205.576571)
					(end 54.10327 -205.561692)
				)
				(arc
					(start 52.70373 -205.561692)
					(mid 52.667809 -205.576571)
					(end 52.65293 -205.612492)
				)
			)
		)
	)
	(zone
		(layers "In1.Cu" "In2.Cu")
		(hatch none 0.5)
		(connect_pads
			(clearance 0)
		)
		(min_thickness 0.25)
		(keepout
			(tracks not_allowed)
			(vias allowed)
			(pads allowed)
			(copperpour not_allowed)
			(footprints allowed)
		)
		(placement
			(enabled no)
			(sheetname "")
		)
		(fill yes
			(thermal_gap 0.5)
			(thermal_bridge_width 0.5)
			(island_removal_mode 0)
		)
		(polygon
			(pts
				(arc
					(start 177.250598 -289.321494)
					(mid 177.265477 -289.357415)
					(end 177.301398 -289.372294)
				)
				(arc
					(start 178.700938 -289.372294)
					(mid 178.736859 -289.357415)
					(end 178.751738 -289.321494)
				)
				(arc
					(start 178.751738 -288.912554)
					(mid 178.736859 -288.876633)
					(end 178.700938 -288.861754)
				)
				(arc
					(start 177.301398 -288.861754)
					(mid 177.265477 -288.876633)
					(end 177.250598 -288.912554)
				)
			)
		)
	)
	(zone
		(layers "In1.Cu" "In2.Cu")
		(hatch none 0.5)
		(connect_pads
			(clearance 0)
		)
		(min_thickness 0.25)
		(keepout
			(tracks not_allowed)
			(vias allowed)
			(pads allowed)
			(copperpour not_allowed)
			(footprints allowed)
		)
		(placement
			(enabled no)
			(sheetname "")
		)
		(fill yes
			(thermal_gap 0.5)
			(thermal_bridge_width 0.5)
			(island_removal_mode 0)
		)
		(polygon
			(pts
				(arc
					(start 214.969598 -250.221496)
					(mid 214.984477 -250.257417)
					(end 215.020398 -250.272296)
				)
				(arc
					(start 216.419938 -250.272296)
					(mid 216.455859 -250.257417)
					(end 216.470738 -250.221496)
				)
				(arc
					(start 216.470738 -249.812556)
					(mid 216.455859 -249.776635)
					(end 216.419938 -249.761756)
				)
				(arc
					(start 215.020398 -249.761756)
					(mid 214.984477 -249.776635)
					(end 214.969598 -249.812556)
				)
			)
		)
	)
	(zone
		(layers "In1.Cu" "In2.Cu")
		(hatch none 0.5)
		(connect_pads
			(clearance 0)
		)
		(min_thickness 0.25)
		(keepout
			(tracks not_allowed)
			(vias allowed)
			(pads allowed)
			(copperpour not_allowed)
			(footprints allowed)
		)
		(placement
			(enabled no)
			(sheetname "")
		)
		(fill yes
			(thermal_gap 0.5)
			(thermal_bridge_width 0.5)
			(island_removal_mode 0)
		)
		(polygon
			(pts
				(arc
					(start 282.061666 -234.921298)
					(mid 282.076545 -234.957219)
					(end 282.112466 -234.972098)
				)
				(arc
					(start 283.512006 -234.972098)
					(mid 283.547927 -234.957219)
					(end 283.562806 -234.921298)
				)
				(arc
					(start 283.562806 -234.512358)
					(mid 283.547927 -234.476437)
					(end 283.512006 -234.461558)
				)
				(arc
					(start 282.112466 -234.461558)
					(mid 282.076545 -234.476437)
					(end 282.061666 -234.512358)
				)
			)
		)
	)
	(zone
		(layers "In1.Cu" "In2.Cu")
		(hatch none 0.5)
		(connect_pads
			(clearance 0)
		)
		(min_thickness 0.25)
		(keepout
			(tracks not_allowed)
			(vias allowed)
			(pads allowed)
			(copperpour not_allowed)
			(footprints allowed)
		)
		(placement
			(enabled no)
			(sheetname "")
		)
		(fill yes
			(thermal_gap 0.5)
			(thermal_bridge_width 0.5)
			(island_removal_mode 0)
		)
		(polygon
			(pts
				(arc
					(start 177.250598 -272.321528)
					(mid 177.265477 -272.357449)
					(end 177.301398 -272.372328)
				)
				(arc
					(start 178.700938 -272.372328)
					(mid 178.736859 -272.357449)
					(end 178.751738 -272.321528)
				)
				(arc
					(start 178.751738 -271.912588)
					(mid 178.736859 -271.876667)
					(end 178.700938 -271.861788)
				)
				(arc
					(start 177.301398 -271.861788)
					(mid 177.265477 -271.876667)
					(end 177.250598 -271.912588)
				)
			)
		)
	)
	(zone
		(layers "In1.Cu" "In2.Cu")
		(hatch none 0.5)
		(connect_pads
			(clearance 0)
		)
		(min_thickness 0.25)
		(keepout
			(tracks not_allowed)
			(vias allowed)
			(pads allowed)
			(copperpour not_allowed)
			(footprints allowed)
		)
		(placement
			(enabled no)
			(sheetname "")
		)
		(fill yes
			(thermal_gap 0.5)
			(thermal_bridge_width 0.5)
			(island_removal_mode 0)
		)
		(polygon
			(pts
				(arc
					(start 417.646866 -300.37151)
					(mid 417.661745 -300.407431)
					(end 417.697666 -300.42231)
				)
				(arc
					(start 419.097206 -300.42231)
					(mid 419.133127 -300.407431)
					(end 419.148006 -300.37151)
				)
				(arc
					(start 419.148006 -299.96257)
					(mid 419.133127 -299.926649)
					(end 419.097206 -299.91177)
				)
				(arc
					(start 417.697666 -299.91177)
					(mid 417.661745 -299.926649)
					(end 417.646866 -299.96257)
				)
			)
		)
	)
	(zone
		(layers "In1.Cu" "In2.Cu")
		(hatch none 0.5)
		(connect_pads
			(clearance 0)
		)
		(min_thickness 0.25)
		(keepout
			(tracks not_allowed)
			(vias allowed)
			(pads allowed)
			(copperpour not_allowed)
			(footprints allowed)
		)
		(placement
			(enabled no)
			(sheetname "")
		)
		(fill yes
			(thermal_gap 0.5)
			(thermal_bridge_width 0.5)
			(island_removal_mode 0)
		)
		(polygon
			(pts
				(arc
					(start 52.65293 -196.671438)
					(mid 52.667809 -196.707359)
					(end 52.70373 -196.722238)
				)
				(arc
					(start 54.10327 -196.722238)
					(mid 54.139191 -196.707359)
					(end 54.15407 -196.671438)
				)
				(arc
					(start 54.15407 -196.262498)
					(mid 54.139191 -196.226577)
					(end 54.10327 -196.211698)
				)
				(arc
					(start 52.70373 -196.211698)
					(mid 52.667809 -196.226577)
					(end 52.65293 -196.262498)
				)
			)
		)
	)
	(zone
		(layers "In1.Cu" "In2.Cu")
		(hatch none 0.5)
		(connect_pads
			(clearance 0)
		)
		(min_thickness 0.25)
		(keepout
			(tracks not_allowed)
			(vias allowed)
			(pads allowed)
			(copperpour not_allowed)
			(footprints allowed)
		)
		(placement
			(enabled no)
			(sheetname "")
		)
		(fill yes
			(thermal_gap 0.5)
			(thermal_bridge_width 0.5)
			(island_removal_mode 0)
		)
		(polygon
			(pts
				(arc
					(start 26.577798 -206.871316)
					(mid 26.592677 -206.907237)
					(end 26.628598 -206.922116)
				)
				(arc
					(start 28.028138 -206.922116)
					(mid 28.064059 -206.907237)
					(end 28.078938 -206.871316)
				)
				(arc
					(start 28.078938 -206.462376)
					(mid 28.064059 -206.426455)
					(end 28.028138 -206.411576)
				)
				(arc
					(start 26.628598 -206.411576)
					(mid 26.592677 -206.426455)
					(end 26.577798 -206.462376)
				)
			)
		)
	)
	(zone
		(layers "In1.Cu" "In2.Cu")
		(hatch none 0.5)
		(connect_pads
			(clearance 0)
		)
		(min_thickness 0.25)
		(keepout
			(tracks not_allowed)
			(vias allowed)
			(pads allowed)
			(copperpour not_allowed)
			(footprints allowed)
		)
		(placement
			(enabled no)
			(sheetname "")
		)
		(fill yes
			(thermal_gap 0.5)
			(thermal_bridge_width 0.5)
			(island_removal_mode 0)
		)
		(polygon
			(pts
				(arc
					(start 41.665398 -315.671454)
					(mid 41.680277 -315.707375)
					(end 41.716198 -315.722254)
				)
				(arc
					(start 43.115738 -315.722254)
					(mid 43.151659 -315.707375)
					(end 43.166538 -315.671454)
				)
				(arc
					(start 43.166538 -315.262514)
					(mid 43.151659 -315.226593)
					(end 43.115738 -315.211714)
				)
				(arc
					(start 41.716198 -315.211714)
					(mid 41.680277 -315.226593)
					(end 41.665398 -315.262514)
				)
			)
		)
	)
	(zone
		(layers "In1.Cu" "In2.Cu")
		(hatch none 0.5)
		(connect_pads
			(clearance 0)
		)
		(min_thickness 0.25)
		(keepout
			(tracks not_allowed)
			(vias allowed)
			(pads allowed)
			(copperpour not_allowed)
			(footprints allowed)
		)
		(placement
			(enabled no)
			(sheetname "")
		)
		(fill yes
			(thermal_gap 0.5)
			(thermal_bridge_width 0.5)
			(island_removal_mode 0)
		)
		(polygon
			(pts
				(arc
					(start 304.693066 -313.971432)
					(mid 304.707945 -314.007353)
					(end 304.743866 -314.022232)
				)
				(arc
					(start 306.143406 -314.022232)
					(mid 306.179327 -314.007353)
					(end 306.194206 -313.971432)
				)
				(arc
					(start 306.194206 -313.562492)
					(mid 306.179327 -313.526571)
					(end 306.143406 -313.511692)
				)
				(arc
					(start 304.743866 -313.511692)
					(mid 304.707945 -313.526571)
					(end 304.693066 -313.562492)
				)
			)
		)
	)
	(zone
		(layers "In1.Cu" "In2.Cu")
		(hatch none 0.5)
		(connect_pads
			(clearance 0)
		)
		(min_thickness 0.25)
		(keepout
			(tracks not_allowed)
			(vias allowed)
			(pads allowed)
			(copperpour not_allowed)
			(footprints allowed)
		)
		(placement
			(enabled no)
			(sheetname "")
		)
		(fill yes
			(thermal_gap 0.5)
			(thermal_bridge_width 0.5)
			(island_removal_mode 0)
		)
		(polygon
			(pts
				(arc
					(start 277.961598 -200.921366)
					(mid 277.976477 -200.957287)
					(end 278.012398 -200.972166)
				)
				(arc
					(start 279.411938 -200.972166)
					(mid 279.447859 -200.957287)
					(end 279.462738 -200.921366)
				)
				(arc
					(start 279.462738 -200.512426)
					(mid 279.447859 -200.476505)
					(end 279.411938 -200.461626)
				)
				(arc
					(start 278.012398 -200.461626)
					(mid 277.976477 -200.476505)
					(end 277.961598 -200.512426)
				)
			)
		)
	)
	(zone
		(layers "In1.Cu" "In2.Cu")
		(hatch none 0.5)
		(connect_pads
			(clearance 0)
		)
		(min_thickness 0.25)
		(keepout
			(tracks not_allowed)
			(vias allowed)
			(pads allowed)
			(copperpour not_allowed)
			(footprints allowed)
		)
		(placement
			(enabled no)
			(sheetname "")
		)
		(fill yes
			(thermal_gap 0.5)
			(thermal_bridge_width 0.5)
			(island_removal_mode 0)
		)
		(polygon
			(pts
				(arc
					(start 158.06293 -285.071312)
					(mid 158.077809 -285.107233)
					(end 158.11373 -285.122112)
				)
				(arc
					(start 159.51327 -285.122112)
					(mid 159.549191 -285.107233)
					(end 159.56407 -285.071312)
				)
				(arc
					(start 159.56407 -284.662372)
					(mid 159.549191 -284.626451)
					(end 159.51327 -284.611572)
				)
				(arc
					(start 158.11373 -284.611572)
					(mid 158.077809 -284.626451)
					(end 158.06293 -284.662372)
				)
			)
		)
	)
	(zone
		(layers "In1.Cu" "In2.Cu")
		(hatch none 0.5)
		(connect_pads
			(clearance 0)
		)
		(min_thickness 0.25)
		(keepout
			(tracks not_allowed)
			(vias allowed)
			(pads allowed)
			(copperpour not_allowed)
			(footprints allowed)
		)
		(placement
			(enabled no)
			(sheetname "")
		)
		(fill yes
			(thermal_gap 0.5)
			(thermal_bridge_width 0.5)
			(island_removal_mode 0)
		)
		(polygon
			(pts
				(arc
					(start 19.033998 -234.921298)
					(mid 19.048877 -234.957219)
					(end 19.084798 -234.972098)
				)
				(arc
					(start 20.484338 -234.972098)
					(mid 20.520259 -234.957219)
					(end 20.535138 -234.921298)
				)
				(arc
					(start 20.535138 -234.512358)
					(mid 20.520259 -234.476437)
					(end 20.484338 -234.461558)
				)
				(arc
					(start 19.084798 -234.461558)
					(mid 19.048877 -234.476437)
					(end 19.033998 -234.512358)
				)
			)
		)
	)
	(zone
		(layers "In1.Cu" "In2.Cu")
		(hatch none 0.5)
		(connect_pads
			(clearance 0)
		)
		(min_thickness 0.25)
		(keepout
			(tracks not_allowed)
			(vias allowed)
			(pads allowed)
			(copperpour not_allowed)
			(footprints allowed)
		)
		(placement
			(enabled no)
			(sheetname "")
		)
		(fill yes
			(thermal_gap 0.5)
			(thermal_bridge_width 0.5)
			(island_removal_mode 0)
		)
		(polygon
			(pts
				(arc
					(start 259.430266 -239.17148)
					(mid 259.445145 -239.207401)
					(end 259.481066 -239.22228)
				)
				(arc
					(start 260.880606 -239.22228)
					(mid 260.916527 -239.207401)
					(end 260.931406 -239.17148)
				)
				(arc
					(start 260.931406 -238.76254)
					(mid 260.916527 -238.726619)
					(end 260.880606 -238.71174)
				)
				(arc
					(start 259.481066 -238.71174)
					(mid 259.445145 -238.726619)
					(end 259.430266 -238.76254)
				)
			)
		)
	)
	(zone
		(layers "In1.Cu" "In2.Cu")
		(hatch none 0.5)
		(connect_pads
			(clearance 0)
		)
		(min_thickness 0.25)
		(keepout
			(tracks not_allowed)
			(vias allowed)
			(pads allowed)
			(copperpour not_allowed)
			(footprints allowed)
		)
		(placement
			(enabled no)
			(sheetname "")
		)
		(fill yes
			(thermal_gap 0.5)
			(thermal_bridge_width 0.5)
			(island_removal_mode 0)
		)
		(polygon
			(pts
				(arc
					(start 432.734466 -260.421374)
					(mid 432.749345 -260.457295)
					(end 432.785266 -260.472174)
				)
				(arc
					(start 434.184806 -260.472174)
					(mid 434.220727 -260.457295)
					(end 434.235606 -260.421374)
				)
				(arc
					(start 434.235606 -260.012434)
					(mid 434.220727 -259.976513)
					(end 434.184806 -259.961634)
				)
				(arc
					(start 432.785266 -259.961634)
					(mid 432.749345 -259.976513)
					(end 432.734466 -260.012434)
				)
			)
		)
	)
	(zone
		(layers "In1.Cu" "In2.Cu")
		(hatch none 0.5)
		(connect_pads
			(clearance 0)
		)
		(min_thickness 0.25)
		(keepout
			(tracks not_allowed)
			(vias allowed)
			(pads allowed)
			(copperpour not_allowed)
			(footprints allowed)
		)
		(placement
			(enabled no)
			(sheetname "")
		)
		(fill yes
			(thermal_gap 0.5)
			(thermal_bridge_width 0.5)
			(island_removal_mode 0)
		)
		(polygon
			(pts
				(arc
					(start 192.338198 -268.921484)
					(mid 192.353077 -268.957405)
					(end 192.388998 -268.972284)
				)
				(arc
					(start 193.788538 -268.972284)
					(mid 193.824459 -268.957405)
					(end 193.839338 -268.921484)
				)
				(arc
					(start 193.839338 -268.512544)
					(mid 193.824459 -268.476623)
					(end 193.788538 -268.461744)
				)
				(arc
					(start 192.388998 -268.461744)
					(mid 192.353077 -268.476623)
					(end 192.338198 -268.512544)
				)
			)
		)
	)
	(zone
		(layers "In1.Cu" "In2.Cu")
		(hatch none 0.5)
		(connect_pads
			(clearance 0)
		)
		(min_thickness 0.25)
		(keepout
			(tracks not_allowed)
			(vias allowed)
			(pads allowed)
			(copperpour not_allowed)
			(footprints allowed)
		)
		(placement
			(enabled no)
			(sheetname "")
		)
		(fill yes
			(thermal_gap 0.5)
			(thermal_bridge_width 0.5)
			(island_removal_mode 0)
		)
		(polygon
			(pts
				(arc
					(start 64.296798 -295.271444)
					(mid 64.311677 -295.307365)
					(end 64.347598 -295.322244)
				)
				(arc
					(start 65.747138 -295.322244)
					(mid 65.783059 -295.307365)
					(end 65.797938 -295.271444)
				)
				(arc
					(start 65.797938 -294.862504)
					(mid 65.783059 -294.826583)
					(end 65.747138 -294.811704)
				)
				(arc
					(start 64.347598 -294.811704)
					(mid 64.311677 -294.826583)
					(end 64.296798 -294.862504)
				)
			)
		)
	)
	(zone
		(layers "In1.Cu" "In2.Cu")
		(hatch none 0.5)
		(connect_pads
			(clearance 0)
		)
		(min_thickness 0.25)
		(keepout
			(tracks not_allowed)
			(vias allowed)
			(pads allowed)
			(copperpour not_allowed)
			(footprints allowed)
		)
		(placement
			(enabled no)
			(sheetname "")
		)
		(fill yes
			(thermal_gap 0.5)
			(thermal_bridge_width 0.5)
			(island_removal_mode 0)
		)
		(polygon
			(pts
				(arc
					(start 462.909666 -225.571304)
					(mid 462.924545 -225.607225)
					(end 462.960466 -225.622104)
				)
				(arc
					(start 464.360006 -225.622104)
					(mid 464.395927 -225.607225)
					(end 464.410806 -225.571304)
				)
				(arc
					(start 464.410806 -225.162364)
					(mid 464.395927 -225.126443)
					(end 464.360006 -225.111564)
				)
				(arc
					(start 462.960466 -225.111564)
					(mid 462.924545 -225.126443)
					(end 462.909666 -225.162364)
				)
			)
		)
	)
	(zone
		(layers "In1.Cu" "In2.Cu")
		(hatch none 0.5)
		(connect_pads
			(clearance 0)
		)
		(min_thickness 0.25)
		(keepout
			(tracks not_allowed)
			(vias allowed)
			(pads allowed)
			(copperpour not_allowed)
			(footprints allowed)
		)
		(placement
			(enabled no)
			(sheetname "")
		)
		(fill yes
			(thermal_gap 0.5)
			(thermal_bridge_width 0.5)
			(island_removal_mode 0)
		)
		(polygon
			(pts
				(arc
					(start 289.605466 -225.571304)
					(mid 289.620345 -225.607225)
					(end 289.656266 -225.622104)
				)
				(arc
					(start 291.055806 -225.622104)
					(mid 291.091727 -225.607225)
					(end 291.106606 -225.571304)
				)
				(arc
					(start 291.106606 -225.162364)
					(mid 291.091727 -225.126443)
					(end 291.055806 -225.111564)
				)
				(arc
					(start 289.656266 -225.111564)
					(mid 289.620345 -225.126443)
					(end 289.605466 -225.162364)
				)
			)
		)
	)
	(zone
		(layers "In1.Cu" "In2.Cu")
		(hatch none 0.5)
		(connect_pads
			(clearance 0)
		)
		(min_thickness 0.25)
		(keepout
			(tracks not_allowed)
			(vias allowed)
			(pads allowed)
			(copperpour not_allowed)
			(footprints allowed)
		)
		(placement
			(enabled no)
			(sheetname "")
		)
		(fill yes
			(thermal_gap 0.5)
			(thermal_bridge_width 0.5)
			(island_removal_mode 0)
		)
		(polygon
			(pts
				(arc
					(start 14.93393 -268.071346)
					(mid 14.948809 -268.107267)
					(end 14.98473 -268.122146)
				)
				(arc
					(start 16.38427 -268.122146)
					(mid 16.420191 -268.107267)
					(end 16.43507 -268.071346)
				)
				(arc
					(start 16.43507 -267.662406)
					(mid 16.420191 -267.626485)
					(end 16.38427 -267.611606)
				)
				(arc
					(start 14.98473 -267.611606)
					(mid 14.948809 -267.626485)
					(end 14.93393 -267.662406)
				)
			)
		)
	)
	(zone
		(layers "In1.Cu" "In2.Cu")
		(hatch none 0.5)
		(connect_pads
			(clearance 0)
		)
		(min_thickness 0.25)
		(keepout
			(tracks not_allowed)
			(vias allowed)
			(pads allowed)
			(copperpour not_allowed)
			(footprints allowed)
		)
		(placement
			(enabled no)
			(sheetname "")
		)
		(fill yes
			(thermal_gap 0.5)
			(thermal_bridge_width 0.5)
			(island_removal_mode 0)
		)
		(polygon
			(pts
				(arc
					(start 60.19673 -264.671302)
					(mid 60.211609 -264.707223)
					(end 60.24753 -264.722102)
				)
				(arc
					(start 61.64707 -264.722102)
					(mid 61.682991 -264.707223)
					(end 61.69787 -264.671302)
				)
				(arc
					(start 61.69787 -264.262362)
					(mid 61.682991 -264.226441)
					(end 61.64707 -264.211562)
				)
				(arc
					(start 60.24753 -264.211562)
					(mid 60.211609 -264.226441)
					(end 60.19673 -264.262362)
				)
			)
		)
	)
	(zone
		(layers "In1.Cu" "In2.Cu")
		(hatch none 0.5)
		(connect_pads
			(clearance 0)
		)
		(min_thickness 0.25)
		(keepout
			(tracks not_allowed)
			(vias allowed)
			(pads allowed)
			(copperpour not_allowed)
			(footprints allowed)
		)
		(placement
			(enabled no)
			(sheetname "")
		)
		(fill yes
			(thermal_gap 0.5)
			(thermal_bridge_width 0.5)
			(island_removal_mode 0)
		)
		(polygon
			(pts
				(arc
					(start 262.873998 -200.071482)
					(mid 262.888877 -200.107403)
					(end 262.924798 -200.122282)
				)
				(arc
					(start 264.324338 -200.122282)
					(mid 264.360259 -200.107403)
					(end 264.375138 -200.071482)
				)
				(arc
					(start 264.375138 -199.662542)
					(mid 264.360259 -199.626621)
					(end 264.324338 -199.611742)
				)
				(arc
					(start 262.924798 -199.611742)
					(mid 262.888877 -199.626621)
					(end 262.873998 -199.662542)
				)
			)
		)
	)
	(zone
		(layers "In1.Cu" "In2.Cu")
		(hatch none 0.5)
		(connect_pads
			(clearance 0)
		)
		(min_thickness 0.25)
		(keepout
			(tracks not_allowed)
			(vias allowed)
			(pads allowed)
			(copperpour not_allowed)
			(footprints allowed)
		)
		(placement
			(enabled no)
			(sheetname "")
		)
		(fill yes
			(thermal_gap 0.5)
			(thermal_bridge_width 0.5)
			(island_removal_mode 0)
		)
		(polygon
			(pts
				(arc
					(start 417.646866 -272.321528)
					(mid 417.661745 -272.357449)
					(end 417.697666 -272.372328)
				)
				(arc
					(start 419.097206 -272.372328)
					(mid 419.133127 -272.357449)
					(end 419.148006 -272.321528)
				)
				(arc
					(start 419.148006 -271.912588)
					(mid 419.133127 -271.876667)
					(end 419.097206 -271.861788)
				)
				(arc
					(start 417.697666 -271.861788)
					(mid 417.661745 -271.876667)
					(end 417.646866 -271.912588)
				)
			)
		)
	)
	(zone
		(layers "In1.Cu" "In2.Cu")
		(hatch none 0.5)
		(connect_pads
			(clearance 0)
		)
		(min_thickness 0.25)
		(keepout
			(tracks not_allowed)
			(vias allowed)
			(pads allowed)
			(copperpour not_allowed)
			(footprints allowed)
		)
		(placement
			(enabled no)
			(sheetname "")
		)
		(fill yes
			(thermal_gap 0.5)
			(thermal_bridge_width 0.5)
			(island_removal_mode 0)
		)
		(polygon
			(pts
				(arc
					(start 158.06293 -288.471356)
					(mid 158.077809 -288.507277)
					(end 158.11373 -288.522156)
				)
				(arc
					(start 159.51327 -288.522156)
					(mid 159.549191 -288.507277)
					(end 159.56407 -288.471356)
				)
				(arc
					(start 159.56407 -288.062416)
					(mid 159.549191 -288.026495)
					(end 159.51327 -288.011616)
				)
				(arc
					(start 158.11373 -288.011616)
					(mid 158.077809 -288.026495)
					(end 158.06293 -288.062416)
				)
			)
		)
	)
	(zone
		(layers "In1.Cu" "In2.Cu")
		(hatch none 0.5)
		(connect_pads
			(clearance 0)
		)
		(min_thickness 0.25)
		(keepout
			(tracks not_allowed)
			(vias allowed)
			(pads allowed)
			(copperpour not_allowed)
			(footprints allowed)
		)
		(placement
			(enabled no)
			(sheetname "")
		)
		(fill yes
			(thermal_gap 0.5)
			(thermal_bridge_width 0.5)
			(island_removal_mode 0)
		)
		(polygon
			(pts
				(arc
					(start 60.19673 -274.871434)
					(mid 60.211609 -274.907355)
					(end 60.24753 -274.922234)
				)
				(arc
					(start 61.64707 -274.922234)
					(mid 61.682991 -274.907355)
					(end 61.69787 -274.871434)
				)
				(arc
					(start 61.69787 -274.462494)
					(mid 61.682991 -274.426573)
					(end 61.64707 -274.411694)
				)
				(arc
					(start 60.24753 -274.411694)
					(mid 60.211609 -274.426573)
					(end 60.19673 -274.462494)
				)
			)
		)
	)
	(zone
		(layers "In1.Cu" "In2.Cu")
		(hatch none 0.5)
		(connect_pads
			(clearance 0)
		)
		(min_thickness 0.25)
		(keepout
			(tracks not_allowed)
			(vias allowed)
			(pads allowed)
			(copperpour not_allowed)
			(footprints allowed)
		)
		(placement
			(enabled no)
			(sheetname "")
		)
		(fill yes
			(thermal_gap 0.5)
			(thermal_bridge_width 0.5)
			(island_removal_mode 0)
		)
		(polygon
			(pts
				(arc
					(start 282.061666 -268.921484)
					(mid 282.076545 -268.957405)
					(end 282.112466 -268.972284)
				)
				(arc
					(start 283.512006 -268.972284)
					(mid 283.547927 -268.957405)
					(end 283.562806 -268.921484)
				)
				(arc
					(start 283.562806 -268.512544)
					(mid 283.547927 -268.476623)
					(end 283.512006 -268.461744)
				)
				(arc
					(start 282.112466 -268.461744)
					(mid 282.076545 -268.476623)
					(end 282.061666 -268.512544)
				)
			)
		)
	)
	(zone
		(layers "In1.Cu" "In2.Cu")
		(hatch none 0.5)
		(connect_pads
			(clearance 0)
		)
		(min_thickness 0.25)
		(keepout
			(tracks not_allowed)
			(vias allowed)
			(pads allowed)
			(copperpour not_allowed)
			(footprints allowed)
		)
		(placement
			(enabled no)
			(sheetname "")
		)
		(fill yes
			(thermal_gap 0.5)
			(thermal_bridge_width 0.5)
			(island_removal_mode 0)
		)
		(polygon
			(pts
				(arc
					(start 255.330198 -282.521406)
					(mid 255.345077 -282.557327)
					(end 255.380998 -282.572206)
				)
				(arc
					(start 256.780538 -282.572206)
					(mid 256.816459 -282.557327)
					(end 256.831338 -282.521406)
				)
				(arc
					(start 256.831338 -282.112466)
					(mid 256.816459 -282.076545)
					(end 256.780538 -282.061666)
				)
				(arc
					(start 255.380998 -282.061666)
					(mid 255.345077 -282.076545)
					(end 255.330198 -282.112466)
				)
			)
		)
	)
	(zone
		(layers "In1.Cu" "In2.Cu")
		(hatch none 0.5)
		(connect_pads
			(clearance 0)
		)
		(min_thickness 0.25)
		(keepout
			(tracks not_allowed)
			(vias allowed)
			(pads allowed)
			(copperpour not_allowed)
			(footprints allowed)
		)
		(placement
			(enabled no)
			(sheetname "")
		)
		(fill yes
			(thermal_gap 0.5)
			(thermal_bridge_width 0.5)
			(island_removal_mode 0)
		)
		(polygon
			(pts
				(arc
					(start 37.56533 -279.121362)
					(mid 37.580209 -279.157283)
					(end 37.61613 -279.172162)
				)
				(arc
					(start 39.01567 -279.172162)
					(mid 39.051591 -279.157283)
					(end 39.06647 -279.121362)
				)
				(arc
					(start 39.06647 -278.712422)
					(mid 39.051591 -278.676501)
					(end 39.01567 -278.661622)
				)
				(arc
					(start 37.61613 -278.661622)
					(mid 37.580209 -278.676501)
					(end 37.56533 -278.712422)
				)
			)
		)
	)
	(zone
		(layers "In1.Cu" "In2.Cu")
		(hatch none 0.5)
		(connect_pads
			(clearance 0)
		)
		(min_thickness 0.25)
		(keepout
			(tracks not_allowed)
			(vias allowed)
			(pads allowed)
			(copperpour not_allowed)
			(footprints allowed)
		)
		(placement
			(enabled no)
			(sheetname "")
		)
		(fill yes
			(thermal_gap 0.5)
			(thermal_bridge_width 0.5)
			(island_removal_mode 0)
		)
		(polygon
			(pts
				(arc
					(start 56.752998 -285.92145)
					(mid 56.767877 -285.957371)
					(end 56.803798 -285.97225)
				)
				(arc
					(start 58.203338 -285.97225)
					(mid 58.239259 -285.957371)
					(end 58.254138 -285.92145)
				)
				(arc
					(start 58.254138 -285.51251)
					(mid 58.239259 -285.476589)
					(end 58.203338 -285.46171)
				)
				(arc
					(start 56.803798 -285.46171)
					(mid 56.767877 -285.476589)
					(end 56.752998 -285.51251)
				)
			)
		)
	)
	(zone
		(layers "In1.Cu" "In2.Cu")
		(hatch none 0.5)
		(connect_pads
			(clearance 0)
		)
		(min_thickness 0.25)
		(keepout
			(tracks not_allowed)
			(vias allowed)
			(pads allowed)
			(copperpour not_allowed)
			(footprints allowed)
		)
		(placement
			(enabled no)
			(sheetname "")
		)
		(fill yes
			(thermal_gap 0.5)
			(thermal_bridge_width 0.5)
			(island_removal_mode 0)
		)
		(polygon
			(pts
				(arc
					(start 162.162998 -265.52144)
					(mid 162.177877 -265.557361)
					(end 162.213798 -265.57224)
				)
				(arc
					(start 163.613338 -265.57224)
					(mid 163.649259 -265.557361)
					(end 163.664138 -265.52144)
				)
				(arc
					(start 163.664138 -265.1125)
					(mid 163.649259 -265.076579)
					(end 163.613338 -265.0617)
				)
				(arc
					(start 162.213798 -265.0617)
					(mid 162.177877 -265.076579)
					(end 162.162998 -265.1125)
				)
			)
		)
	)
	(zone
		(layers "In1.Cu" "In2.Cu")
		(hatch none 0.5)
		(connect_pads
			(clearance 0)
		)
		(min_thickness 0.25)
		(keepout
			(tracks not_allowed)
			(vias allowed)
			(pads allowed)
			(copperpour not_allowed)
			(footprints allowed)
		)
		(placement
			(enabled no)
			(sheetname "")
		)
		(fill yes
			(thermal_gap 0.5)
			(thermal_bridge_width 0.5)
			(island_removal_mode 0)
		)
		(polygon
			(pts
				(arc
					(start 214.969598 -209.421476)
					(mid 214.984477 -209.457397)
					(end 215.020398 -209.472276)
				)
				(arc
					(start 216.419938 -209.472276)
					(mid 216.455859 -209.457397)
					(end 216.470738 -209.421476)
				)
				(arc
					(start 216.470738 -209.012536)
					(mid 216.455859 -208.976615)
					(end 216.419938 -208.961736)
				)
				(arc
					(start 215.020398 -208.961736)
					(mid 214.984477 -208.976615)
					(end 214.969598 -209.012536)
				)
			)
		)
	)
	(zone
		(layers "In1.Cu" "In2.Cu")
		(hatch none 0.5)
		(connect_pads
			(clearance 0)
		)
		(min_thickness 0.25)
		(keepout
			(tracks not_allowed)
			(vias allowed)
			(pads allowed)
			(copperpour not_allowed)
			(footprints allowed)
		)
		(placement
			(enabled no)
			(sheetname "")
		)
		(fill yes
			(thermal_gap 0.5)
			(thermal_bridge_width 0.5)
			(island_removal_mode 0)
		)
		(polygon
			(pts
				(arc
					(start 60.19673 -302.921416)
					(mid 60.211609 -302.957337)
					(end 60.24753 -302.972216)
				)
				(arc
					(start 61.64707 -302.972216)
					(mid 61.682991 -302.957337)
					(end 61.69787 -302.921416)
				)
				(arc
					(start 61.69787 -302.512476)
					(mid 61.682991 -302.476555)
					(end 61.64707 -302.461676)
				)
				(arc
					(start 60.24753 -302.461676)
					(mid 60.211609 -302.476555)
					(end 60.19673 -302.512476)
				)
			)
		)
	)
	(zone
		(layers "In1.Cu" "In2.Cu")
		(hatch none 0.5)
		(connect_pads
			(clearance 0)
		)
		(min_thickness 0.25)
		(keepout
			(tracks not_allowed)
			(vias allowed)
			(pads allowed)
			(copperpour not_allowed)
			(footprints allowed)
		)
		(placement
			(enabled no)
			(sheetname "")
		)
		(fill yes
			(thermal_gap 0.5)
			(thermal_bridge_width 0.5)
			(island_removal_mode 0)
		)
		(polygon
			(pts
				(arc
					(start 297.149266 -293.571422)
					(mid 297.164145 -293.607343)
					(end 297.200066 -293.622222)
				)
				(arc
					(start 298.599606 -293.622222)
					(mid 298.635527 -293.607343)
					(end 298.650406 -293.571422)
				)
				(arc
					(start 298.650406 -293.162482)
					(mid 298.635527 -293.126561)
					(end 298.599606 -293.111682)
				)
				(arc
					(start 297.200066 -293.111682)
					(mid 297.164145 -293.126561)
					(end 297.149266 -293.162482)
				)
			)
		)
	)
	(zone
		(layers "In1.Cu" "In2.Cu")
		(hatch none 0.5)
		(connect_pads
			(clearance 0)
		)
		(min_thickness 0.25)
		(keepout
			(tracks not_allowed)
			(vias allowed)
			(pads allowed)
			(copperpour not_allowed)
			(footprints allowed)
		)
		(placement
			(enabled no)
			(sheetname "")
		)
		(fill yes
			(thermal_gap 0.5)
			(thermal_bridge_width 0.5)
			(island_removal_mode 0)
		)
		(polygon
			(pts
				(arc
					(start 192.338198 -267.221462)
					(mid 192.353077 -267.257383)
					(end 192.388998 -267.272262)
				)
				(arc
					(start 193.788538 -267.272262)
					(mid 193.824459 -267.257383)
					(end 193.839338 -267.221462)
				)
				(arc
					(start 193.839338 -266.812522)
					(mid 193.824459 -266.776601)
					(end 193.788538 -266.761722)
				)
				(arc
					(start 192.388998 -266.761722)
					(mid 192.353077 -266.776601)
					(end 192.338198 -266.812522)
				)
			)
		)
	)
	(zone
		(layers "In1.Cu" "In2.Cu")
		(hatch none 0.5)
		(connect_pads
			(clearance 0)
		)
		(min_thickness 0.25)
		(keepout
			(tracks not_allowed)
			(vias allowed)
			(pads allowed)
			(copperpour not_allowed)
			(footprints allowed)
		)
		(placement
			(enabled no)
			(sheetname "")
		)
		(fill yes
			(thermal_gap 0.5)
			(thermal_bridge_width 0.5)
			(island_removal_mode 0)
		)
		(polygon
			(pts
				(arc
					(start 22.47773 -241.721386)
					(mid 22.492609 -241.757307)
					(end 22.52853 -241.772186)
				)
				(arc
					(start 23.92807 -241.772186)
					(mid 23.963991 -241.757307)
					(end 23.97887 -241.721386)
				)
				(arc
					(start 23.97887 -241.312446)
					(mid 23.963991 -241.276525)
					(end 23.92807 -241.261646)
				)
				(arc
					(start 22.52853 -241.261646)
					(mid 22.492609 -241.276525)
					(end 22.47773 -241.312446)
				)
			)
		)
	)
	(zone
		(layers "In1.Cu" "In2.Cu")
		(hatch none 0.5)
		(connect_pads
			(clearance 0)
		)
		(min_thickness 0.25)
		(keepout
			(tracks not_allowed)
			(vias allowed)
			(pads allowed)
			(copperpour not_allowed)
			(footprints allowed)
		)
		(placement
			(enabled no)
			(sheetname "")
		)
		(fill yes
			(thermal_gap 0.5)
			(thermal_bridge_width 0.5)
			(island_removal_mode 0)
		)
		(polygon
			(pts
				(arc
					(start 308.136798 -243.421408)
					(mid 308.151677 -243.457329)
					(end 308.187598 -243.472208)
				)
				(arc
					(start 309.587138 -243.472208)
					(mid 309.623059 -243.457329)
					(end 309.637938 -243.421408)
				)
				(arc
					(start 309.637938 -243.012468)
					(mid 309.623059 -242.976547)
					(end 309.587138 -242.961668)
				)
				(arc
					(start 308.187598 -242.961668)
					(mid 308.151677 -242.976547)
					(end 308.136798 -243.012468)
				)
			)
		)
	)
	(zone
		(layers "In1.Cu" "In2.Cu")
		(hatch none 0.5)
		(connect_pads
			(clearance 0)
		)
		(min_thickness 0.25)
		(keepout
			(tracks not_allowed)
			(vias allowed)
			(pads allowed)
			(copperpour not_allowed)
			(footprints allowed)
		)
		(placement
			(enabled no)
			(sheetname "")
		)
		(fill yes
			(thermal_gap 0.5)
			(thermal_bridge_width 0.5)
			(island_removal_mode 0)
		)
		(polygon
			(pts
				(arc
					(start 406.002998 -240.021364)
					(mid 406.017877 -240.057285)
					(end 406.053798 -240.072164)
				)
				(arc
					(start 407.453338 -240.072164)
					(mid 407.489259 -240.057285)
					(end 407.504138 -240.021364)
				)
				(arc
					(start 407.504138 -239.612424)
					(mid 407.489259 -239.576503)
					(end 407.453338 -239.561624)
				)
				(arc
					(start 406.053798 -239.561624)
					(mid 406.017877 -239.576503)
					(end 406.002998 -239.612424)
				)
			)
		)
	)
	(zone
		(layers "In1.Cu" "In2.Cu")
		(hatch none 0.5)
		(connect_pads
			(clearance 0)
		)
		(min_thickness 0.25)
		(keepout
			(tracks not_allowed)
			(vias allowed)
			(pads allowed)
			(copperpour not_allowed)
			(footprints allowed)
		)
		(placement
			(enabled no)
			(sheetname "")
		)
		(fill yes
			(thermal_gap 0.5)
			(thermal_bridge_width 0.5)
			(island_removal_mode 0)
		)
		(polygon
			(pts
				(arc
					(start 192.338198 -201.771504)
					(mid 192.353077 -201.807425)
					(end 192.388998 -201.822304)
				)
				(arc
					(start 193.788538 -201.822304)
					(mid 193.824459 -201.807425)
					(end 193.839338 -201.771504)
				)
				(arc
					(start 193.839338 -201.362564)
					(mid 193.824459 -201.326643)
					(end 193.788538 -201.311764)
				)
				(arc
					(start 192.388998 -201.311764)
					(mid 192.353077 -201.326643)
					(end 192.338198 -201.362564)
				)
			)
		)
	)
	(zone
		(layers "In1.Cu" "In2.Cu")
		(hatch none 0.5)
		(connect_pads
			(clearance 0)
		)
		(min_thickness 0.25)
		(keepout
			(tracks not_allowed)
			(vias allowed)
			(pads allowed)
			(copperpour not_allowed)
			(footprints allowed)
		)
		(placement
			(enabled no)
			(sheetname "")
		)
		(fill yes
			(thermal_gap 0.5)
			(thermal_bridge_width 0.5)
			(island_removal_mode 0)
		)
		(polygon
			(pts
				(arc
					(start 440.278266 -279.9715)
					(mid 440.293145 -280.007421)
					(end 440.329066 -280.0223)
				)
				(arc
					(start 441.728606 -280.0223)
					(mid 441.764527 -280.007421)
					(end 441.779406 -279.9715)
				)
				(arc
					(start 441.779406 -279.56256)
					(mid 441.764527 -279.526639)
					(end 441.728606 -279.51176)
				)
				(arc
					(start 440.329066 -279.51176)
					(mid 440.293145 -279.526639)
					(end 440.278266 -279.56256)
				)
			)
		)
	)
	(zone
		(layers "In1.Cu" "In2.Cu")
		(hatch none 0.5)
		(connect_pads
			(clearance 0)
		)
		(min_thickness 0.25)
		(keepout
			(tracks not_allowed)
			(vias allowed)
			(pads allowed)
			(copperpour not_allowed)
			(footprints allowed)
		)
		(placement
			(enabled no)
			(sheetname "")
		)
		(fill yes
			(thermal_gap 0.5)
			(thermal_bridge_width 0.5)
			(island_removal_mode 0)
		)
		(polygon
			(pts
				(arc
					(start 413.546798 -261.271512)
					(mid 413.561677 -261.307433)
					(end 413.597598 -261.322312)
				)
				(arc
					(start 414.997138 -261.322312)
					(mid 415.033059 -261.307433)
					(end 415.047938 -261.271512)
				)
				(arc
					(start 415.047938 -260.862572)
					(mid 415.033059 -260.826651)
					(end 414.997138 -260.811772)
				)
				(arc
					(start 413.597598 -260.811772)
					(mid 413.561677 -260.826651)
					(end 413.546798 -260.862572)
				)
			)
		)
	)
	(zone
		(layers "In1.Cu" "In2.Cu")
		(hatch none 0.5)
		(connect_pads
			(clearance 0)
		)
		(min_thickness 0.25)
		(keepout
			(tracks not_allowed)
			(vias allowed)
			(pads allowed)
			(copperpour not_allowed)
			(footprints allowed)
		)
		(placement
			(enabled no)
			(sheetname "")
		)
		(fill yes
			(thermal_gap 0.5)
			(thermal_bridge_width 0.5)
			(island_removal_mode 0)
		)
		(polygon
			(pts
				(arc
					(start 266.974066 -208.571338)
					(mid 266.988945 -208.607259)
					(end 267.024866 -208.622138)
				)
				(arc
					(start 268.424406 -208.622138)
					(mid 268.460327 -208.607259)
					(end 268.475206 -208.571338)
				)
				(arc
					(start 268.475206 -208.162398)
					(mid 268.460327 -208.126477)
					(end 268.424406 -208.111598)
				)
				(arc
					(start 267.024866 -208.111598)
					(mid 266.988945 -208.126477)
					(end 266.974066 -208.162398)
				)
			)
		)
	)
	(zone
		(layers "In1.Cu" "In2.Cu")
		(hatch none 0.5)
		(connect_pads
			(clearance 0)
		)
		(min_thickness 0.25)
		(keepout
			(tracks not_allowed)
			(vias allowed)
			(pads allowed)
			(copperpour not_allowed)
			(footprints allowed)
		)
		(placement
			(enabled no)
			(sheetname "")
		)
		(fill yes
			(thermal_gap 0.5)
			(thermal_bridge_width 0.5)
			(island_removal_mode 0)
		)
		(polygon
			(pts
				(arc
					(start 312.236866 -229.821486)
					(mid 312.251745 -229.857407)
					(end 312.287666 -229.872286)
				)
				(arc
					(start 313.687206 -229.872286)
					(mid 313.723127 -229.857407)
					(end 313.738006 -229.821486)
				)
				(arc
					(start 313.738006 -229.412546)
					(mid 313.723127 -229.376625)
					(end 313.687206 -229.361746)
				)
				(arc
					(start 312.287666 -229.361746)
					(mid 312.251745 -229.376625)
					(end 312.236866 -229.412546)
				)
			)
		)
	)
	(zone
		(layers "In1.Cu" "In2.Cu")
		(hatch none 0.5)
		(connect_pads
			(clearance 0)
		)
		(min_thickness 0.25)
		(keepout
			(tracks not_allowed)
			(vias allowed)
			(pads allowed)
			(copperpour not_allowed)
			(footprints allowed)
		)
		(placement
			(enabled no)
			(sheetname "")
		)
		(fill yes
			(thermal_gap 0.5)
			(thermal_bridge_width 0.5)
			(island_removal_mode 0)
		)
		(polygon
			(pts
				(arc
					(start 289.605466 -287.621472)
					(mid 289.620345 -287.657393)
					(end 289.656266 -287.672272)
				)
				(arc
					(start 291.055806 -287.672272)
					(mid 291.091727 -287.657393)
					(end 291.106606 -287.621472)
				)
				(arc
					(start 291.106606 -287.212532)
					(mid 291.091727 -287.176611)
					(end 291.055806 -287.161732)
				)
				(arc
					(start 289.656266 -287.161732)
					(mid 289.620345 -287.176611)
					(end 289.605466 -287.212532)
				)
			)
		)
	)
	(zone
		(layers "In1.Cu" "In2.Cu")
		(hatch none 0.5)
		(connect_pads
			(clearance 0)
		)
		(min_thickness 0.25)
		(keepout
			(tracks not_allowed)
			(vias allowed)
			(pads allowed)
			(copperpour not_allowed)
			(footprints allowed)
		)
		(placement
			(enabled no)
			(sheetname "")
		)
		(fill yes
			(thermal_gap 0.5)
			(thermal_bridge_width 0.5)
			(island_removal_mode 0)
		)
		(polygon
			(pts
				(arc
					(start 428.634398 -209.421476)
					(mid 428.649277 -209.457397)
					(end 428.685198 -209.472276)
				)
				(arc
					(start 430.084738 -209.472276)
					(mid 430.120659 -209.457397)
					(end 430.135538 -209.421476)
				)
				(arc
					(start 430.135538 -209.012536)
					(mid 430.120659 -208.976615)
					(end 430.084738 -208.961736)
				)
				(arc
					(start 428.685198 -208.961736)
					(mid 428.649277 -208.976615)
					(end 428.634398 -209.012536)
				)
			)
		)
	)
	(zone
		(layers "In1.Cu" "In2.Cu")
		(hatch none 0.5)
		(connect_pads
			(clearance 0)
		)
		(min_thickness 0.25)
		(keepout
			(tracks not_allowed)
			(vias allowed)
			(pads allowed)
			(copperpour not_allowed)
			(footprints allowed)
		)
		(placement
			(enabled no)
			(sheetname "")
		)
		(fill yes
			(thermal_gap 0.5)
			(thermal_bridge_width 0.5)
			(island_removal_mode 0)
		)
		(polygon
			(pts
				(arc
					(start 308.136798 -235.771436)
					(mid 308.151677 -235.807357)
					(end 308.187598 -235.822236)
				)
				(arc
					(start 309.587138 -235.822236)
					(mid 309.623059 -235.807357)
					(end 309.637938 -235.771436)
				)
				(arc
					(start 309.637938 -235.362496)
					(mid 309.623059 -235.326575)
					(end 309.587138 -235.311696)
				)
				(arc
					(start 308.187598 -235.311696)
					(mid 308.151677 -235.326575)
					(end 308.136798 -235.362496)
				)
			)
		)
	)
	(zone
		(layers "In1.Cu" "In2.Cu")
		(hatch none 0.5)
		(connect_pads
			(clearance 0)
		)
		(min_thickness 0.25)
		(keepout
			(tracks not_allowed)
			(vias allowed)
			(pads allowed)
			(copperpour not_allowed)
			(footprints allowed)
		)
		(placement
			(enabled no)
			(sheetname "")
		)
		(fill yes
			(thermal_gap 0.5)
			(thermal_bridge_width 0.5)
			(island_removal_mode 0)
		)
		(polygon
			(pts
				(arc
					(start 255.330198 -243.421408)
					(mid 255.345077 -243.457329)
					(end 255.380998 -243.472208)
				)
				(arc
					(start 256.780538 -243.472208)
					(mid 256.816459 -243.457329)
					(end 256.831338 -243.421408)
				)
				(arc
					(start 256.831338 -243.012468)
					(mid 256.816459 -242.976547)
					(end 256.780538 -242.961668)
				)
				(arc
					(start 255.380998 -242.961668)
					(mid 255.345077 -242.976547)
					(end 255.330198 -243.012468)
				)
			)
		)
	)
	(zone
		(layers "In1.Cu" "In2.Cu")
		(hatch none 0.5)
		(connect_pads
			(clearance 0)
		)
		(min_thickness 0.25)
		(keepout
			(tracks not_allowed)
			(vias allowed)
			(pads allowed)
			(copperpour not_allowed)
			(footprints allowed)
		)
		(placement
			(enabled no)
			(sheetname "")
		)
		(fill yes
			(thermal_gap 0.5)
			(thermal_bridge_width 0.5)
			(island_removal_mode 0)
		)
		(polygon
			(pts
				(arc
					(start 262.873998 -296.121328)
					(mid 262.888877 -296.157249)
					(end 262.924798 -296.172128)
				)
				(arc
					(start 264.324338 -296.172128)
					(mid 264.360259 -296.157249)
					(end 264.375138 -296.121328)
				)
				(arc
					(start 264.375138 -295.712388)
					(mid 264.360259 -295.676467)
					(end 264.324338 -295.661588)
				)
				(arc
					(start 262.924798 -295.661588)
					(mid 262.888877 -295.676467)
					(end 262.873998 -295.712388)
				)
			)
		)
	)
	(zone
		(layers "In1.Cu" "In2.Cu")
		(hatch none 0.5)
		(connect_pads
			(clearance 0)
		)
		(min_thickness 0.25)
		(keepout
			(tracks not_allowed)
			(vias allowed)
			(pads allowed)
			(copperpour not_allowed)
			(footprints allowed)
		)
		(placement
			(enabled no)
			(sheetname "")
		)
		(fill yes
			(thermal_gap 0.5)
			(thermal_bridge_width 0.5)
			(island_removal_mode 0)
		)
		(polygon
			(pts
				(arc
					(start 188.23813 -196.671438)
					(mid 188.253009 -196.707359)
					(end 188.28893 -196.722238)
				)
				(arc
					(start 189.68847 -196.722238)
					(mid 189.724391 -196.707359)
					(end 189.73927 -196.671438)
				)
				(arc
					(start 189.73927 -196.262498)
					(mid 189.724391 -196.226577)
					(end 189.68847 -196.211698)
				)
				(arc
					(start 188.28893 -196.211698)
					(mid 188.253009 -196.226577)
					(end 188.23813 -196.262498)
				)
			)
		)
	)
	(zone
		(layers "In1.Cu" "In2.Cu")
		(hatch none 0.5)
		(connect_pads
			(clearance 0)
		)
		(min_thickness 0.25)
		(keepout
			(tracks not_allowed)
			(vias allowed)
			(pads allowed)
			(copperpour not_allowed)
			(footprints allowed)
		)
		(placement
			(enabled no)
			(sheetname "")
		)
		(fill yes
			(thermal_gap 0.5)
			(thermal_bridge_width 0.5)
			(island_removal_mode 0)
		)
		(polygon
			(pts
				(arc
					(start 184.794398 -205.171548)
					(mid 184.809277 -205.207469)
					(end 184.845198 -205.222348)
				)
				(arc
					(start 186.244738 -205.222348)
					(mid 186.280659 -205.207469)
					(end 186.295538 -205.171548)
				)
				(arc
					(start 186.295538 -204.762608)
					(mid 186.280659 -204.726687)
					(end 186.244738 -204.711808)
				)
				(arc
					(start 184.845198 -204.711808)
					(mid 184.809277 -204.726687)
					(end 184.794398 -204.762608)
				)
			)
		)
	)
	(zone
		(layers "In1.Cu" "In2.Cu")
		(hatch none 0.5)
		(connect_pads
			(clearance 0)
		)
		(min_thickness 0.25)
		(keepout
			(tracks not_allowed)
			(vias allowed)
			(pads allowed)
			(copperpour not_allowed)
			(footprints allowed)
		)
		(placement
			(enabled no)
			(sheetname "")
		)
		(fill yes
			(thermal_gap 0.5)
			(thermal_bridge_width 0.5)
			(island_removal_mode 0)
		)
		(polygon
			(pts
				(arc
					(start 285.505398 -313.121294)
					(mid 285.520277 -313.157215)
					(end 285.556198 -313.172094)
				)
				(arc
					(start 286.955738 -313.172094)
					(mid 286.991659 -313.157215)
					(end 287.006538 -313.121294)
				)
				(arc
					(start 287.006538 -312.712354)
					(mid 286.991659 -312.676433)
					(end 286.955738 -312.661554)
				)
				(arc
					(start 285.556198 -312.661554)
					(mid 285.520277 -312.676433)
					(end 285.505398 -312.712354)
				)
			)
		)
	)
	(zone
		(layers "In1.Cu" "In2.Cu")
		(hatch none 0.5)
		(connect_pads
			(clearance 0)
		)
		(min_thickness 0.25)
		(keepout
			(tracks not_allowed)
			(vias allowed)
			(pads allowed)
			(copperpour not_allowed)
			(footprints allowed)
		)
		(placement
			(enabled no)
			(sheetname "")
		)
		(fill yes
			(thermal_gap 0.5)
			(thermal_bridge_width 0.5)
			(island_removal_mode 0)
		)
		(polygon
			(pts
				(arc
					(start 45.10913 -312.27141)
					(mid 45.124009 -312.307331)
					(end 45.15993 -312.32221)
				)
				(arc
					(start 46.55947 -312.32221)
					(mid 46.595391 -312.307331)
					(end 46.61027 -312.27141)
				)
				(arc
					(start 46.61027 -311.86247)
					(mid 46.595391 -311.826549)
					(end 46.55947 -311.81167)
				)
				(arc
					(start 45.15993 -311.81167)
					(mid 45.124009 -311.826549)
					(end 45.10913 -311.86247)
				)
			)
		)
	)
	(zone
		(layers "In1.Cu" "In2.Cu")
		(hatch none 0.5)
		(connect_pads
			(clearance 0)
		)
		(min_thickness 0.25)
		(keepout
			(tracks not_allowed)
			(vias allowed)
			(pads allowed)
			(copperpour not_allowed)
			(footprints allowed)
		)
		(placement
			(enabled no)
			(sheetname "")
		)
		(fill yes
			(thermal_gap 0.5)
			(thermal_bridge_width 0.5)
			(island_removal_mode 0)
		)
		(polygon
			(pts
				(arc
					(start 37.56533 -294.421306)
					(mid 37.580209 -294.457227)
					(end 37.61613 -294.472106)
				)
				(arc
					(start 39.01567 -294.472106)
					(mid 39.051591 -294.457227)
					(end 39.06647 -294.421306)
				)
				(arc
					(start 39.06647 -294.012366)
					(mid 39.051591 -293.976445)
					(end 39.01567 -293.961566)
				)
				(arc
					(start 37.61613 -293.961566)
					(mid 37.580209 -293.976445)
					(end 37.56533 -294.012366)
				)
			)
		)
	)
	(zone
		(layers "In1.Cu" "In2.Cu")
		(hatch none 0.5)
		(connect_pads
			(clearance 0)
		)
		(min_thickness 0.25)
		(keepout
			(tracks not_allowed)
			(vias allowed)
			(pads allowed)
			(copperpour not_allowed)
			(footprints allowed)
		)
		(placement
			(enabled no)
			(sheetname "")
		)
		(fill yes
			(thermal_gap 0.5)
			(thermal_bridge_width 0.5)
			(island_removal_mode 0)
		)
		(polygon
			(pts
				(arc
					(start 458.809598 -213.671404)
					(mid 458.824477 -213.707325)
					(end 458.860398 -213.722204)
				)
				(arc
					(start 460.259938 -213.722204)
					(mid 460.295859 -213.707325)
					(end 460.310738 -213.671404)
				)
				(arc
					(start 460.310738 -213.262464)
					(mid 460.295859 -213.226543)
					(end 460.259938 -213.211664)
				)
				(arc
					(start 458.860398 -213.211664)
					(mid 458.824477 -213.226543)
					(end 458.809598 -213.262464)
				)
			)
		)
	)
	(zone
		(layers "In1.Cu" "In2.Cu")
		(hatch none 0.5)
		(connect_pads
			(clearance 0)
		)
		(min_thickness 0.25)
		(keepout
			(tracks not_allowed)
			(vias allowed)
			(pads allowed)
			(copperpour not_allowed)
			(footprints allowed)
		)
		(placement
			(enabled no)
			(sheetname "")
		)
		(fill yes
			(thermal_gap 0.5)
			(thermal_bridge_width 0.5)
			(island_removal_mode 0)
		)
		(polygon
			(pts
				(arc
					(start 417.646866 -263.821418)
					(mid 417.661745 -263.857339)
					(end 417.697666 -263.872218)
				)
				(arc
					(start 419.097206 -263.872218)
					(mid 419.133127 -263.857339)
					(end 419.148006 -263.821418)
				)
				(arc
					(start 419.148006 -263.412478)
					(mid 419.133127 -263.376557)
					(end 419.097206 -263.361678)
				)
				(arc
					(start 417.697666 -263.361678)
					(mid 417.661745 -263.376557)
					(end 417.646866 -263.412478)
				)
			)
		)
	)
	(zone
		(layers "In1.Cu" "In2.Cu")
		(hatch none 0.5)
		(connect_pads
			(clearance 0)
		)
		(min_thickness 0.25)
		(keepout
			(tracks not_allowed)
			(vias allowed)
			(pads allowed)
			(copperpour not_allowed)
			(footprints allowed)
		)
		(placement
			(enabled no)
			(sheetname "")
		)
		(fill yes
			(thermal_gap 0.5)
			(thermal_bridge_width 0.5)
			(island_removal_mode 0)
		)
		(polygon
			(pts
				(arc
					(start 173.15053 -313.121294)
					(mid 173.165409 -313.157215)
					(end 173.20133 -313.172094)
				)
				(arc
					(start 174.60087 -313.172094)
					(mid 174.636791 -313.157215)
					(end 174.65167 -313.121294)
				)
				(arc
					(start 174.65167 -312.712354)
					(mid 174.636791 -312.676433)
					(end 174.60087 -312.661554)
				)
				(arc
					(start 173.20133 -312.661554)
					(mid 173.165409 -312.676433)
					(end 173.15053 -312.712354)
				)
			)
		)
	)
	(zone
		(layers "In1.Cu" "In2.Cu")
		(hatch none 0.5)
		(connect_pads
			(clearance 0)
		)
		(min_thickness 0.25)
		(keepout
			(tracks not_allowed)
			(vias allowed)
			(pads allowed)
			(copperpour not_allowed)
			(footprints allowed)
		)
		(placement
			(enabled no)
			(sheetname "")
		)
		(fill yes
			(thermal_gap 0.5)
			(thermal_bridge_width 0.5)
			(island_removal_mode 0)
		)
		(polygon
			(pts
				(arc
					(start 285.505398 -312.27141)
					(mid 285.520277 -312.307331)
					(end 285.556198 -312.32221)
				)
				(arc
					(start 286.955738 -312.32221)
					(mid 286.991659 -312.307331)
					(end 287.006538 -312.27141)
				)
				(arc
					(start 287.006538 -311.86247)
					(mid 286.991659 -311.826549)
					(end 286.955738 -311.81167)
				)
				(arc
					(start 285.556198 -311.81167)
					(mid 285.520277 -311.826549)
					(end 285.505398 -311.86247)
				)
			)
		)
	)
	(zone
		(layers "In1.Cu" "In2.Cu")
		(hatch none 0.5)
		(connect_pads
			(clearance 0)
		)
		(min_thickness 0.25)
		(keepout
			(tracks not_allowed)
			(vias allowed)
			(pads allowed)
			(copperpour not_allowed)
			(footprints allowed)
		)
		(placement
			(enabled no)
			(sheetname "")
		)
		(fill yes
			(thermal_gap 0.5)
			(thermal_bridge_width 0.5)
			(island_removal_mode 0)
		)
		(polygon
			(pts
				(arc
					(start 410.103066 -200.071482)
					(mid 410.117945 -200.107403)
					(end 410.153866 -200.122282)
				)
				(arc
					(start 411.553406 -200.122282)
					(mid 411.589327 -200.107403)
					(end 411.604206 -200.071482)
				)
				(arc
					(start 411.604206 -199.662542)
					(mid 411.589327 -199.626621)
					(end 411.553406 -199.611742)
				)
				(arc
					(start 410.153866 -199.611742)
					(mid 410.117945 -199.626621)
					(end 410.103066 -199.662542)
				)
			)
		)
	)
	(zone
		(layers "In1.Cu" "In2.Cu")
		(hatch none 0.5)
		(connect_pads
			(clearance 0)
		)
		(min_thickness 0.25)
		(keepout
			(tracks not_allowed)
			(vias allowed)
			(pads allowed)
			(copperpour not_allowed)
			(footprints allowed)
		)
		(placement
			(enabled no)
			(sheetname "")
		)
		(fill yes
			(thermal_gap 0.5)
			(thermal_bridge_width 0.5)
			(island_removal_mode 0)
		)
		(polygon
			(pts
				(arc
					(start 169.706798 -195.821554)
					(mid 169.721677 -195.857475)
					(end 169.757598 -195.872354)
				)
				(arc
					(start 171.157138 -195.872354)
					(mid 171.193059 -195.857475)
					(end 171.207938 -195.821554)
				)
				(arc
					(start 171.207938 -195.412614)
					(mid 171.193059 -195.376693)
					(end 171.157138 -195.361814)
				)
				(arc
					(start 169.757598 -195.361814)
					(mid 169.721677 -195.376693)
					(end 169.706798 -195.412614)
				)
			)
		)
	)
	(zone
		(layers "In1.Cu" "In2.Cu")
		(hatch none 0.5)
		(connect_pads
			(clearance 0)
		)
		(min_thickness 0.25)
		(keepout
			(tracks not_allowed)
			(vias allowed)
			(pads allowed)
			(copperpour not_allowed)
			(footprints allowed)
		)
		(placement
			(enabled no)
			(sheetname "")
		)
		(fill yes
			(thermal_gap 0.5)
			(thermal_bridge_width 0.5)
			(island_removal_mode 0)
		)
		(polygon
			(pts
				(arc
					(start 410.103066 -293.571422)
					(mid 410.117945 -293.607343)
					(end 410.153866 -293.622222)
				)
				(arc
					(start 411.553406 -293.622222)
					(mid 411.589327 -293.607343)
					(end 411.604206 -293.571422)
				)
				(arc
					(start 411.604206 -293.162482)
					(mid 411.589327 -293.126561)
					(end 411.553406 -293.111682)
				)
				(arc
					(start 410.153866 -293.111682)
					(mid 410.117945 -293.126561)
					(end 410.103066 -293.162482)
				)
			)
		)
	)
	(zone
		(layers "In1.Cu" "In2.Cu")
		(hatch none 0.5)
		(connect_pads
			(clearance 0)
		)
		(min_thickness 0.25)
		(keepout
			(tracks not_allowed)
			(vias allowed)
			(pads allowed)
			(copperpour not_allowed)
			(footprints allowed)
		)
		(placement
			(enabled no)
			(sheetname "")
		)
		(fill yes
			(thermal_gap 0.5)
			(thermal_bridge_width 0.5)
			(island_removal_mode 0)
		)
		(polygon
			(pts
				(arc
					(start 64.296798 -281.671522)
					(mid 64.311677 -281.707443)
					(end 64.347598 -281.722322)
				)
				(arc
					(start 65.747138 -281.722322)
					(mid 65.783059 -281.707443)
					(end 65.797938 -281.671522)
				)
				(arc
					(start 65.797938 -281.262582)
					(mid 65.783059 -281.226661)
					(end 65.747138 -281.211782)
				)
				(arc
					(start 64.347598 -281.211782)
					(mid 64.311677 -281.226661)
					(end 64.296798 -281.262582)
				)
			)
		)
	)
	(zone
		(layers "In1.Cu" "In2.Cu")
		(hatch none 0.5)
		(connect_pads
			(clearance 0)
		)
		(min_thickness 0.25)
		(keepout
			(tracks not_allowed)
			(vias allowed)
			(pads allowed)
			(copperpour not_allowed)
			(footprints allowed)
		)
		(placement
			(enabled no)
			(sheetname "")
		)
		(fill yes
			(thermal_gap 0.5)
			(thermal_bridge_width 0.5)
			(island_removal_mode 0)
		)
		(polygon
			(pts
				(arc
					(start 177.250598 -250.221496)
					(mid 177.265477 -250.257417)
					(end 177.301398 -250.272296)
				)
				(arc
					(start 178.700938 -250.272296)
					(mid 178.736859 -250.257417)
					(end 178.751738 -250.221496)
				)
				(arc
					(start 178.751738 -249.812556)
					(mid 178.736859 -249.776635)
					(end 178.700938 -249.761756)
				)
				(arc
					(start 177.301398 -249.761756)
					(mid 177.265477 -249.776635)
					(end 177.250598 -249.812556)
				)
			)
		)
	)
	(zone
		(layers "In1.Cu" "In2.Cu")
		(hatch none 0.5)
		(connect_pads
			(clearance 0)
		)
		(min_thickness 0.25)
		(keepout
			(tracks not_allowed)
			(vias allowed)
			(pads allowed)
			(copperpour not_allowed)
			(footprints allowed)
		)
		(placement
			(enabled no)
			(sheetname "")
		)
		(fill yes
			(thermal_gap 0.5)
			(thermal_bridge_width 0.5)
			(island_removal_mode 0)
		)
		(polygon
			(pts
				(arc
					(start 417.646866 -312.27141)
					(mid 417.661745 -312.307331)
					(end 417.697666 -312.32221)
				)
				(arc
					(start 419.097206 -312.32221)
					(mid 419.133127 -312.307331)
					(end 419.148006 -312.27141)
				)
				(arc
					(start 419.148006 -311.86247)
					(mid 419.133127 -311.826549)
					(end 419.097206 -311.81167)
				)
				(arc
					(start 417.697666 -311.81167)
					(mid 417.661745 -311.826549)
					(end 417.646866 -311.86247)
				)
			)
		)
	)
	(zone
		(layers "In1.Cu" "In2.Cu")
		(hatch none 0.5)
		(connect_pads
			(clearance 0)
		)
		(min_thickness 0.25)
		(keepout
			(tracks not_allowed)
			(vias allowed)
			(pads allowed)
			(copperpour not_allowed)
			(footprints allowed)
		)
		(placement
			(enabled no)
			(sheetname "")
		)
		(fill yes
			(thermal_gap 0.5)
			(thermal_bridge_width 0.5)
			(island_removal_mode 0)
		)
		(polygon
			(pts
				(arc
					(start 274.517866 -313.971432)
					(mid 274.532745 -314.007353)
					(end 274.568666 -314.022232)
				)
				(arc
					(start 275.968206 -314.022232)
					(mid 276.004127 -314.007353)
					(end 276.019006 -313.971432)
				)
				(arc
					(start 276.019006 -313.562492)
					(mid 276.004127 -313.526571)
					(end 275.968206 -313.511692)
				)
				(arc
					(start 274.568666 -313.511692)
					(mid 274.532745 -313.526571)
					(end 274.517866 -313.562492)
				)
			)
		)
	)
	(zone
		(layers "In1.Cu" "In2.Cu")
		(hatch none 0.5)
		(connect_pads
			(clearance 0)
		)
		(min_thickness 0.25)
		(keepout
			(tracks not_allowed)
			(vias allowed)
			(pads allowed)
			(copperpour not_allowed)
			(footprints allowed)
		)
		(placement
			(enabled no)
			(sheetname "")
		)
		(fill yes
			(thermal_gap 0.5)
			(thermal_bridge_width 0.5)
			(island_removal_mode 0)
		)
		(polygon
			(pts
				(arc
					(start 34.121598 -233.22153)
					(mid 34.136477 -233.257451)
					(end 34.172398 -233.27233)
				)
				(arc
					(start 35.571938 -233.27233)
					(mid 35.607859 -233.257451)
					(end 35.622738 -233.22153)
				)
				(arc
					(start 35.622738 -232.81259)
					(mid 35.607859 -232.776669)
					(end 35.571938 -232.76179)
				)
				(arc
					(start 34.172398 -232.76179)
					(mid 34.136477 -232.776669)
					(end 34.121598 -232.81259)
				)
			)
		)
	)
	(zone
		(layers "In1.Cu" "In2.Cu")
		(hatch none 0.5)
		(connect_pads
			(clearance 0)
		)
		(min_thickness 0.25)
		(keepout
			(tracks not_allowed)
			(vias allowed)
			(pads allowed)
			(copperpour not_allowed)
			(footprints allowed)
		)
		(placement
			(enabled no)
			(sheetname "")
		)
		(fill yes
			(thermal_gap 0.5)
			(thermal_bridge_width 0.5)
			(island_removal_mode 0)
		)
		(polygon
			(pts
				(arc
					(start 56.752998 -211.121498)
					(mid 56.767877 -211.157419)
					(end 56.803798 -211.172298)
				)
				(arc
					(start 58.203338 -211.172298)
					(mid 58.239259 -211.157419)
					(end 58.254138 -211.121498)
				)
				(arc
					(start 58.254138 -210.712558)
					(mid 58.239259 -210.676637)
					(end 58.203338 -210.661758)
				)
				(arc
					(start 56.803798 -210.661758)
					(mid 56.767877 -210.676637)
					(end 56.752998 -210.712558)
				)
			)
		)
	)
	(zone
		(layers "In1.Cu" "In2.Cu")
		(hatch none 0.5)
		(connect_pads
			(clearance 0)
		)
		(min_thickness 0.25)
		(keepout
			(tracks not_allowed)
			(vias allowed)
			(pads allowed)
			(copperpour not_allowed)
			(footprints allowed)
		)
		(placement
			(enabled no)
			(sheetname "")
		)
		(fill yes
			(thermal_gap 0.5)
			(thermal_bridge_width 0.5)
			(island_removal_mode 0)
		)
		(polygon
			(pts
				(arc
					(start 289.605466 -298.671488)
					(mid 289.620345 -298.707409)
					(end 289.656266 -298.722288)
				)
				(arc
					(start 291.055806 -298.722288)
					(mid 291.091727 -298.707409)
					(end 291.106606 -298.671488)
				)
				(arc
					(start 291.106606 -298.262548)
					(mid 291.091727 -298.226627)
					(end 291.055806 -298.211748)
				)
				(arc
					(start 289.656266 -298.211748)
					(mid 289.620345 -298.226627)
					(end 289.605466 -298.262548)
				)
			)
		)
	)
	(zone
		(layers "In1.Cu" "In2.Cu")
		(hatch none 0.5)
		(connect_pads
			(clearance 0)
		)
		(min_thickness 0.25)
		(keepout
			(tracks not_allowed)
			(vias allowed)
			(pads allowed)
			(copperpour not_allowed)
			(footprints allowed)
		)
		(placement
			(enabled no)
			(sheetname "")
		)
		(fill yes
			(thermal_gap 0.5)
			(thermal_bridge_width 0.5)
			(island_removal_mode 0)
		)
		(polygon
			(pts
				(arc
					(start 64.296798 -246.821452)
					(mid 64.311677 -246.857373)
					(end 64.347598 -246.872252)
				)
				(arc
					(start 65.747138 -246.872252)
					(mid 65.783059 -246.857373)
					(end 65.797938 -246.821452)
				)
				(arc
					(start 65.797938 -246.412512)
					(mid 65.783059 -246.376591)
					(end 65.747138 -246.361712)
				)
				(arc
					(start 64.347598 -246.361712)
					(mid 64.311677 -246.376591)
					(end 64.296798 -246.412512)
				)
			)
		)
	)
	(zone
		(layers "In1.Cu" "In2.Cu")
		(hatch none 0.5)
		(connect_pads
			(clearance 0)
		)
		(min_thickness 0.25)
		(keepout
			(tracks not_allowed)
			(vias allowed)
			(pads allowed)
			(copperpour not_allowed)
			(footprints allowed)
		)
		(placement
			(enabled no)
			(sheetname "")
		)
		(fill yes
			(thermal_gap 0.5)
			(thermal_bridge_width 0.5)
			(island_removal_mode 0)
		)
		(polygon
			(pts
				(arc
					(start 425.190666 -302.921416)
					(mid 425.205545 -302.957337)
					(end 425.241466 -302.972216)
				)
				(arc
					(start 426.641006 -302.972216)
					(mid 426.676927 -302.957337)
					(end 426.691806 -302.921416)
				)
				(arc
					(start 426.691806 -302.512476)
					(mid 426.676927 -302.476555)
					(end 426.641006 -302.461676)
				)
				(arc
					(start 425.241466 -302.461676)
					(mid 425.205545 -302.476555)
					(end 425.190666 -302.512476)
				)
			)
		)
	)
	(zone
		(layers "In1.Cu" "In2.Cu")
		(hatch none 0.5)
		(connect_pads
			(clearance 0)
		)
		(min_thickness 0.25)
		(keepout
			(tracks not_allowed)
			(vias allowed)
			(pads allowed)
			(copperpour not_allowed)
			(footprints allowed)
		)
		(placement
			(enabled no)
			(sheetname "")
		)
		(fill yes
			(thermal_gap 0.5)
			(thermal_bridge_width 0.5)
			(island_removal_mode 0)
		)
		(polygon
			(pts
				(arc
					(start 428.634398 -266.371324)
					(mid 428.649277 -266.407245)
					(end 428.685198 -266.422124)
				)
				(arc
					(start 430.084738 -266.422124)
					(mid 430.120659 -266.407245)
					(end 430.135538 -266.371324)
				)
				(arc
					(start 430.135538 -265.962384)
					(mid 430.120659 -265.926463)
					(end 430.084738 -265.911584)
				)
				(arc
					(start 428.685198 -265.911584)
					(mid 428.649277 -265.926463)
					(end 428.634398 -265.962384)
				)
			)
		)
	)
	(zone
		(layers "In1.Cu" "In2.Cu")
		(hatch none 0.5)
		(connect_pads
			(clearance 0)
		)
		(min_thickness 0.25)
		(keepout
			(tracks not_allowed)
			(vias allowed)
			(pads allowed)
			(copperpour not_allowed)
			(footprints allowed)
		)
		(placement
			(enabled no)
			(sheetname "")
		)
		(fill yes
			(thermal_gap 0.5)
			(thermal_bridge_width 0.5)
			(island_removal_mode 0)
		)
		(polygon
			(pts
				(arc
					(start 49.209198 -218.77147)
					(mid 49.224077 -218.807391)
					(end 49.259998 -218.82227)
				)
				(arc
					(start 50.659538 -218.82227)
					(mid 50.695459 -218.807391)
					(end 50.710338 -218.77147)
				)
				(arc
					(start 50.710338 -218.36253)
					(mid 50.695459 -218.326609)
					(end 50.659538 -218.31173)
				)
				(arc
					(start 49.259998 -218.31173)
					(mid 49.224077 -218.326609)
					(end 49.209198 -218.36253)
				)
			)
		)
	)
	(zone
		(layers "In1.Cu" "In2.Cu")
		(hatch none 0.5)
		(connect_pads
			(clearance 0)
		)
		(min_thickness 0.25)
		(keepout
			(tracks not_allowed)
			(vias allowed)
			(pads allowed)
			(copperpour not_allowed)
			(footprints allowed)
		)
		(placement
			(enabled no)
			(sheetname "")
		)
		(fill yes
			(thermal_gap 0.5)
			(thermal_bridge_width 0.5)
			(island_removal_mode 0)
		)
		(polygon
			(pts
				(arc
					(start 462.909666 -306.32146)
					(mid 462.924545 -306.357381)
					(end 462.960466 -306.37226)
				)
				(arc
					(start 464.360006 -306.37226)
					(mid 464.395927 -306.357381)
					(end 464.410806 -306.32146)
				)
				(arc
					(start 464.410806 -305.91252)
					(mid 464.395927 -305.876599)
					(end 464.360006 -305.86172)
				)
				(arc
					(start 462.960466 -305.86172)
					(mid 462.924545 -305.876599)
					(end 462.909666 -305.91252)
				)
			)
		)
	)
	(zone
		(layers "In1.Cu" "In2.Cu")
		(hatch none 0.5)
		(connect_pads
			(clearance 0)
		)
		(min_thickness 0.25)
		(keepout
			(tracks not_allowed)
			(vias allowed)
			(pads allowed)
			(copperpour not_allowed)
			(footprints allowed)
		)
		(placement
			(enabled no)
			(sheetname "")
		)
		(fill yes
			(thermal_gap 0.5)
			(thermal_bridge_width 0.5)
			(island_removal_mode 0)
		)
		(polygon
			(pts
				(arc
					(start 7.39013 -275.721318)
					(mid 7.405009 -275.757239)
					(end 7.44093 -275.772118)
				)
				(arc
					(start 8.84047 -275.772118)
					(mid 8.876391 -275.757239)
					(end 8.89127 -275.721318)
				)
				(arc
					(start 8.89127 -275.312378)
					(mid 8.876391 -275.276457)
					(end 8.84047 -275.261578)
				)
				(arc
					(start 7.44093 -275.261578)
					(mid 7.405009 -275.276457)
					(end 7.39013 -275.312378)
				)
			)
		)
	)
	(zone
		(layers "In1.Cu" "In2.Cu")
		(hatch none 0.5)
		(connect_pads
			(clearance 0)
		)
		(min_thickness 0.25)
		(keepout
			(tracks not_allowed)
			(vias allowed)
			(pads allowed)
			(copperpour not_allowed)
			(footprints allowed)
		)
		(placement
			(enabled no)
			(sheetname "")
		)
		(fill yes
			(thermal_gap 0.5)
			(thermal_bridge_width 0.5)
			(island_removal_mode 0)
		)
		(polygon
			(pts
				(arc
					(start 455.365866 -206.871316)
					(mid 455.380745 -206.907237)
					(end 455.416666 -206.922116)
				)
				(arc
					(start 456.816206 -206.922116)
					(mid 456.852127 -206.907237)
					(end 456.867006 -206.871316)
				)
				(arc
					(start 456.867006 -206.462376)
					(mid 456.852127 -206.426455)
					(end 456.816206 -206.411576)
				)
				(arc
					(start 455.416666 -206.411576)
					(mid 455.380745 -206.426455)
					(end 455.365866 -206.462376)
				)
			)
		)
	)
	(zone
		(layers "In1.Cu" "In2.Cu")
		(hatch none 0.5)
		(connect_pads
			(clearance 0)
		)
		(min_thickness 0.25)
		(keepout
			(tracks not_allowed)
			(vias allowed)
			(pads allowed)
			(copperpour not_allowed)
			(footprints allowed)
		)
		(placement
			(enabled no)
			(sheetname "")
		)
		(fill yes
			(thermal_gap 0.5)
			(thermal_bridge_width 0.5)
			(island_removal_mode 0)
		)
		(polygon
			(pts
				(arc
					(start 312.236866 -306.32146)
					(mid 312.251745 -306.357381)
					(end 312.287666 -306.37226)
				)
				(arc
					(start 313.687206 -306.37226)
					(mid 313.723127 -306.357381)
					(end 313.738006 -306.32146)
				)
				(arc
					(start 313.738006 -305.91252)
					(mid 313.723127 -305.876599)
					(end 313.687206 -305.86172)
				)
				(arc
					(start 312.287666 -305.86172)
					(mid 312.251745 -305.876599)
					(end 312.236866 -305.91252)
				)
			)
		)
	)
	(zone
		(layers "In1.Cu" "In2.Cu")
		(hatch none 0.5)
		(connect_pads
			(clearance 0)
		)
		(min_thickness 0.25)
		(keepout
			(tracks not_allowed)
			(vias allowed)
			(pads allowed)
			(copperpour not_allowed)
			(footprints allowed)
		)
		(placement
			(enabled no)
			(sheetname "")
		)
		(fill yes
			(thermal_gap 0.5)
			(thermal_bridge_width 0.5)
			(island_removal_mode 0)
		)
		(polygon
			(pts
				(arc
					(start 214.969598 -251.921518)
					(mid 214.984477 -251.957439)
					(end 215.020398 -251.972318)
				)
				(arc
					(start 216.419938 -251.972318)
					(mid 216.455859 -251.957439)
					(end 216.470738 -251.921518)
				)
				(arc
					(start 216.470738 -251.512578)
					(mid 216.455859 -251.476657)
					(end 216.419938 -251.461778)
				)
				(arc
					(start 215.020398 -251.461778)
					(mid 214.984477 -251.476657)
					(end 214.969598 -251.512578)
				)
			)
		)
	)
	(zone
		(layers "In1.Cu" "In2.Cu")
		(hatch none 0.5)
		(connect_pads
			(clearance 0)
		)
		(min_thickness 0.25)
		(keepout
			(tracks not_allowed)
			(vias allowed)
			(pads allowed)
			(copperpour not_allowed)
			(footprints allowed)
		)
		(placement
			(enabled no)
			(sheetname "")
		)
		(fill yes
			(thermal_gap 0.5)
			(thermal_bridge_width 0.5)
			(island_removal_mode 0)
		)
		(polygon
			(pts
				(arc
					(start 188.23813 -277.42134)
					(mid 188.253009 -277.457261)
					(end 188.28893 -277.47214)
				)
				(arc
					(start 189.68847 -277.47214)
					(mid 189.724391 -277.457261)
					(end 189.73927 -277.42134)
				)
				(arc
					(start 189.73927 -277.0124)
					(mid 189.724391 -276.976479)
					(end 189.68847 -276.9616)
				)
				(arc
					(start 188.28893 -276.9616)
					(mid 188.253009 -276.976479)
					(end 188.23813 -277.0124)
				)
			)
		)
	)
	(zone
		(layers "In1.Cu" "In2.Cu")
		(hatch none 0.5)
		(connect_pads
			(clearance 0)
		)
		(min_thickness 0.25)
		(keepout
			(tracks not_allowed)
			(vias allowed)
			(pads allowed)
			(copperpour not_allowed)
			(footprints allowed)
		)
		(placement
			(enabled no)
			(sheetname "")
		)
		(fill yes
			(thermal_gap 0.5)
			(thermal_bridge_width 0.5)
			(island_removal_mode 0)
		)
		(polygon
			(pts
				(arc
					(start 188.23813 -271.47139)
					(mid 188.253009 -271.507311)
					(end 188.28893 -271.52219)
				)
				(arc
					(start 189.68847 -271.52219)
					(mid 189.724391 -271.507311)
					(end 189.73927 -271.47139)
				)
				(arc
					(start 189.73927 -271.06245)
					(mid 189.724391 -271.026529)
					(end 189.68847 -271.01165)
				)
				(arc
					(start 188.28893 -271.01165)
					(mid 188.253009 -271.026529)
					(end 188.23813 -271.06245)
				)
			)
		)
	)
	(zone
		(layers "In1.Cu" "In2.Cu")
		(hatch none 0.5)
		(connect_pads
			(clearance 0)
		)
		(min_thickness 0.25)
		(keepout
			(tracks not_allowed)
			(vias allowed)
			(pads allowed)
			(copperpour not_allowed)
			(footprints allowed)
		)
		(placement
			(enabled no)
			(sheetname "")
		)
		(fill yes
			(thermal_gap 0.5)
			(thermal_bridge_width 0.5)
			(island_removal_mode 0)
		)
		(polygon
			(pts
				(arc
					(start 440.278266 -300.37151)
					(mid 440.293145 -300.407431)
					(end 440.329066 -300.42231)
				)
				(arc
					(start 441.728606 -300.42231)
					(mid 441.764527 -300.407431)
					(end 441.779406 -300.37151)
				)
				(arc
					(start 441.779406 -299.96257)
					(mid 441.764527 -299.926649)
					(end 441.728606 -299.91177)
				)
				(arc
					(start 440.329066 -299.91177)
					(mid 440.293145 -299.926649)
					(end 440.278266 -299.96257)
				)
			)
		)
	)
	(zone
		(layers "In1.Cu" "In2.Cu")
		(hatch none 0.5)
		(connect_pads
			(clearance 0)
		)
		(min_thickness 0.25)
		(keepout
			(tracks not_allowed)
			(vias allowed)
			(pads allowed)
			(copperpour not_allowed)
			(footprints allowed)
		)
		(placement
			(enabled no)
			(sheetname "")
		)
		(fill yes
			(thermal_gap 0.5)
			(thermal_bridge_width 0.5)
			(island_removal_mode 0)
		)
		(polygon
			(pts
				(arc
					(start 447.822066 -234.921298)
					(mid 447.836945 -234.957219)
					(end 447.872866 -234.972098)
				)
				(arc
					(start 449.272406 -234.972098)
					(mid 449.308327 -234.957219)
					(end 449.323206 -234.921298)
				)
				(arc
					(start 449.323206 -234.512358)
					(mid 449.308327 -234.476437)
					(end 449.272406 -234.461558)
				)
				(arc
					(start 447.872866 -234.461558)
					(mid 447.836945 -234.476437)
					(end 447.822066 -234.512358)
				)
			)
		)
	)
	(zone
		(layers "In1.Cu" "In2.Cu")
		(hatch none 0.5)
		(connect_pads
			(clearance 0)
		)
		(min_thickness 0.25)
		(keepout
			(tracks not_allowed)
			(vias allowed)
			(pads allowed)
			(copperpour not_allowed)
			(footprints allowed)
		)
		(placement
			(enabled no)
			(sheetname "")
		)
		(fill yes
			(thermal_gap 0.5)
			(thermal_bridge_width 0.5)
			(island_removal_mode 0)
		)
		(polygon
			(pts
				(arc
					(start 22.47773 -252.771402)
					(mid 22.492609 -252.807323)
					(end 22.52853 -252.822202)
				)
				(arc
					(start 23.92807 -252.822202)
					(mid 23.963991 -252.807323)
					(end 23.97887 -252.771402)
				)
				(arc
					(start 23.97887 -252.362462)
					(mid 23.963991 -252.326541)
					(end 23.92807 -252.311662)
				)
				(arc
					(start 22.52853 -252.311662)
					(mid 22.492609 -252.326541)
					(end 22.47773 -252.362462)
				)
			)
		)
	)
	(zone
		(layers "In1.Cu" "In2.Cu")
		(hatch none 0.5)
		(connect_pads
			(clearance 0)
		)
		(min_thickness 0.25)
		(keepout
			(tracks not_allowed)
			(vias allowed)
			(pads allowed)
			(copperpour not_allowed)
			(footprints allowed)
		)
		(placement
			(enabled no)
			(sheetname "")
		)
		(fill yes
			(thermal_gap 0.5)
			(thermal_bridge_width 0.5)
			(island_removal_mode 0)
		)
		(polygon
			(pts
				(arc
					(start 14.93393 -286.771334)
					(mid 14.948809 -286.807255)
					(end 14.98473 -286.822134)
				)
				(arc
					(start 16.38427 -286.822134)
					(mid 16.420191 -286.807255)
					(end 16.43507 -286.771334)
				)
				(arc
					(start 16.43507 -286.362394)
					(mid 16.420191 -286.326473)
					(end 16.38427 -286.311594)
				)
				(arc
					(start 14.98473 -286.311594)
					(mid 14.948809 -286.326473)
					(end 14.93393 -286.362394)
				)
			)
		)
	)
	(zone
		(layers "In1.Cu" "In2.Cu")
		(hatch none 0.5)
		(connect_pads
			(clearance 0)
		)
		(min_thickness 0.25)
		(keepout
			(tracks not_allowed)
			(vias allowed)
			(pads allowed)
			(copperpour not_allowed)
			(footprints allowed)
		)
		(placement
			(enabled no)
			(sheetname "")
		)
		(fill yes
			(thermal_gap 0.5)
			(thermal_bridge_width 0.5)
			(island_removal_mode 0)
		)
		(polygon
			(pts
				(arc
					(start 184.794398 -211.121498)
					(mid 184.809277 -211.157419)
					(end 184.845198 -211.172298)
				)
				(arc
					(start 186.244738 -211.172298)
					(mid 186.280659 -211.157419)
					(end 186.295538 -211.121498)
				)
				(arc
					(start 186.295538 -210.712558)
					(mid 186.280659 -210.676637)
					(end 186.244738 -210.661758)
				)
				(arc
					(start 184.845198 -210.661758)
					(mid 184.809277 -210.676637)
					(end 184.794398 -210.712558)
				)
			)
		)
	)
	(zone
		(layers "In1.Cu" "In2.Cu")
		(hatch none 0.5)
		(connect_pads
			(clearance 0)
		)
		(min_thickness 0.25)
		(keepout
			(tracks not_allowed)
			(vias allowed)
			(pads allowed)
			(copperpour not_allowed)
			(footprints allowed)
		)
		(placement
			(enabled no)
			(sheetname "")
		)
		(fill yes
			(thermal_gap 0.5)
			(thermal_bridge_width 0.5)
			(island_removal_mode 0)
		)
		(polygon
			(pts
				(arc
					(start 406.002998 -294.421306)
					(mid 406.017877 -294.457227)
					(end 406.053798 -294.472106)
				)
				(arc
					(start 407.453338 -294.472106)
					(mid 407.489259 -294.457227)
					(end 407.504138 -294.421306)
				)
				(arc
					(start 407.504138 -294.012366)
					(mid 407.489259 -293.976445)
					(end 407.453338 -293.961566)
				)
				(arc
					(start 406.053798 -293.961566)
					(mid 406.017877 -293.976445)
					(end 406.002998 -294.012366)
				)
			)
		)
	)
	(zone
		(layers "In1.Cu" "In2.Cu")
		(hatch none 0.5)
		(connect_pads
			(clearance 0)
		)
		(min_thickness 0.25)
		(keepout
			(tracks not_allowed)
			(vias allowed)
			(pads allowed)
			(copperpour not_allowed)
			(footprints allowed)
		)
		(placement
			(enabled no)
			(sheetname "")
		)
		(fill yes
			(thermal_gap 0.5)
			(thermal_bridge_width 0.5)
			(island_removal_mode 0)
		)
		(polygon
			(pts
				(arc
					(start 266.974066 -284.221428)
					(mid 266.988945 -284.257349)
					(end 267.024866 -284.272228)
				)
				(arc
					(start 268.424406 -284.272228)
					(mid 268.460327 -284.257349)
					(end 268.475206 -284.221428)
				)
				(arc
					(start 268.475206 -283.812488)
					(mid 268.460327 -283.776567)
					(end 268.424406 -283.761688)
				)
				(arc
					(start 267.024866 -283.761688)
					(mid 266.988945 -283.776567)
					(end 266.974066 -283.812488)
				)
			)
		)
	)
	(zone
		(layers "In1.Cu" "In2.Cu")
		(hatch none 0.5)
		(connect_pads
			(clearance 0)
		)
		(min_thickness 0.25)
		(keepout
			(tracks not_allowed)
			(vias allowed)
			(pads allowed)
			(copperpour not_allowed)
			(footprints allowed)
		)
		(placement
			(enabled no)
			(sheetname "")
		)
		(fill yes
			(thermal_gap 0.5)
			(thermal_bridge_width 0.5)
			(island_removal_mode 0)
		)
		(polygon
			(pts
				(arc
					(start 199.881998 -240.871502)
					(mid 199.896877 -240.907423)
					(end 199.932798 -240.922302)
				)
				(arc
					(start 201.332338 -240.922302)
					(mid 201.368259 -240.907423)
					(end 201.383138 -240.871502)
				)
				(arc
					(start 201.383138 -240.462562)
					(mid 201.368259 -240.426641)
					(end 201.332338 -240.411762)
				)
				(arc
					(start 199.932798 -240.411762)
					(mid 199.896877 -240.426641)
					(end 199.881998 -240.462562)
				)
			)
		)
	)
	(zone
		(layers "In1.Cu" "In2.Cu")
		(hatch none 0.5)
		(connect_pads
			(clearance 0)
		)
		(min_thickness 0.25)
		(keepout
			(tracks not_allowed)
			(vias allowed)
			(pads allowed)
			(copperpour not_allowed)
			(footprints allowed)
		)
		(placement
			(enabled no)
			(sheetname "")
		)
		(fill yes
			(thermal_gap 0.5)
			(thermal_bridge_width 0.5)
			(island_removal_mode 0)
		)
		(polygon
			(pts
				(arc
					(start 462.909666 -250.221496)
					(mid 462.924545 -250.257417)
					(end 462.960466 -250.272296)
				)
				(arc
					(start 464.360006 -250.272296)
					(mid 464.395927 -250.257417)
					(end 464.410806 -250.221496)
				)
				(arc
					(start 464.410806 -249.812556)
					(mid 464.395927 -249.776635)
					(end 464.360006 -249.761756)
				)
				(arc
					(start 462.960466 -249.761756)
					(mid 462.924545 -249.776635)
					(end 462.909666 -249.812556)
				)
			)
		)
	)
	(zone
		(layers "In1.Cu" "In2.Cu")
		(hatch none 0.5)
		(connect_pads
			(clearance 0)
		)
		(min_thickness 0.25)
		(keepout
			(tracks not_allowed)
			(vias allowed)
			(pads allowed)
			(copperpour not_allowed)
			(footprints allowed)
		)
		(placement
			(enabled no)
			(sheetname "")
		)
		(fill yes
			(thermal_gap 0.5)
			(thermal_bridge_width 0.5)
			(island_removal_mode 0)
		)
		(polygon
			(pts
				(arc
					(start 60.19673 -235.771436)
					(mid 60.211609 -235.807357)
					(end 60.24753 -235.822236)
				)
				(arc
					(start 61.64707 -235.822236)
					(mid 61.682991 -235.807357)
					(end 61.69787 -235.771436)
				)
				(arc
					(start 61.69787 -235.362496)
					(mid 61.682991 -235.326575)
					(end 61.64707 -235.311696)
				)
				(arc
					(start 60.24753 -235.311696)
					(mid 60.211609 -235.326575)
					(end 60.19673 -235.362496)
				)
			)
		)
	)
	(zone
		(layers "In1.Cu" "In2.Cu")
		(hatch none 0.5)
		(connect_pads
			(clearance 0)
		)
		(min_thickness 0.25)
		(keepout
			(tracks not_allowed)
			(vias allowed)
			(pads allowed)
			(copperpour not_allowed)
			(footprints allowed)
		)
		(placement
			(enabled no)
			(sheetname "")
		)
		(fill yes
			(thermal_gap 0.5)
			(thermal_bridge_width 0.5)
			(island_removal_mode 0)
		)
		(polygon
			(pts
				(arc
					(start 428.634398 -215.371426)
					(mid 428.649277 -215.407347)
					(end 428.685198 -215.422226)
				)
				(arc
					(start 430.084738 -215.422226)
					(mid 430.120659 -215.407347)
					(end 430.135538 -215.371426)
				)
				(arc
					(start 430.135538 -214.962486)
					(mid 430.120659 -214.926565)
					(end 430.084738 -214.911686)
				)
				(arc
					(start 428.685198 -214.911686)
					(mid 428.649277 -214.926565)
					(end 428.634398 -214.962486)
				)
			)
		)
	)
	(zone
		(layers "In1.Cu" "In2.Cu")
		(hatch none 0.5)
		(connect_pads
			(clearance 0)
		)
		(min_thickness 0.25)
		(keepout
			(tracks not_allowed)
			(vias allowed)
			(pads allowed)
			(copperpour not_allowed)
			(footprints allowed)
		)
		(placement
			(enabled no)
			(sheetname "")
		)
		(fill yes
			(thermal_gap 0.5)
			(thermal_bridge_width 0.5)
			(island_removal_mode 0)
		)
		(polygon
			(pts
				(arc
					(start 282.061666 -246.821452)
					(mid 282.076545 -246.857373)
					(end 282.112466 -246.872252)
				)
				(arc
					(start 283.512006 -246.872252)
					(mid 283.547927 -246.857373)
					(end 283.562806 -246.821452)
				)
				(arc
					(start 283.562806 -246.412512)
					(mid 283.547927 -246.376591)
					(end 283.512006 -246.361712)
				)
				(arc
					(start 282.112466 -246.361712)
					(mid 282.076545 -246.376591)
					(end 282.061666 -246.412512)
				)
			)
		)
	)
	(zone
		(layers "In1.Cu" "In2.Cu")
		(hatch none 0.5)
		(connect_pads
			(clearance 0)
		)
		(min_thickness 0.25)
		(keepout
			(tracks not_allowed)
			(vias allowed)
			(pads allowed)
			(copperpour not_allowed)
			(footprints allowed)
		)
		(placement
			(enabled no)
			(sheetname "")
		)
		(fill yes
			(thermal_gap 0.5)
			(thermal_bridge_width 0.5)
			(island_removal_mode 0)
		)
		(polygon
			(pts
				(arc
					(start 282.061666 -208.571338)
					(mid 282.076545 -208.607259)
					(end 282.112466 -208.622138)
				)
				(arc
					(start 283.512006 -208.622138)
					(mid 283.547927 -208.607259)
					(end 283.562806 -208.571338)
				)
				(arc
					(start 283.562806 -208.162398)
					(mid 283.547927 -208.126477)
					(end 283.512006 -208.111598)
				)
				(arc
					(start 282.112466 -208.111598)
					(mid 282.076545 -208.126477)
					(end 282.061666 -208.162398)
				)
			)
		)
	)
	(zone
		(layers "In1.Cu" "In2.Cu")
		(hatch none 0.5)
		(connect_pads
			(clearance 0)
		)
		(min_thickness 0.25)
		(keepout
			(tracks not_allowed)
			(vias allowed)
			(pads allowed)
			(copperpour not_allowed)
			(footprints allowed)
		)
		(placement
			(enabled no)
			(sheetname "")
		)
		(fill yes
			(thermal_gap 0.5)
			(thermal_bridge_width 0.5)
			(island_removal_mode 0)
		)
		(polygon
			(pts
				(arc
					(start 199.881998 -278.271478)
					(mid 199.896877 -278.307399)
					(end 199.932798 -278.322278)
				)
				(arc
					(start 201.332338 -278.322278)
					(mid 201.368259 -278.307399)
					(end 201.383138 -278.271478)
				)
				(arc
					(start 201.383138 -277.862538)
					(mid 201.368259 -277.826617)
					(end 201.332338 -277.811738)
				)
				(arc
					(start 199.932798 -277.811738)
					(mid 199.896877 -277.826617)
					(end 199.881998 -277.862538)
				)
			)
		)
	)
	(zone
		(layers "In1.Cu" "In2.Cu")
		(hatch none 0.5)
		(connect_pads
			(clearance 0)
		)
		(min_thickness 0.25)
		(keepout
			(tracks not_allowed)
			(vias allowed)
			(pads allowed)
			(copperpour not_allowed)
			(footprints allowed)
		)
		(placement
			(enabled no)
			(sheetname "")
		)
		(fill yes
			(thermal_gap 0.5)
			(thermal_bridge_width 0.5)
			(island_removal_mode 0)
		)
		(polygon
			(pts
				(arc
					(start 45.10913 -294.421306)
					(mid 45.124009 -294.457227)
					(end 45.15993 -294.472106)
				)
				(arc
					(start 46.55947 -294.472106)
					(mid 46.595391 -294.457227)
					(end 46.61027 -294.421306)
				)
				(arc
					(start 46.61027 -294.012366)
					(mid 46.595391 -293.976445)
					(end 46.55947 -293.961566)
				)
				(arc
					(start 45.15993 -293.961566)
					(mid 45.124009 -293.976445)
					(end 45.10913 -294.012366)
				)
			)
		)
	)
	(zone
		(layers "In1.Cu" "In2.Cu")
		(hatch none 0.5)
		(connect_pads
			(clearance 0)
		)
		(min_thickness 0.25)
		(keepout
			(tracks not_allowed)
			(vias allowed)
			(pads allowed)
			(copperpour not_allowed)
			(footprints allowed)
		)
		(placement
			(enabled no)
			(sheetname "")
		)
		(fill yes
			(thermal_gap 0.5)
			(thermal_bridge_width 0.5)
			(island_removal_mode 0)
		)
		(polygon
			(pts
				(arc
					(start 406.002998 -310.571388)
					(mid 406.017877 -310.607309)
					(end 406.053798 -310.622188)
				)
				(arc
					(start 407.453338 -310.622188)
					(mid 407.489259 -310.607309)
					(end 407.504138 -310.571388)
				)
				(arc
					(start 407.504138 -310.162448)
					(mid 407.489259 -310.126527)
					(end 407.453338 -310.111648)
				)
				(arc
					(start 406.053798 -310.111648)
					(mid 406.017877 -310.126527)
					(end 406.002998 -310.162448)
				)
			)
		)
	)
	(zone
		(layers "In1.Cu" "In2.Cu")
		(hatch none 0.5)
		(connect_pads
			(clearance 0)
		)
		(min_thickness 0.25)
		(keepout
			(tracks not_allowed)
			(vias allowed)
			(pads allowed)
			(copperpour not_allowed)
			(footprints allowed)
		)
		(placement
			(enabled no)
			(sheetname "")
		)
		(fill yes
			(thermal_gap 0.5)
			(thermal_bridge_width 0.5)
			(island_removal_mode 0)
		)
		(polygon
			(pts
				(arc
					(start 255.330198 -244.271292)
					(mid 255.345077 -244.307213)
					(end 255.380998 -244.322092)
				)
				(arc
					(start 256.780538 -244.322092)
					(mid 256.816459 -244.307213)
					(end 256.831338 -244.271292)
				)
				(arc
					(start 256.831338 -243.862352)
					(mid 256.816459 -243.826431)
					(end 256.780538 -243.811552)
				)
				(arc
					(start 255.380998 -243.811552)
					(mid 255.345077 -243.826431)
					(end 255.330198 -243.862352)
				)
			)
		)
	)
	(zone
		(layers "In1.Cu" "In2.Cu")
		(hatch none 0.5)
		(connect_pads
			(clearance 0)
		)
		(min_thickness 0.25)
		(keepout
			(tracks not_allowed)
			(vias allowed)
			(pads allowed)
			(copperpour not_allowed)
			(footprints allowed)
		)
		(placement
			(enabled no)
			(sheetname "")
		)
		(fill yes
			(thermal_gap 0.5)
			(thermal_bridge_width 0.5)
			(island_removal_mode 0)
		)
		(polygon
			(pts
				(arc
					(start 188.23813 -223.021398)
					(mid 188.253009 -223.057319)
					(end 188.28893 -223.072198)
				)
				(arc
					(start 189.68847 -223.072198)
					(mid 189.724391 -223.057319)
					(end 189.73927 -223.021398)
				)
				(arc
					(start 189.73927 -222.612458)
					(mid 189.724391 -222.576537)
					(end 189.68847 -222.561658)
				)
				(arc
					(start 188.28893 -222.561658)
					(mid 188.253009 -222.576537)
					(end 188.23813 -222.612458)
				)
			)
		)
	)
	(zone
		(layers "In1.Cu" "In2.Cu")
		(hatch none 0.5)
		(connect_pads
			(clearance 0)
		)
		(min_thickness 0.25)
		(keepout
			(tracks not_allowed)
			(vias allowed)
			(pads allowed)
			(copperpour not_allowed)
			(footprints allowed)
		)
		(placement
			(enabled no)
			(sheetname "")
		)
		(fill yes
			(thermal_gap 0.5)
			(thermal_bridge_width 0.5)
			(island_removal_mode 0)
		)
		(polygon
			(pts
				(arc
					(start 289.605466 -218.77147)
					(mid 289.620345 -218.807391)
					(end 289.656266 -218.82227)
				)
				(arc
					(start 291.055806 -218.82227)
					(mid 291.091727 -218.807391)
					(end 291.106606 -218.77147)
				)
				(arc
					(start 291.106606 -218.36253)
					(mid 291.091727 -218.326609)
					(end 291.055806 -218.31173)
				)
				(arc
					(start 289.656266 -218.31173)
					(mid 289.620345 -218.326609)
					(end 289.605466 -218.36253)
				)
			)
		)
	)
	(zone
		(layers "In1.Cu" "In2.Cu" "In3.Cu" "In4.Cu" "In5.Cu" "In6.Cu" "In7.Cu"
			"In8.Cu" "In9.Cu" "In10.Cu" "In11.Cu" "In12.Cu" "In13.Cu" "In14.Cu" "In15.Cu"
			"In16.Cu"
		)
		(hatch none 0.5)
		(connect_pads
			(clearance 0)
		)
		(min_thickness 0.25)
		(keepout
			(tracks not_allowed)
			(vias allowed)
			(pads allowed)
			(copperpour not_allowed)
			(footprints allowed)
		)
		(placement
			(enabled no)
			(sheetname "")
		)
		(fill yes
			(thermal_gap 0.5)
			(thermal_bridge_width 0.5)
			(island_removal_mode 0)
		)
		(polygon
			(pts
				(arc
					(start 281.4955 -393.533884)
					(mid 279.7175 -393.533884)
					(end 281.4955 -393.533884)
				)
			)
		)
	)
	(zone
		(layers "In1.Cu" "In2.Cu" "In3.Cu" "In4.Cu" "In5.Cu" "In6.Cu" "In7.Cu"
			"In8.Cu" "In9.Cu" "In10.Cu" "In11.Cu" "In12.Cu" "In13.Cu" "In14.Cu" "In15.Cu"
			"In16.Cu"
		)
		(hatch none 0.5)
		(connect_pads
			(clearance 0)
		)
		(min_thickness 0.25)
		(keepout
			(tracks not_allowed)
			(vias allowed)
			(pads allowed)
			(copperpour not_allowed)
			(footprints allowed)
		)
		(placement
			(enabled no)
			(sheetname "")
		)
		(fill yes
			(thermal_gap 0.5)
			(thermal_bridge_width 0.5)
			(island_removal_mode 0)
		)
		(polygon
			(pts
				(arc
					(start 268.698472 -394.808456)
					(mid 266.920472 -394.808456)
					(end 268.698472 -394.808456)
				)
			)
		)
	)
	(zone
		(layers "In1.Cu" "In2.Cu" "In3.Cu" "In4.Cu" "In5.Cu" "In6.Cu" "In7.Cu"
			"In8.Cu" "In9.Cu" "In10.Cu" "In11.Cu" "In12.Cu" "In13.Cu" "In14.Cu" "In15.Cu"
			"In16.Cu"
		)
		(hatch none 0.5)
		(connect_pads
			(clearance 0)
		)
		(min_thickness 0.25)
		(keepout
			(tracks not_allowed)
			(vias allowed)
			(pads allowed)
			(copperpour not_allowed)
			(footprints allowed)
		)
		(placement
			(enabled no)
			(sheetname "")
		)
		(fill yes
			(thermal_gap 0.5)
			(thermal_bridge_width 0.5)
			(island_removal_mode 0)
		)
		(polygon
			(pts
				(arc
					(start 258.098544 -394.808456)
					(mid 256.320544 -394.808456)
					(end 258.098544 -394.808456)
				)
			)
		)
	)
	(zone
		(layers "In1.Cu" "In2.Cu" "In3.Cu" "In4.Cu" "In5.Cu" "In6.Cu" "In7.Cu"
			"In8.Cu" "In9.Cu" "In10.Cu" "In11.Cu" "In12.Cu" "In13.Cu" "In14.Cu" "In15.Cu"
			"In16.Cu"
		)
		(hatch none 0.5)
		(connect_pads
			(clearance 0)
		)
		(min_thickness 0.25)
		(keepout
			(tracks not_allowed)
			(vias allowed)
			(pads allowed)
			(copperpour not_allowed)
			(footprints allowed)
		)
		(placement
			(enabled no)
			(sheetname "")
		)
		(fill yes
			(thermal_gap 0.5)
			(thermal_bridge_width 0.5)
			(island_removal_mode 0)
		)
		(polygon
			(pts
				(arc
					(start 269.968472 -394.808456)
					(mid 268.190472 -394.808456)
					(end 269.968472 -394.808456)
				)
			)
		)
	)
	(zone
		(layers "In1.Cu" "In2.Cu" "In3.Cu" "In4.Cu" "In5.Cu" "In6.Cu" "In7.Cu"
			"In8.Cu" "In9.Cu" "In10.Cu" "In11.Cu" "In12.Cu" "In13.Cu" "In14.Cu" "In15.Cu"
			"In16.Cu"
		)
		(hatch none 0.5)
		(connect_pads
			(clearance 0)
		)
		(min_thickness 0.25)
		(keepout
			(tracks not_allowed)
			(vias allowed)
			(pads allowed)
			(copperpour not_allowed)
			(footprints allowed)
		)
		(placement
			(enabled no)
			(sheetname "")
		)
		(fill yes
			(thermal_gap 0.5)
			(thermal_bridge_width 0.5)
			(island_removal_mode 0)
		)
		(polygon
			(pts
				(arc
					(start 256.828544 -394.808456)
					(mid 255.050544 -394.808456)
					(end 256.828544 -394.808456)
				)
			)
		)
	)
	(zone
		(layers "In1.Cu" "In2.Cu" "In3.Cu" "In4.Cu" "In5.Cu" "In6.Cu" "In7.Cu"
			"In8.Cu" "In9.Cu" "In10.Cu" "In11.Cu" "In12.Cu" "In13.Cu" "In14.Cu" "In15.Cu"
			"In16.Cu"
		)
		(hatch none 0.5)
		(connect_pads
			(clearance 0)
		)
		(min_thickness 0.25)
		(keepout
			(tracks not_allowed)
			(vias allowed)
			(pads allowed)
			(copperpour not_allowed)
			(footprints allowed)
		)
		(placement
			(enabled no)
			(sheetname "")
		)
		(fill yes
			(thermal_gap 0.5)
			(thermal_bridge_width 0.5)
			(island_removal_mode 0)
		)
		(polygon
			(pts
				(arc
					(start 264.033508 -394.808456)
					(mid 262.255508 -394.808456)
					(end 264.033508 -394.808456)
				)
			)
		)
	)
	(zone
		(layers "In1.Cu" "In2.Cu" "In3.Cu" "In4.Cu" "In5.Cu" "In6.Cu" "In7.Cu"
			"In8.Cu" "In9.Cu" "In10.Cu" "In11.Cu" "In12.Cu" "In13.Cu" "In14.Cu" "In15.Cu"
			"In16.Cu"
		)
		(hatch none 0.5)
		(connect_pads
			(clearance 0)
		)
		(min_thickness 0.25)
		(keepout
			(tracks not_allowed)
			(vias allowed)
			(pads allowed)
			(copperpour not_allowed)
			(footprints allowed)
		)
		(placement
			(enabled no)
			(sheetname "")
		)
		(fill yes
			(thermal_gap 0.5)
			(thermal_bridge_width 0.5)
			(island_removal_mode 0)
		)
		(polygon
			(pts
				(arc
					(start 262.763508 -394.808456)
					(mid 260.985508 -394.808456)
					(end 262.763508 -394.808456)
				)
			)
		)
	)
	(zone
		(layers "In1.Cu" "In2.Cu" "In3.Cu" "In4.Cu" "In5.Cu" "In6.Cu" "In7.Cu"
			"In8.Cu" "In9.Cu" "In10.Cu" "In11.Cu" "In12.Cu" "In13.Cu" "In14.Cu" "In15.Cu"
			"In16.Cu"
		)
		(hatch none 0.5)
		(connect_pads
			(clearance 0)
		)
		(min_thickness 0.25)
		(keepout
			(tracks not_allowed)
			(vias allowed)
			(pads allowed)
			(copperpour not_allowed)
			(footprints allowed)
		)
		(placement
			(enabled no)
			(sheetname "")
		)
		(fill yes
			(thermal_gap 0.5)
			(thermal_bridge_width 0.5)
			(island_removal_mode 0)
		)
		(polygon
			(pts
				(arc
					(start 246.228616 -394.808456)
					(mid 244.450616 -394.808456)
					(end 246.228616 -394.808456)
				)
			)
		)
	)
	(zone
		(layers "In1.Cu" "In2.Cu" "In3.Cu" "In4.Cu" "In5.Cu" "In6.Cu" "In7.Cu"
			"In8.Cu" "In9.Cu" "In10.Cu" "In11.Cu" "In12.Cu" "In13.Cu" "In14.Cu" "In15.Cu"
			"In16.Cu"
		)
		(hatch none 0.5)
		(connect_pads
			(clearance 0)
		)
		(min_thickness 0.25)
		(keepout
			(tracks not_allowed)
			(vias allowed)
			(pads allowed)
			(copperpour not_allowed)
			(footprints allowed)
		)
		(placement
			(enabled no)
			(sheetname "")
		)
		(fill yes
			(thermal_gap 0.5)
			(thermal_bridge_width 0.5)
			(island_removal_mode 0)
		)
		(polygon
			(pts
				(arc
					(start 244.958616 -394.808456)
					(mid 243.180616 -394.808456)
					(end 244.958616 -394.808456)
				)
			)
		)
	)
	(zone
		(layers "In1.Cu" "In2.Cu" "In3.Cu" "In4.Cu" "In5.Cu" "In6.Cu" "In7.Cu"
			"In8.Cu" "In9.Cu" "In10.Cu" "In11.Cu" "In12.Cu" "In13.Cu" "In14.Cu" "In15.Cu"
			"In16.Cu"
		)
		(hatch none 0.5)
		(connect_pads
			(clearance 0)
		)
		(min_thickness 0.25)
		(keepout
			(tracks not_allowed)
			(vias allowed)
			(pads allowed)
			(copperpour not_allowed)
			(footprints allowed)
		)
		(placement
			(enabled no)
			(sheetname "")
		)
		(fill yes
			(thermal_gap 0.5)
			(thermal_bridge_width 0.5)
			(island_removal_mode 0)
		)
		(polygon
			(pts
				(arc
					(start 274.633436 -394.808456)
					(mid 272.855436 -394.808456)
					(end 274.633436 -394.808456)
				)
			)
		)
	)
	(zone
		(layers "In1.Cu" "In2.Cu" "In3.Cu" "In4.Cu" "In5.Cu" "In6.Cu" "In7.Cu"
			"In8.Cu" "In9.Cu" "In10.Cu" "In11.Cu" "In12.Cu" "In13.Cu" "In14.Cu" "In15.Cu"
			"In16.Cu"
		)
		(hatch none 0.5)
		(connect_pads
			(clearance 0)
		)
		(min_thickness 0.25)
		(keepout
			(tracks not_allowed)
			(vias allowed)
			(pads allowed)
			(copperpour not_allowed)
			(footprints allowed)
		)
		(placement
			(enabled no)
			(sheetname "")
		)
		(fill yes
			(thermal_gap 0.5)
			(thermal_bridge_width 0.5)
			(island_removal_mode 0)
		)
		(polygon
			(pts
				(arc
					(start 280.6954 -394.808456)
					(mid 278.9174 -394.808456)
					(end 280.6954 -394.808456)
				)
			)
		)
	)
	(zone
		(layers "In1.Cu" "In2.Cu" "In3.Cu" "In4.Cu" "In5.Cu" "In6.Cu" "In7.Cu"
			"In8.Cu" "In9.Cu" "In10.Cu" "In11.Cu" "In12.Cu" "In13.Cu" "In14.Cu" "In15.Cu"
			"In16.Cu"
		)
		(hatch none 0.5)
		(connect_pads
			(clearance 0)
		)
		(min_thickness 0.25)
		(keepout
			(tracks not_allowed)
			(vias allowed)
			(pads allowed)
			(copperpour not_allowed)
			(footprints allowed)
		)
		(placement
			(enabled no)
			(sheetname "")
		)
		(fill yes
			(thermal_gap 0.5)
			(thermal_bridge_width 0.5)
			(island_removal_mode 0)
		)
		(polygon
			(pts
				(arc
					(start 252.16358 -394.808456)
					(mid 250.38558 -394.808456)
					(end 252.16358 -394.808456)
				)
			)
		)
	)
	(zone
		(layers "In1.Cu" "In2.Cu" "In3.Cu" "In4.Cu" "In5.Cu" "In6.Cu" "In7.Cu"
			"In8.Cu" "In9.Cu" "In10.Cu" "In11.Cu" "In12.Cu" "In13.Cu" "In14.Cu" "In15.Cu"
			"In16.Cu"
		)
		(hatch none 0.5)
		(connect_pads
			(clearance 0)
		)
		(min_thickness 0.25)
		(keepout
			(tracks not_allowed)
			(vias allowed)
			(pads allowed)
			(copperpour not_allowed)
			(footprints allowed)
		)
		(placement
			(enabled no)
			(sheetname "")
		)
		(fill yes
			(thermal_gap 0.5)
			(thermal_bridge_width 0.5)
			(island_removal_mode 0)
		)
		(polygon
			(pts
				(arc
					(start 275.903436 -394.808456)
					(mid 274.125436 -394.808456)
					(end 275.903436 -394.808456)
				)
			)
		)
	)
	(zone
		(layers "In1.Cu" "In2.Cu" "In3.Cu" "In4.Cu" "In5.Cu" "In6.Cu" "In7.Cu"
			"In8.Cu" "In9.Cu" "In10.Cu" "In11.Cu" "In12.Cu" "In13.Cu" "In14.Cu" "In15.Cu"
			"In16.Cu"
		)
		(hatch none 0.5)
		(connect_pads
			(clearance 0)
		)
		(min_thickness 0.25)
		(keepout
			(tracks not_allowed)
			(vias allowed)
			(pads allowed)
			(copperpour not_allowed)
			(footprints allowed)
		)
		(placement
			(enabled no)
			(sheetname "")
		)
		(fill yes
			(thermal_gap 0.5)
			(thermal_bridge_width 0.5)
			(island_removal_mode 0)
		)
		(polygon
			(pts
				(arc
					(start 250.89358 -394.808456)
					(mid 249.11558 -394.808456)
					(end 250.89358 -394.808456)
				)
			)
		)
	)
	(zone
		(layers "In1.Cu" "In2.Cu" "In3.Cu" "In4.Cu" "In5.Cu" "In6.Cu" "In7.Cu"
			"In8.Cu" "In9.Cu" "In10.Cu" "In12.Cu" "In13.Cu" "In14.Cu" "In15.Cu" "In16.Cu"
		)
		(hatch none 0.5)
		(connect_pads
			(clearance 0)
		)
		(min_thickness 0.25)
		(keepout
			(tracks not_allowed)
			(vias allowed)
			(pads allowed)
			(copperpour not_allowed)
			(footprints allowed)
		)
		(placement
			(enabled no)
			(sheetname "")
		)
		(fill yes
			(thermal_gap 0.5)
			(thermal_bridge_width 0.5)
			(island_removal_mode 0)
		)
		(polygon
			(pts
				(arc
					(start 122.212608 -361.133136)
					(mid 121.44756 -361.133136)
					(end 122.212608 -361.133136)
				)
			)
		)
	)
	(zone
		(layers "In1.Cu" "In3.Cu" "In5.Cu" "In7.Cu" "In8.Cu" "In9.Cu" "In10.Cu"
			"In12.Cu" "In14.Cu" "In15.Cu" "In16.Cu"
		)
		(hatch none 0.5)
		(connect_pads
			(clearance 0)
		)
		(min_thickness 0.25)
		(keepout
			(tracks not_allowed)
			(vias allowed)
			(pads allowed)
			(copperpour not_allowed)
			(footprints allowed)
		)
		(placement
			(enabled no)
			(sheetname "")
		)
		(fill yes
			(thermal_gap 0.5)
			(thermal_bridge_width 0.5)
			(island_removal_mode 0)
		)
		(polygon
			(pts
				(arc
					(start 293.163498 -399.983452)
					(mid 292.147498 -399.983452)
					(end 293.163498 -399.983452)
				)
			)
		)
	)
	(zone
		(layers "In1.Cu" "In3.Cu" "In5.Cu" "In7.Cu" "In8.Cu" "In9.Cu" "In10.Cu"
			"In12.Cu" "In14.Cu" "In15.Cu" "In16.Cu"
		)
		(hatch none 0.5)
		(connect_pads
			(clearance 0)
		)
		(min_thickness 0.25)
		(keepout
			(tracks not_allowed)
			(vias allowed)
			(pads allowed)
			(copperpour not_allowed)
			(footprints allowed)
		)
		(placement
			(enabled no)
			(sheetname "")
		)
		(fill yes
			(thermal_gap 0.5)
			(thermal_bridge_width 0.5)
			(island_removal_mode 0)
		)
		(polygon
			(pts
				(arc
					(start 298.85513 -402.015452)
					(mid 297.83913 -402.015452)
					(end 298.85513 -402.015452)
				)
			)
		)
	)
	(zone
		(layers "In1.Cu" "In3.Cu" "In5.Cu" "In7.Cu" "In8.Cu" "In9.Cu" "In10.Cu"
			"In12.Cu" "In14.Cu" "In15.Cu" "In16.Cu"
		)
		(hatch none 0.5)
		(connect_pads
			(clearance 0)
		)
		(min_thickness 0.25)
		(keepout
			(tracks not_allowed)
			(vias allowed)
			(pads allowed)
			(copperpour not_allowed)
			(footprints allowed)
		)
		(placement
			(enabled no)
			(sheetname "")
		)
		(fill yes
			(thermal_gap 0.5)
			(thermal_bridge_width 0.5)
			(island_removal_mode 0)
		)
		(polygon
			(pts
				(arc
					(start 298.09313 -399.983452)
					(mid 297.07713 -399.983452)
					(end 298.09313 -399.983452)
				)
			)
		)
	)
	(zone
		(layers "In1.Cu" "In3.Cu" "In5.Cu" "In7.Cu" "In8.Cu" "In9.Cu" "In10.Cu"
			"In12.Cu" "In14.Cu" "In15.Cu" "In16.Cu"
		)
		(hatch none 0.5)
		(connect_pads
			(clearance 0)
		)
		(min_thickness 0.25)
		(keepout
			(tracks not_allowed)
			(vias allowed)
			(pads allowed)
			(copperpour not_allowed)
			(footprints allowed)
		)
		(placement
			(enabled no)
			(sheetname "")
		)
		(fill yes
			(thermal_gap 0.5)
			(thermal_bridge_width 0.5)
			(island_removal_mode 0)
		)
		(polygon
			(pts
				(arc
					(start 288.083498 -404.047452)
					(mid 287.067498 -404.047452)
					(end 288.083498 -404.047452)
				)
			)
		)
	)
	(zone
		(layers "In1.Cu" "In3.Cu" "In5.Cu" "In7.Cu" "In8.Cu" "In9.Cu" "In10.Cu"
			"In12.Cu" "In14.Cu" "In15.Cu" "In16.Cu"
		)
		(hatch none 0.5)
		(connect_pads
			(clearance 0)
		)
		(min_thickness 0.25)
		(keepout
			(tracks not_allowed)
			(vias allowed)
			(pads allowed)
			(copperpour not_allowed)
			(footprints allowed)
		)
		(placement
			(enabled no)
			(sheetname "")
		)
		(fill yes
			(thermal_gap 0.5)
			(thermal_bridge_width 0.5)
			(island_removal_mode 0)
		)
		(polygon
			(pts
				(arc
					(start 290.49726 -394.44168)
					(mid 289.48126 -394.44168)
					(end 290.49726 -394.44168)
				)
			)
		)
	)
	(zone
		(layers "In1.Cu" "In3.Cu" "In5.Cu" "In7.Cu" "In8.Cu" "In9.Cu" "In10.Cu"
			"In12.Cu" "In14.Cu" "In15.Cu" "In16.Cu"
		)
		(hatch none 0.5)
		(connect_pads
			(clearance 0)
		)
		(min_thickness 0.25)
		(keepout
			(tracks not_allowed)
			(vias allowed)
			(pads allowed)
			(copperpour not_allowed)
			(footprints allowed)
		)
		(placement
			(enabled no)
			(sheetname "")
		)
		(fill yes
			(thermal_gap 0.5)
			(thermal_bridge_width 0.5)
			(island_removal_mode 0)
		)
		(polygon
			(pts
				(arc
					(start 293.48811 -393.776454)
					(mid 292.47211 -393.776454)
					(end 293.48811 -393.776454)
				)
			)
		)
	)
	(zone
		(layers "In1.Cu" "In3.Cu" "In5.Cu" "In7.Cu" "In8.Cu" "In9.Cu" "In10.Cu"
			"In12.Cu" "In14.Cu" "In15.Cu" "In16.Cu"
		)
		(hatch none 0.5)
		(connect_pads
			(clearance 0)
		)
		(min_thickness 0.25)
		(keepout
			(tracks not_allowed)
			(vias allowed)
			(pads allowed)
			(copperpour not_allowed)
			(footprints allowed)
		)
		(placement
			(enabled no)
			(sheetname "")
		)
		(fill yes
			(thermal_gap 0.5)
			(thermal_bridge_width 0.5)
			(island_removal_mode 0)
		)
		(polygon
			(pts
				(arc
					(start 296.31513 -402.015452)
					(mid 295.29913 -402.015452)
					(end 296.31513 -402.015452)
				)
			)
		)
	)
	(zone
		(layers "In1.Cu" "In3.Cu" "In5.Cu" "In7.Cu" "In8.Cu" "In9.Cu" "In10.Cu"
			"In12.Cu" "In14.Cu" "In15.Cu" "In16.Cu"
		)
		(hatch none 0.5)
		(connect_pads
			(clearance 0)
		)
		(min_thickness 0.25)
		(keepout
			(tracks not_allowed)
			(vias allowed)
			(pads allowed)
			(copperpour not_allowed)
			(footprints allowed)
		)
		(placement
			(enabled no)
			(sheetname "")
		)
		(fill yes
			(thermal_gap 0.5)
			(thermal_bridge_width 0.5)
			(island_removal_mode 0)
		)
		(polygon
			(pts
				(arc
					(start 296.31513 -399.983452)
					(mid 295.29913 -399.983452)
					(end 296.31513 -399.983452)
				)
			)
		)
	)
	(zone
		(layers "In1.Cu" "In3.Cu" "In5.Cu" "In7.Cu" "In8.Cu" "In9.Cu" "In10.Cu"
			"In12.Cu" "In14.Cu" "In15.Cu" "In16.Cu"
		)
		(hatch none 0.5)
		(connect_pads
			(clearance 0)
		)
		(min_thickness 0.25)
		(keepout
			(tracks not_allowed)
			(vias allowed)
			(pads allowed)
			(copperpour not_allowed)
			(footprints allowed)
		)
		(placement
			(enabled no)
			(sheetname "")
		)
		(fill yes
			(thermal_gap 0.5)
			(thermal_bridge_width 0.5)
			(island_removal_mode 0)
		)
		(polygon
			(pts
				(arc
					(start 293.163498 -402.015452)
					(mid 292.147498 -402.015452)
					(end 293.163498 -402.015452)
				)
			)
		)
	)
	(zone
		(layers "In1.Cu" "In3.Cu" "In5.Cu" "In7.Cu" "In8.Cu" "In9.Cu" "In10.Cu"
			"In12.Cu" "In14.Cu" "In15.Cu" "In16.Cu"
		)
		(hatch none 0.5)
		(connect_pads
			(clearance 0)
		)
		(min_thickness 0.25)
		(keepout
			(tracks not_allowed)
			(vias allowed)
			(pads allowed)
			(copperpour not_allowed)
			(footprints allowed)
		)
		(placement
			(enabled no)
			(sheetname "")
		)
		(fill yes
			(thermal_gap 0.5)
			(thermal_bridge_width 0.5)
			(island_removal_mode 0)
		)
		(polygon
			(pts
				(arc
					(start 294.488108 -393.776454)
					(mid 293.472108 -393.776454)
					(end 294.488108 -393.776454)
				)
			)
		)
	)
	(zone
		(layers "In1.Cu" "In3.Cu" "In5.Cu" "In7.Cu" "In8.Cu" "In9.Cu" "In10.Cu"
			"In12.Cu" "In14.Cu" "In15.Cu" "In16.Cu"
		)
		(hatch none 0.5)
		(connect_pads
			(clearance 0)
		)
		(min_thickness 0.25)
		(keepout
			(tracks not_allowed)
			(vias allowed)
			(pads allowed)
			(copperpour not_allowed)
			(footprints allowed)
		)
		(placement
			(enabled no)
			(sheetname "")
		)
		(fill yes
			(thermal_gap 0.5)
			(thermal_bridge_width 0.5)
			(island_removal_mode 0)
		)
		(polygon
			(pts
				(arc
					(start 290.488116 -393.776454)
					(mid 289.472116 -393.776454)
					(end 290.488116 -393.776454)
				)
			)
		)
	)
	(zone
		(layers "In1.Cu" "In3.Cu" "In5.Cu" "In7.Cu" "In8.Cu" "In9.Cu" "In10.Cu"
			"In12.Cu" "In14.Cu" "In15.Cu" "In16.Cu"
		)
		(hatch none 0.5)
		(connect_pads
			(clearance 0)
		)
		(min_thickness 0.25)
		(keepout
			(tracks not_allowed)
			(vias allowed)
			(pads allowed)
			(copperpour not_allowed)
			(footprints allowed)
		)
		(placement
			(enabled no)
			(sheetname "")
		)
		(fill yes
			(thermal_gap 0.5)
			(thermal_bridge_width 0.5)
			(island_removal_mode 0)
		)
		(polygon
			(pts
				(arc
					(start 293.925498 -399.983452)
					(mid 292.909498 -399.983452)
					(end 293.925498 -399.983452)
				)
			)
		)
	)
	(zone
		(layers "In1.Cu" "In3.Cu" "In5.Cu" "In7.Cu" "In8.Cu" "In9.Cu" "In10.Cu"
			"In12.Cu" "In14.Cu" "In15.Cu" "In16.Cu"
		)
		(hatch none 0.5)
		(connect_pads
			(clearance 0)
		)
		(min_thickness 0.25)
		(keepout
			(tracks not_allowed)
			(vias allowed)
			(pads allowed)
			(copperpour not_allowed)
			(footprints allowed)
		)
		(placement
			(enabled no)
			(sheetname "")
		)
		(fill yes
			(thermal_gap 0.5)
			(thermal_bridge_width 0.5)
			(island_removal_mode 0)
		)
		(polygon
			(pts
				(arc
					(start 291.385498 -402.015452)
					(mid 290.369498 -402.015452)
					(end 291.385498 -402.015452)
				)
			)
		)
	)
	(zone
		(layers "In1.Cu" "In3.Cu" "In5.Cu" "In7.Cu" "In8.Cu" "In9.Cu" "In10.Cu"
			"In12.Cu" "In14.Cu" "In15.Cu" "In16.Cu"
		)
		(hatch none 0.5)
		(connect_pads
			(clearance 0)
		)
		(min_thickness 0.25)
		(keepout
			(tracks not_allowed)
			(vias allowed)
			(pads allowed)
			(copperpour not_allowed)
			(footprints allowed)
		)
		(placement
			(enabled no)
			(sheetname "")
		)
		(fill yes
			(thermal_gap 0.5)
			(thermal_bridge_width 0.5)
			(island_removal_mode 0)
		)
		(polygon
			(pts
				(arc
					(start 298.09313 -404.047452)
					(mid 297.07713 -404.047452)
					(end 298.09313 -404.047452)
				)
			)
		)
	)
	(zone
		(layers "In1.Cu" "In3.Cu" "In5.Cu" "In7.Cu" "In8.Cu" "In9.Cu" "In10.Cu"
			"In12.Cu" "In14.Cu" "In15.Cu" "In16.Cu"
		)
		(hatch none 0.5)
		(connect_pads
			(clearance 0)
		)
		(min_thickness 0.25)
		(keepout
			(tracks not_allowed)
			(vias allowed)
			(pads allowed)
			(copperpour not_allowed)
			(footprints allowed)
		)
		(placement
			(enabled no)
			(sheetname "")
		)
		(fill yes
			(thermal_gap 0.5)
			(thermal_bridge_width 0.5)
			(island_removal_mode 0)
		)
		(polygon
			(pts
				(arc
					(start 291.385498 -399.983452)
					(mid 290.369498 -399.983452)
					(end 291.385498 -399.983452)
				)
			)
		)
	)
	(zone
		(layers "In1.Cu" "In3.Cu" "In5.Cu" "In7.Cu" "In8.Cu" "In9.Cu" "In10.Cu"
			"In12.Cu" "In14.Cu" "In15.Cu" "In16.Cu"
		)
		(hatch none 0.5)
		(connect_pads
			(clearance 0)
		)
		(min_thickness 0.25)
		(keepout
			(tracks not_allowed)
			(vias allowed)
			(pads allowed)
			(copperpour not_allowed)
			(footprints allowed)
		)
		(placement
			(enabled no)
			(sheetname "")
		)
		(fill yes
			(thermal_gap 0.5)
			(thermal_bridge_width 0.5)
			(island_removal_mode 0)
		)
		(polygon
			(pts
				(arc
					(start 298.09313 -402.015452)
					(mid 297.07713 -402.015452)
					(end 298.09313 -402.015452)
				)
			)
		)
	)
	(zone
		(layers "In1.Cu" "In3.Cu" "In5.Cu" "In7.Cu" "In8.Cu" "In9.Cu" "In10.Cu"
			"In12.Cu" "In14.Cu" "In15.Cu" "In16.Cu"
		)
		(hatch none 0.5)
		(connect_pads
			(clearance 0)
		)
		(min_thickness 0.25)
		(keepout
			(tracks not_allowed)
			(vias allowed)
			(pads allowed)
			(copperpour not_allowed)
			(footprints allowed)
		)
		(placement
			(enabled no)
			(sheetname "")
		)
		(fill yes
			(thermal_gap 0.5)
			(thermal_bridge_width 0.5)
			(island_removal_mode 0)
		)
		(polygon
			(pts
				(arc
					(start 298.85513 -404.047452)
					(mid 297.83913 -404.047452)
					(end 298.85513 -404.047452)
				)
			)
		)
	)
	(zone
		(layers "In1.Cu" "In3.Cu" "In5.Cu" "In7.Cu" "In8.Cu" "In9.Cu" "In10.Cu"
			"In12.Cu" "In14.Cu" "In15.Cu" "In16.Cu"
		)
		(hatch none 0.5)
		(connect_pads
			(clearance 0)
		)
		(min_thickness 0.25)
		(keepout
			(tracks not_allowed)
			(vias allowed)
			(pads allowed)
			(copperpour not_allowed)
			(footprints allowed)
		)
		(placement
			(enabled no)
			(sheetname "")
		)
		(fill yes
			(thermal_gap 0.5)
			(thermal_bridge_width 0.5)
			(island_removal_mode 0)
		)
		(polygon
			(pts
				(arc
					(start 295.55313 -399.983452)
					(mid 294.53713 -399.983452)
					(end 295.55313 -399.983452)
				)
			)
		)
	)
	(zone
		(layers "In1.Cu" "In3.Cu" "In5.Cu" "In7.Cu" "In8.Cu" "In9.Cu" "In10.Cu"
			"In12.Cu" "In14.Cu" "In15.Cu" "In16.Cu"
		)
		(hatch none 0.5)
		(connect_pads
			(clearance 0)
		)
		(min_thickness 0.25)
		(keepout
			(tracks not_allowed)
			(vias allowed)
			(pads allowed)
			(copperpour not_allowed)
			(footprints allowed)
		)
		(placement
			(enabled no)
			(sheetname "")
		)
		(fill yes
			(thermal_gap 0.5)
			(thermal_bridge_width 0.5)
			(island_removal_mode 0)
		)
		(polygon
			(pts
				(arc
					(start 293.163498 -404.047452)
					(mid 292.147498 -404.047452)
					(end 293.163498 -404.047452)
				)
			)
		)
	)
	(zone
		(layers "In1.Cu" "In3.Cu" "In5.Cu" "In7.Cu" "In8.Cu" "In9.Cu" "In10.Cu"
			"In12.Cu" "In14.Cu" "In15.Cu" "In16.Cu"
		)
		(hatch none 0.5)
		(connect_pads
			(clearance 0)
		)
		(min_thickness 0.25)
		(keepout
			(tracks not_allowed)
			(vias allowed)
			(pads allowed)
			(copperpour not_allowed)
			(footprints allowed)
		)
		(placement
			(enabled no)
			(sheetname "")
		)
		(fill yes
			(thermal_gap 0.5)
			(thermal_bridge_width 0.5)
			(island_removal_mode 0)
		)
		(polygon
			(pts
				(arc
					(start 295.488106 -393.776454)
					(mid 294.472106 -393.776454)
					(end 295.488106 -393.776454)
				)
			)
		)
	)
	(zone
		(layers "In1.Cu" "In3.Cu" "In5.Cu" "In7.Cu" "In8.Cu" "In9.Cu" "In10.Cu"
			"In12.Cu" "In14.Cu" "In15.Cu" "In16.Cu"
		)
		(hatch none 0.5)
		(connect_pads
			(clearance 0)
		)
		(min_thickness 0.25)
		(keepout
			(tracks not_allowed)
			(vias allowed)
			(pads allowed)
			(copperpour not_allowed)
			(footprints allowed)
		)
		(placement
			(enabled no)
			(sheetname "")
		)
		(fill yes
			(thermal_gap 0.5)
			(thermal_bridge_width 0.5)
			(island_removal_mode 0)
		)
		(polygon
			(pts
				(arc
					(start 296.31513 -404.047452)
					(mid 295.29913 -404.047452)
					(end 296.31513 -404.047452)
				)
			)
		)
	)
	(zone
		(layers "In1.Cu" "In3.Cu" "In5.Cu" "In7.Cu" "In8.Cu" "In9.Cu" "In10.Cu"
			"In12.Cu" "In14.Cu" "In15.Cu" "In16.Cu"
		)
		(hatch none 0.5)
		(connect_pads
			(clearance 0)
		)
		(min_thickness 0.25)
		(keepout
			(tracks not_allowed)
			(vias allowed)
			(pads allowed)
			(copperpour not_allowed)
			(footprints allowed)
		)
		(placement
			(enabled no)
			(sheetname "")
		)
		(fill yes
			(thermal_gap 0.5)
			(thermal_bridge_width 0.5)
			(island_removal_mode 0)
		)
		(polygon
			(pts
				(arc
					(start 298.85513 -399.983452)
					(mid 297.83913 -399.983452)
					(end 298.85513 -399.983452)
				)
			)
		)
	)
	(zone
		(layers "In1.Cu" "In3.Cu" "In5.Cu" "In7.Cu" "In8.Cu" "In9.Cu" "In10.Cu"
			"In12.Cu" "In14.Cu" "In15.Cu" "In16.Cu"
		)
		(hatch none 0.5)
		(connect_pads
			(clearance 0)
		)
		(min_thickness 0.25)
		(keepout
			(tracks not_allowed)
			(vias allowed)
			(pads allowed)
			(copperpour not_allowed)
			(footprints allowed)
		)
		(placement
			(enabled no)
			(sheetname "")
		)
		(fill yes
			(thermal_gap 0.5)
			(thermal_bridge_width 0.5)
			(island_removal_mode 0)
		)
		(polygon
			(pts
				(arc
					(start 290.84524 -390.74852)
					(mid 289.82924 -390.74852)
					(end 290.84524 -390.74852)
				)
			)
		)
	)
	(zone
		(layers "In1.Cu" "In3.Cu" "In5.Cu" "In7.Cu" "In8.Cu" "In9.Cu" "In10.Cu"
			"In12.Cu" "In14.Cu" "In15.Cu" "In16.Cu"
		)
		(hatch none 0.5)
		(connect_pads
			(clearance 0)
		)
		(min_thickness 0.25)
		(keepout
			(tracks not_allowed)
			(vias allowed)
			(pads allowed)
			(copperpour not_allowed)
			(footprints allowed)
		)
		(placement
			(enabled no)
			(sheetname "")
		)
		(fill yes
			(thermal_gap 0.5)
			(thermal_bridge_width 0.5)
			(island_removal_mode 0)
		)
		(polygon
			(pts
				(arc
					(start 293.925498 -404.047452)
					(mid 292.909498 -404.047452)
					(end 293.925498 -404.047452)
				)
			)
		)
	)
	(zone
		(layers "In1.Cu" "In3.Cu" "In5.Cu" "In7.Cu" "In8.Cu" "In9.Cu" "In10.Cu"
			"In12.Cu" "In14.Cu" "In15.Cu" "In16.Cu"
		)
		(hatch none 0.5)
		(connect_pads
			(clearance 0)
		)
		(min_thickness 0.25)
		(keepout
			(tracks not_allowed)
			(vias allowed)
			(pads allowed)
			(copperpour not_allowed)
			(footprints allowed)
		)
		(placement
			(enabled no)
			(sheetname "")
		)
		(fill yes
			(thermal_gap 0.5)
			(thermal_bridge_width 0.5)
			(island_removal_mode 0)
		)
		(polygon
			(pts
				(arc
					(start 293.925498 -402.015452)
					(mid 292.909498 -402.015452)
					(end 293.925498 -402.015452)
				)
			)
		)
	)
	(zone
		(layers "In1.Cu" "In3.Cu" "In5.Cu" "In7.Cu" "In8.Cu" "In9.Cu" "In10.Cu"
			"In12.Cu" "In14.Cu" "In15.Cu" "In16.Cu"
		)
		(hatch none 0.5)
		(connect_pads
			(clearance 0)
		)
		(min_thickness 0.25)
		(keepout
			(tracks not_allowed)
			(vias allowed)
			(pads allowed)
			(copperpour not_allowed)
			(footprints allowed)
		)
		(placement
			(enabled no)
			(sheetname "")
		)
		(fill yes
			(thermal_gap 0.5)
			(thermal_bridge_width 0.5)
			(island_removal_mode 0)
		)
		(polygon
			(pts
				(arc
					(start 295.55313 -404.047452)
					(mid 294.53713 -404.047452)
					(end 295.55313 -404.047452)
				)
			)
		)
	)
	(zone
		(layers "In1.Cu" "In3.Cu" "In5.Cu" "In7.Cu" "In8.Cu" "In9.Cu" "In10.Cu"
			"In12.Cu" "In14.Cu" "In15.Cu" "In16.Cu"
		)
		(hatch none 0.5)
		(connect_pads
			(clearance 0)
		)
		(min_thickness 0.25)
		(keepout
			(tracks not_allowed)
			(vias allowed)
			(pads allowed)
			(copperpour not_allowed)
			(footprints allowed)
		)
		(placement
			(enabled no)
			(sheetname "")
		)
		(fill yes
			(thermal_gap 0.5)
			(thermal_bridge_width 0.5)
			(island_removal_mode 0)
		)
		(polygon
			(pts
				(arc
					(start 289.488118 -395.73708)
					(mid 288.472118 -395.73708)
					(end 289.488118 -395.73708)
				)
			)
		)
	)
	(zone
		(layers "In1.Cu" "In3.Cu" "In5.Cu" "In7.Cu" "In8.Cu" "In9.Cu" "In10.Cu"
			"In12.Cu" "In14.Cu" "In15.Cu" "In16.Cu"
		)
		(hatch none 0.5)
		(connect_pads
			(clearance 0)
		)
		(min_thickness 0.25)
		(keepout
			(tracks not_allowed)
			(vias allowed)
			(pads allowed)
			(copperpour not_allowed)
			(footprints allowed)
		)
		(placement
			(enabled no)
			(sheetname "")
		)
		(fill yes
			(thermal_gap 0.5)
			(thermal_bridge_width 0.5)
			(island_removal_mode 0)
		)
		(polygon
			(pts
				(arc
					(start 296.488104 -393.776454)
					(mid 295.472104 -393.776454)
					(end 296.488104 -393.776454)
				)
			)
		)
	)
	(zone
		(layers "In1.Cu" "In3.Cu" "In5.Cu" "In7.Cu" "In8.Cu" "In9.Cu" "In10.Cu"
			"In12.Cu" "In14.Cu" "In15.Cu" "In16.Cu"
		)
		(hatch none 0.5)
		(connect_pads
			(clearance 0)
		)
		(min_thickness 0.25)
		(keepout
			(tracks not_allowed)
			(vias allowed)
			(pads allowed)
			(copperpour not_allowed)
			(footprints allowed)
		)
		(placement
			(enabled no)
			(sheetname "")
		)
		(fill yes
			(thermal_gap 0.5)
			(thermal_bridge_width 0.5)
			(island_removal_mode 0)
		)
		(polygon
			(pts
				(arc
					(start 288.845498 -402.015452)
					(mid 287.829498 -402.015452)
					(end 288.845498 -402.015452)
				)
			)
		)
	)
	(zone
		(layers "In1.Cu" "In3.Cu" "In5.Cu" "In7.Cu" "In8.Cu" "In9.Cu" "In10.Cu"
			"In12.Cu" "In14.Cu" "In15.Cu" "In16.Cu"
		)
		(hatch none 0.5)
		(connect_pads
			(clearance 0)
		)
		(min_thickness 0.25)
		(keepout
			(tracks not_allowed)
			(vias allowed)
			(pads allowed)
			(copperpour not_allowed)
			(footprints allowed)
		)
		(placement
			(enabled no)
			(sheetname "")
		)
		(fill yes
			(thermal_gap 0.5)
			(thermal_bridge_width 0.5)
			(island_removal_mode 0)
		)
		(polygon
			(pts
				(arc
					(start 292.488112 -393.776454)
					(mid 291.472112 -393.776454)
					(end 292.488112 -393.776454)
				)
			)
		)
	)
	(zone
		(layers "In1.Cu" "In3.Cu" "In5.Cu" "In7.Cu" "In8.Cu" "In9.Cu" "In10.Cu"
			"In12.Cu" "In14.Cu" "In15.Cu" "In16.Cu"
		)
		(hatch none 0.5)
		(connect_pads
			(clearance 0)
		)
		(min_thickness 0.25)
		(keepout
			(tracks not_allowed)
			(vias allowed)
			(pads allowed)
			(copperpour not_allowed)
			(footprints allowed)
		)
		(placement
			(enabled no)
			(sheetname "")
		)
		(fill yes
			(thermal_gap 0.5)
			(thermal_bridge_width 0.5)
			(island_removal_mode 0)
		)
		(polygon
			(pts
				(arc
					(start 290.623498 -404.047452)
					(mid 289.607498 -404.047452)
					(end 290.623498 -404.047452)
				)
			)
		)
	)
	(zone
		(layers "In1.Cu" "In3.Cu" "In5.Cu" "In7.Cu" "In8.Cu" "In9.Cu" "In10.Cu"
			"In12.Cu" "In14.Cu" "In15.Cu" "In16.Cu"
		)
		(hatch none 0.5)
		(connect_pads
			(clearance 0)
		)
		(min_thickness 0.25)
		(keepout
			(tracks not_allowed)
			(vias allowed)
			(pads allowed)
			(copperpour not_allowed)
			(footprints allowed)
		)
		(placement
			(enabled no)
			(sheetname "")
		)
		(fill yes
			(thermal_gap 0.5)
			(thermal_bridge_width 0.5)
			(island_removal_mode 0)
		)
		(polygon
			(pts
				(arc
					(start 291.385498 -404.047452)
					(mid 290.369498 -404.047452)
					(end 291.385498 -404.047452)
				)
			)
		)
	)
	(zone
		(layers "In1.Cu" "In3.Cu" "In5.Cu" "In7.Cu" "In8.Cu" "In9.Cu" "In10.Cu"
			"In12.Cu" "In14.Cu" "In15.Cu" "In16.Cu"
		)
		(hatch none 0.5)
		(connect_pads
			(clearance 0)
		)
		(min_thickness 0.25)
		(keepout
			(tracks not_allowed)
			(vias allowed)
			(pads allowed)
			(copperpour not_allowed)
			(footprints allowed)
		)
		(placement
			(enabled no)
			(sheetname "")
		)
		(fill yes
			(thermal_gap 0.5)
			(thermal_bridge_width 0.5)
			(island_removal_mode 0)
		)
		(polygon
			(pts
				(arc
					(start 288.845498 -404.047452)
					(mid 287.829498 -404.047452)
					(end 288.845498 -404.047452)
				)
			)
		)
	)
	(zone
		(layers "In1.Cu" "In3.Cu" "In5.Cu" "In7.Cu" "In8.Cu" "In9.Cu" "In10.Cu"
			"In12.Cu" "In14.Cu" "In15.Cu" "In16.Cu"
		)
		(hatch none 0.5)
		(connect_pads
			(clearance 0)
		)
		(min_thickness 0.25)
		(keepout
			(tracks not_allowed)
			(vias allowed)
			(pads allowed)
			(copperpour not_allowed)
			(footprints allowed)
		)
		(placement
			(enabled no)
			(sheetname "")
		)
		(fill yes
			(thermal_gap 0.5)
			(thermal_bridge_width 0.5)
			(island_removal_mode 0)
		)
		(polygon
			(pts
				(arc
					(start 291.44214 -391.32256)
					(mid 290.42614 -391.32256)
					(end 291.44214 -391.32256)
				)
			)
		)
	)
	(zone
		(layers "In1.Cu" "In3.Cu" "In5.Cu" "In7.Cu" "In8.Cu" "In9.Cu" "In10.Cu"
			"In12.Cu" "In14.Cu" "In15.Cu" "In16.Cu"
		)
		(hatch none 0.5)
		(connect_pads
			(clearance 0)
		)
		(min_thickness 0.25)
		(keepout
			(tracks not_allowed)
			(vias allowed)
			(pads allowed)
			(copperpour not_allowed)
			(footprints allowed)
		)
		(placement
			(enabled no)
			(sheetname "")
		)
		(fill yes
			(thermal_gap 0.5)
			(thermal_bridge_width 0.5)
			(island_removal_mode 0)
		)
		(polygon
			(pts
				(arc
					(start 290.623498 -399.983452)
					(mid 289.607498 -399.983452)
					(end 290.623498 -399.983452)
				)
			)
		)
	)
	(zone
		(layers "In1.Cu" "In3.Cu" "In5.Cu" "In7.Cu" "In8.Cu" "In9.Cu" "In10.Cu"
			"In12.Cu" "In14.Cu" "In15.Cu" "In16.Cu"
		)
		(hatch none 0.5)
		(connect_pads
			(clearance 0)
		)
		(min_thickness 0.25)
		(keepout
			(tracks not_allowed)
			(vias allowed)
			(pads allowed)
			(copperpour not_allowed)
			(footprints allowed)
		)
		(placement
			(enabled no)
			(sheetname "")
		)
		(fill yes
			(thermal_gap 0.5)
			(thermal_bridge_width 0.5)
			(island_removal_mode 0)
		)
		(polygon
			(pts
				(arc
					(start 295.55313 -402.015452)
					(mid 294.53713 -402.015452)
					(end 295.55313 -402.015452)
				)
			)
		)
	)
	(zone
		(layers "In1.Cu" "In3.Cu" "In5.Cu" "In7.Cu" "In8.Cu" "In9.Cu" "In10.Cu"
			"In12.Cu" "In14.Cu" "In15.Cu" "In16.Cu"
		)
		(hatch none 0.5)
		(connect_pads
			(clearance 0)
		)
		(min_thickness 0.25)
		(keepout
			(tracks not_allowed)
			(vias allowed)
			(pads allowed)
			(copperpour not_allowed)
			(footprints allowed)
		)
		(placement
			(enabled no)
			(sheetname "")
		)
		(fill yes
			(thermal_gap 0.5)
			(thermal_bridge_width 0.5)
			(island_removal_mode 0)
		)
		(polygon
			(pts
				(arc
					(start 297.488102 -393.776454)
					(mid 296.472102 -393.776454)
					(end 297.488102 -393.776454)
				)
			)
		)
	)
	(zone
		(layers "In1.Cu" "In3.Cu" "In5.Cu" "In7.Cu" "In8.Cu" "In9.Cu" "In10.Cu"
			"In12.Cu" "In14.Cu" "In15.Cu" "In16.Cu"
		)
		(hatch none 0.5)
		(connect_pads
			(clearance 0)
		)
		(min_thickness 0.25)
		(keepout
			(tracks not_allowed)
			(vias allowed)
			(pads allowed)
			(copperpour not_allowed)
			(footprints allowed)
		)
		(placement
			(enabled no)
			(sheetname "")
		)
		(fill yes
			(thermal_gap 0.5)
			(thermal_bridge_width 0.5)
			(island_removal_mode 0)
		)
		(polygon
			(pts
				(arc
					(start 290.623498 -402.015452)
					(mid 289.607498 -402.015452)
					(end 290.623498 -402.015452)
				)
			)
		)
	)
	(zone
		(layers "In1.Cu" "In3.Cu" "In5.Cu" "In7.Cu" "In8.Cu" "In9.Cu" "In10.Cu"
			"In12.Cu" "In14.Cu" "In15.Cu" "In16.Cu"
		)
		(hatch none 0.5)
		(connect_pads
			(clearance 0)
		)
		(min_thickness 0.25)
		(keepout
			(tracks not_allowed)
			(vias allowed)
			(pads allowed)
			(copperpour not_allowed)
			(footprints allowed)
		)
		(placement
			(enabled no)
			(sheetname "")
		)
		(fill yes
			(thermal_gap 0.5)
			(thermal_bridge_width 0.5)
			(island_removal_mode 0)
		)
		(polygon
			(pts
				(arc
					(start 288.083498 -402.015452)
					(mid 287.067498 -402.015452)
					(end 288.083498 -402.015452)
				)
			)
		)
	)
	(zone
		(layers "In1.Cu" "In3.Cu" "In5.Cu" "In7.Cu" "In8.Cu" "In9.Cu" "In10.Cu"
			"In16.Cu"
		)
		(hatch none 0.5)
		(connect_pads
			(clearance 0)
		)
		(min_thickness 0.25)
		(keepout
			(tracks not_allowed)
			(vias allowed)
			(pads allowed)
			(copperpour not_allowed)
			(footprints allowed)
		)
		(placement
			(enabled no)
			(sheetname "")
		)
		(fill yes
			(thermal_gap 0.5)
			(thermal_bridge_width 0.5)
			(island_removal_mode 0)
		)
		(polygon
			(pts
				(arc
					(start 383.242058 -436.160418)
					(mid 383.264376 -436.2143)
					(end 383.318258 -436.236618)
				)
				(arc
					(start 384.258058 -436.236618)
					(mid 384.31194 -436.2143)
					(end 384.334258 -436.160418)
				)
				(arc
					(start 384.334258 -433.618894)
					(mid 384.31194 -433.565012)
					(end 384.258058 -433.542694)
				)
				(arc
					(start 383.318258 -433.542694)
					(mid 383.264376 -433.565012)
					(end 383.242058 -433.618894)
				)
			)
		)
	)
	(zone
		(layers "In1.Cu" "In3.Cu" "In5.Cu" "In7.Cu" "In8.Cu" "In9.Cu" "In10.Cu"
			"In16.Cu"
		)
		(hatch none 0.5)
		(connect_pads
			(clearance 0)
		)
		(min_thickness 0.25)
		(keepout
			(tracks not_allowed)
			(vias allowed)
			(pads allowed)
			(copperpour not_allowed)
			(footprints allowed)
		)
		(placement
			(enabled no)
			(sheetname "")
		)
		(fill yes
			(thermal_gap 0.5)
			(thermal_bridge_width 0.5)
			(island_removal_mode 0)
		)
		(polygon
			(pts
				(arc
					(start 131.242054 -436.160418)
					(mid 131.264372 -436.2143)
					(end 131.318254 -436.236618)
				)
				(arc
					(start 132.258054 -436.236618)
					(mid 132.311936 -436.2143)
					(end 132.334254 -436.160418)
				)
				(arc
					(start 132.334254 -433.618894)
					(mid 132.311936 -433.565012)
					(end 132.258054 -433.542694)
				)
				(arc
					(start 131.318254 -433.542694)
					(mid 131.264372 -433.565012)
					(end 131.242054 -433.618894)
				)
			)
		)
	)
	(zone
		(layers "In1.Cu" "In3.Cu" "In5.Cu" "In7.Cu" "In8.Cu" "In9.Cu" "In10.Cu"
			"In16.Cu"
		)
		(hatch none 0.5)
		(connect_pads
			(clearance 0)
		)
		(min_thickness 0.25)
		(keepout
			(tracks not_allowed)
			(vias allowed)
			(pads allowed)
			(copperpour not_allowed)
			(footprints allowed)
		)
		(placement
			(enabled no)
			(sheetname "")
		)
		(fill yes
			(thermal_gap 0.5)
			(thermal_bridge_width 0.5)
			(island_removal_mode 0)
		)
		(polygon
			(pts
				(arc
					(start 137.242042 -435.16042)
					(mid 137.26436 -435.214302)
					(end 137.318242 -435.23662)
				)
				(arc
					(start 138.258042 -435.23662)
					(mid 138.311924 -435.214302)
					(end 138.334242 -435.16042)
				)
				(arc
					(start 138.334242 -432.618896)
					(mid 138.311924 -432.565014)
					(end 138.258042 -432.542696)
				)
				(arc
					(start 137.318242 -432.542696)
					(mid 137.26436 -432.565014)
					(end 137.242042 -432.618896)
				)
			)
		)
	)
	(zone
		(layers "In1.Cu" "In3.Cu" "In5.Cu" "In7.Cu" "In8.Cu" "In9.Cu" "In10.Cu"
			"In16.Cu"
		)
		(hatch none 0.5)
		(connect_pads
			(clearance 0)
		)
		(min_thickness 0.25)
		(keepout
			(tracks not_allowed)
			(vias allowed)
			(pads allowed)
			(copperpour not_allowed)
			(footprints allowed)
		)
		(placement
			(enabled no)
			(sheetname "")
		)
		(fill yes
			(thermal_gap 0.5)
			(thermal_bridge_width 0.5)
			(island_removal_mode 0)
		)
		(polygon
			(pts
				(arc
					(start 127.242062 -436.160418)
					(mid 127.26438 -436.2143)
					(end 127.318262 -436.236618)
				)
				(arc
					(start 128.258062 -436.236618)
					(mid 128.311944 -436.2143)
					(end 128.334262 -436.160418)
				)
				(arc
					(start 128.334262 -433.618894)
					(mid 128.311944 -433.565012)
					(end 128.258062 -433.542694)
				)
				(arc
					(start 127.318262 -433.542694)
					(mid 127.26438 -433.565012)
					(end 127.242062 -433.618894)
				)
			)
		)
	)
	(zone
		(layers "In1.Cu" "In3.Cu" "In5.Cu" "In7.Cu" "In8.Cu" "In9.Cu" "In10.Cu"
			"In16.Cu"
		)
		(hatch none 0.5)
		(connect_pads
			(clearance 0)
		)
		(min_thickness 0.25)
		(keepout
			(tracks not_allowed)
			(vias allowed)
			(pads allowed)
			(copperpour not_allowed)
			(footprints allowed)
		)
		(placement
			(enabled no)
			(sheetname "")
		)
		(fill yes
			(thermal_gap 0.5)
			(thermal_bridge_width 0.5)
			(island_removal_mode 0)
		)
		(polygon
			(pts
				(arc
					(start 133.24205 -435.16042)
					(mid 133.264368 -435.214302)
					(end 133.31825 -435.23662)
				)
				(arc
					(start 134.25805 -435.23662)
					(mid 134.311932 -435.214302)
					(end 134.33425 -435.16042)
				)
				(arc
					(start 134.33425 -432.618896)
					(mid 134.311932 -432.565014)
					(end 134.25805 -432.542696)
				)
				(arc
					(start 133.31825 -432.542696)
					(mid 133.264368 -432.565014)
					(end 133.24205 -432.618896)
				)
			)
		)
	)
	(zone
		(layers "In1.Cu" "In3.Cu" "In5.Cu" "In7.Cu" "In8.Cu" "In9.Cu" "In10.Cu"
			"In16.Cu"
		)
		(hatch none 0.5)
		(connect_pads
			(clearance 0)
		)
		(min_thickness 0.25)
		(keepout
			(tracks not_allowed)
			(vias allowed)
			(pads allowed)
			(copperpour not_allowed)
			(footprints allowed)
		)
		(placement
			(enabled no)
			(sheetname "")
		)
		(fill yes
			(thermal_gap 0.5)
			(thermal_bridge_width 0.5)
			(island_removal_mode 0)
		)
		(polygon
			(pts
				(arc
					(start 410.242004 -435.16042)
					(mid 410.264322 -435.214302)
					(end 410.318204 -435.23662)
				)
				(arc
					(start 411.258004 -435.23662)
					(mid 411.311886 -435.214302)
					(end 411.334204 -435.16042)
				)
				(arc
					(start 411.334204 -432.618896)
					(mid 411.311886 -432.565014)
					(end 411.258004 -432.542696)
				)
				(arc
					(start 410.318204 -432.542696)
					(mid 410.264322 -432.565014)
					(end 410.242004 -432.618896)
				)
			)
		)
	)
	(zone
		(layers "In1.Cu" "In3.Cu" "In5.Cu" "In7.Cu" "In8.Cu" "In9.Cu" "In10.Cu"
			"In16.Cu"
		)
		(hatch none 0.5)
		(connect_pads
			(clearance 0)
		)
		(min_thickness 0.25)
		(keepout
			(tracks not_allowed)
			(vias allowed)
			(pads allowed)
			(copperpour not_allowed)
			(footprints allowed)
		)
		(placement
			(enabled no)
			(sheetname "")
		)
		(fill yes
			(thermal_gap 0.5)
			(thermal_bridge_width 0.5)
			(island_removal_mode 0)
		)
		(polygon
			(pts
				(arc
					(start 125.242066 -435.16042)
					(mid 125.264384 -435.214302)
					(end 125.318266 -435.23662)
				)
				(arc
					(start 126.258066 -435.23662)
					(mid 126.311948 -435.214302)
					(end 126.334266 -435.16042)
				)
				(arc
					(start 126.334266 -432.618896)
					(mid 126.311948 -432.565014)
					(end 126.258066 -432.542696)
				)
				(arc
					(start 125.318266 -432.542696)
					(mid 125.264384 -432.565014)
					(end 125.242066 -432.618896)
				)
			)
		)
	)
	(zone
		(layers "In1.Cu" "In3.Cu" "In5.Cu" "In7.Cu" "In8.Cu" "In9.Cu" "In10.Cu"
			"In16.Cu"
		)
		(hatch none 0.5)
		(connect_pads
			(clearance 0)
		)
		(min_thickness 0.25)
		(keepout
			(tracks not_allowed)
			(vias allowed)
			(pads allowed)
			(copperpour not_allowed)
			(footprints allowed)
		)
		(placement
			(enabled no)
			(sheetname "")
		)
		(fill yes
			(thermal_gap 0.5)
			(thermal_bridge_width 0.5)
			(island_removal_mode 0)
		)
		(polygon
			(pts
				(arc
					(start 381.242062 -435.16042)
					(mid 381.26438 -435.214302)
					(end 381.318262 -435.23662)
				)
				(arc
					(start 382.258062 -435.23662)
					(mid 382.311944 -435.214302)
					(end 382.334262 -435.16042)
				)
				(arc
					(start 382.334262 -432.618896)
					(mid 382.311944 -432.565014)
					(end 382.258062 -432.542696)
				)
				(arc
					(start 381.318262 -432.542696)
					(mid 381.26438 -432.565014)
					(end 381.242062 -432.618896)
				)
			)
		)
	)
	(zone
		(layers "In1.Cu" "In3.Cu" "In5.Cu" "In7.Cu" "In8.Cu" "In9.Cu" "In10.Cu"
			"In16.Cu"
		)
		(hatch none 0.5)
		(connect_pads
			(clearance 0)
		)
		(min_thickness 0.25)
		(keepout
			(tracks not_allowed)
			(vias allowed)
			(pads allowed)
			(copperpour not_allowed)
			(footprints allowed)
		)
		(placement
			(enabled no)
			(sheetname "")
		)
		(fill yes
			(thermal_gap 0.5)
			(thermal_bridge_width 0.5)
			(island_removal_mode 0)
		)
		(polygon
			(pts
				(arc
					(start 412.242 -436.160418)
					(mid 412.264318 -436.2143)
					(end 412.3182 -436.236618)
				)
				(arc
					(start 413.258 -436.236618)
					(mid 413.311882 -436.2143)
					(end 413.3342 -436.160418)
				)
				(arc
					(start 413.3342 -433.618894)
					(mid 413.311882 -433.565012)
					(end 413.258 -433.542694)
				)
				(arc
					(start 412.3182 -433.542694)
					(mid 412.264318 -433.565012)
					(end 412.242 -433.618894)
				)
			)
		)
	)
	(zone
		(layers "In1.Cu" "In3.Cu" "In5.Cu" "In7.Cu" "In8.Cu" "In9.Cu" "In10.Cu"
			"In16.Cu"
		)
		(hatch none 0.5)
		(connect_pads
			(clearance 0)
		)
		(min_thickness 0.25)
		(keepout
			(tracks not_allowed)
			(vias allowed)
			(pads allowed)
			(copperpour not_allowed)
			(footprints allowed)
		)
		(placement
			(enabled no)
			(sheetname "")
		)
		(fill yes
			(thermal_gap 0.5)
			(thermal_bridge_width 0.5)
			(island_removal_mode 0)
		)
		(polygon
			(pts
				(arc
					(start 144.242028 -436.160418)
					(mid 144.264346 -436.2143)
					(end 144.318228 -436.236618)
				)
				(arc
					(start 145.258028 -436.236618)
					(mid 145.31191 -436.2143)
					(end 145.334228 -436.160418)
				)
				(arc
					(start 145.334228 -433.618894)
					(mid 145.31191 -433.565012)
					(end 145.258028 -433.542694)
				)
				(arc
					(start 144.318228 -433.542694)
					(mid 144.264346 -433.565012)
					(end 144.242028 -433.618894)
				)
			)
		)
	)
	(zone
		(layers "In1.Cu" "In3.Cu" "In5.Cu" "In7.Cu" "In8.Cu" "In9.Cu" "In10.Cu"
			"In16.Cu"
		)
		(hatch none 0.5)
		(connect_pads
			(clearance 0)
		)
		(min_thickness 0.25)
		(keepout
			(tracks not_allowed)
			(vias allowed)
			(pads allowed)
			(copperpour not_allowed)
			(footprints allowed)
		)
		(placement
			(enabled no)
			(sheetname "")
		)
		(fill yes
			(thermal_gap 0.5)
			(thermal_bridge_width 0.5)
			(island_removal_mode 0)
		)
		(polygon
			(pts
				(arc
					(start 152.242012 -436.160418)
					(mid 152.26433 -436.2143)
					(end 152.318212 -436.236618)
				)
				(arc
					(start 153.258012 -436.236618)
					(mid 153.311894 -436.2143)
					(end 153.334212 -436.160418)
				)
				(arc
					(start 153.334212 -433.618894)
					(mid 153.311894 -433.565012)
					(end 153.258012 -433.542694)
				)
				(arc
					(start 152.318212 -433.542694)
					(mid 152.26433 -433.565012)
					(end 152.242012 -433.618894)
				)
			)
		)
	)
	(zone
		(layers "In1.Cu" "In3.Cu" "In5.Cu" "In7.Cu" "In8.Cu" "In9.Cu" "In10.Cu"
			"In16.Cu"
		)
		(hatch none 0.5)
		(connect_pads
			(clearance 0)
		)
		(min_thickness 0.25)
		(keepout
			(tracks not_allowed)
			(vias allowed)
			(pads allowed)
			(copperpour not_allowed)
			(footprints allowed)
		)
		(placement
			(enabled no)
			(sheetname "")
		)
		(fill yes
			(thermal_gap 0.5)
			(thermal_bridge_width 0.5)
			(island_removal_mode 0)
		)
		(polygon
			(pts
				(arc
					(start 146.242024 -435.16042)
					(mid 146.264342 -435.214302)
					(end 146.318224 -435.23662)
				)
				(arc
					(start 147.258024 -435.23662)
					(mid 147.311906 -435.214302)
					(end 147.334224 -435.16042)
				)
				(arc
					(start 147.334224 -432.618896)
					(mid 147.311906 -432.565014)
					(end 147.258024 -432.542696)
				)
				(arc
					(start 146.318224 -432.542696)
					(mid 146.264342 -432.565014)
					(end 146.242024 -432.618896)
				)
			)
		)
	)
	(zone
		(layers "In1.Cu" "In3.Cu" "In5.Cu" "In7.Cu" "In8.Cu" "In9.Cu" "In10.Cu"
			"In16.Cu"
		)
		(hatch none 0.5)
		(connect_pads
			(clearance 0)
		)
		(min_thickness 0.25)
		(keepout
			(tracks not_allowed)
			(vias allowed)
			(pads allowed)
			(copperpour not_allowed)
			(footprints allowed)
		)
		(placement
			(enabled no)
			(sheetname "")
		)
		(fill yes
			(thermal_gap 0.5)
			(thermal_bridge_width 0.5)
			(island_removal_mode 0)
		)
		(polygon
			(pts
				(arc
					(start 385.242054 -435.16042)
					(mid 385.264372 -435.214302)
					(end 385.318254 -435.23662)
				)
				(arc
					(start 386.258054 -435.23662)
					(mid 386.311936 -435.214302)
					(end 386.334254 -435.16042)
				)
				(arc
					(start 386.334254 -432.618896)
					(mid 386.311936 -432.565014)
					(end 386.258054 -432.542696)
				)
				(arc
					(start 385.318254 -432.542696)
					(mid 385.264372 -432.565014)
					(end 385.242054 -432.618896)
				)
			)
		)
	)
	(zone
		(layers "In1.Cu" "In3.Cu" "In5.Cu" "In7.Cu" "In8.Cu" "In9.Cu" "In10.Cu"
			"In16.Cu"
		)
		(hatch none 0.5)
		(connect_pads
			(clearance 0)
		)
		(min_thickness 0.25)
		(keepout
			(tracks not_allowed)
			(vias allowed)
			(pads allowed)
			(copperpour not_allowed)
			(footprints allowed)
		)
		(placement
			(enabled no)
			(sheetname "")
		)
		(fill yes
			(thermal_gap 0.5)
			(thermal_bridge_width 0.5)
			(island_removal_mode 0)
		)
		(polygon
			(pts
				(arc
					(start 393.242038 -435.16042)
					(mid 393.264356 -435.214302)
					(end 393.318238 -435.23662)
				)
				(arc
					(start 394.258038 -435.23662)
					(mid 394.31192 -435.214302)
					(end 394.334238 -435.16042)
				)
				(arc
					(start 394.334238 -432.618896)
					(mid 394.31192 -432.565014)
					(end 394.258038 -432.542696)
				)
				(arc
					(start 393.318238 -432.542696)
					(mid 393.264356 -432.565014)
					(end 393.242038 -432.618896)
				)
			)
		)
	)
	(zone
		(layers "In1.Cu" "In3.Cu" "In5.Cu" "In7.Cu" "In8.Cu" "In9.Cu" "In10.Cu"
			"In16.Cu"
		)
		(hatch none 0.5)
		(connect_pads
			(clearance 0)
		)
		(min_thickness 0.25)
		(keepout
			(tracks not_allowed)
			(vias allowed)
			(pads allowed)
			(copperpour not_allowed)
			(footprints allowed)
		)
		(placement
			(enabled no)
			(sheetname "")
		)
		(fill yes
			(thermal_gap 0.5)
			(thermal_bridge_width 0.5)
			(island_removal_mode 0)
		)
		(polygon
			(pts
				(arc
					(start 406.242012 -435.16042)
					(mid 406.26433 -435.214302)
					(end 406.318212 -435.23662)
				)
				(arc
					(start 407.258012 -435.23662)
					(mid 407.311894 -435.214302)
					(end 407.334212 -435.16042)
				)
				(arc
					(start 407.334212 -432.618896)
					(mid 407.311894 -432.565014)
					(end 407.258012 -432.542696)
				)
				(arc
					(start 406.318212 -432.542696)
					(mid 406.26433 -432.565014)
					(end 406.242012 -432.618896)
				)
			)
		)
	)
	(zone
		(layers "In1.Cu" "In3.Cu" "In5.Cu" "In7.Cu" "In8.Cu" "In9.Cu" "In10.Cu"
			"In16.Cu"
		)
		(hatch none 0.5)
		(connect_pads
			(clearance 0)
		)
		(min_thickness 0.25)
		(keepout
			(tracks not_allowed)
			(vias allowed)
			(pads allowed)
			(copperpour not_allowed)
			(footprints allowed)
		)
		(placement
			(enabled no)
			(sheetname "")
		)
		(fill yes
			(thermal_gap 0.5)
			(thermal_bridge_width 0.5)
			(island_removal_mode 0)
		)
		(polygon
			(pts
				(arc
					(start 148.24202 -436.160418)
					(mid 148.264338 -436.2143)
					(end 148.31822 -436.236618)
				)
				(arc
					(start 149.25802 -436.236618)
					(mid 149.311902 -436.2143)
					(end 149.33422 -436.160418)
				)
				(arc
					(start 149.33422 -433.618894)
					(mid 149.311902 -433.565012)
					(end 149.25802 -433.542694)
				)
				(arc
					(start 148.31822 -433.542694)
					(mid 148.264338 -433.565012)
					(end 148.24202 -433.618894)
				)
			)
		)
	)
	(zone
		(layers "In1.Cu" "In3.Cu" "In5.Cu" "In7.Cu" "In8.Cu" "In9.Cu" "In10.Cu"
			"In16.Cu"
		)
		(hatch none 0.5)
		(connect_pads
			(clearance 0)
		)
		(min_thickness 0.25)
		(keepout
			(tracks not_allowed)
			(vias allowed)
			(pads allowed)
			(copperpour not_allowed)
			(footprints allowed)
		)
		(placement
			(enabled no)
			(sheetname "")
		)
		(fill yes
			(thermal_gap 0.5)
			(thermal_bridge_width 0.5)
			(island_removal_mode 0)
		)
		(polygon
			(pts
				(arc
					(start 156.242004 -436.160418)
					(mid 156.264322 -436.2143)
					(end 156.318204 -436.236618)
				)
				(arc
					(start 157.258004 -436.236618)
					(mid 157.311886 -436.2143)
					(end 157.334204 -436.160418)
				)
				(arc
					(start 157.334204 -433.618894)
					(mid 157.311886 -433.565012)
					(end 157.258004 -433.542694)
				)
				(arc
					(start 156.318204 -433.542694)
					(mid 156.264322 -433.565012)
					(end 156.242004 -433.618894)
				)
			)
		)
	)
	(zone
		(layers "In1.Cu" "In3.Cu" "In5.Cu" "In7.Cu" "In8.Cu" "In9.Cu" "In10.Cu"
			"In16.Cu"
		)
		(hatch none 0.5)
		(connect_pads
			(clearance 0)
		)
		(min_thickness 0.25)
		(keepout
			(tracks not_allowed)
			(vias allowed)
			(pads allowed)
			(copperpour not_allowed)
			(footprints allowed)
		)
		(placement
			(enabled no)
			(sheetname "")
		)
		(fill yes
			(thermal_gap 0.5)
			(thermal_bridge_width 0.5)
			(island_removal_mode 0)
		)
		(polygon
			(pts
				(arc
					(start 150.242016 -435.16042)
					(mid 150.264334 -435.214302)
					(end 150.318216 -435.23662)
				)
				(arc
					(start 151.258016 -435.23662)
					(mid 151.311898 -435.214302)
					(end 151.334216 -435.16042)
				)
				(arc
					(start 151.334216 -432.618896)
					(mid 151.311898 -432.565014)
					(end 151.258016 -432.542696)
				)
				(arc
					(start 150.318216 -432.542696)
					(mid 150.264334 -432.565014)
					(end 150.242016 -432.618896)
				)
			)
		)
	)
	(zone
		(layers "In1.Cu" "In3.Cu" "In5.Cu" "In7.Cu" "In8.Cu" "In9.Cu" "In10.Cu"
			"In16.Cu"
		)
		(hatch none 0.5)
		(connect_pads
			(clearance 0)
		)
		(min_thickness 0.25)
		(keepout
			(tracks not_allowed)
			(vias allowed)
			(pads allowed)
			(copperpour not_allowed)
			(footprints allowed)
		)
		(placement
			(enabled no)
			(sheetname "")
		)
		(fill yes
			(thermal_gap 0.5)
			(thermal_bridge_width 0.5)
			(island_removal_mode 0)
		)
		(polygon
			(pts
				(arc
					(start 402.24202 -435.16042)
					(mid 402.264338 -435.214302)
					(end 402.31822 -435.23662)
				)
				(arc
					(start 403.25802 -435.23662)
					(mid 403.311902 -435.214302)
					(end 403.33422 -435.16042)
				)
				(arc
					(start 403.33422 -432.618896)
					(mid 403.311902 -432.565014)
					(end 403.25802 -432.542696)
				)
				(arc
					(start 402.31822 -432.542696)
					(mid 402.264338 -432.565014)
					(end 402.24202 -432.618896)
				)
			)
		)
	)
	(zone
		(layers "In1.Cu" "In3.Cu" "In5.Cu" "In7.Cu" "In8.Cu" "In9.Cu" "In10.Cu"
			"In16.Cu"
		)
		(hatch none 0.5)
		(connect_pads
			(clearance 0)
		)
		(min_thickness 0.25)
		(keepout
			(tracks not_allowed)
			(vias allowed)
			(pads allowed)
			(copperpour not_allowed)
			(footprints allowed)
		)
		(placement
			(enabled no)
			(sheetname "")
		)
		(fill yes
			(thermal_gap 0.5)
			(thermal_bridge_width 0.5)
			(island_removal_mode 0)
		)
		(polygon
			(pts
				(arc
					(start 408.242008 -436.160418)
					(mid 408.264326 -436.2143)
					(end 408.318208 -436.236618)
				)
				(arc
					(start 409.258008 -436.236618)
					(mid 409.31189 -436.2143)
					(end 409.334208 -436.160418)
				)
				(arc
					(start 409.334208 -433.618894)
					(mid 409.31189 -433.565012)
					(end 409.258008 -433.542694)
				)
				(arc
					(start 408.318208 -433.542694)
					(mid 408.264326 -433.565012)
					(end 408.242008 -433.618894)
				)
			)
		)
	)
	(zone
		(layers "In1.Cu" "In3.Cu" "In5.Cu" "In7.Cu" "In8.Cu" "In9.Cu" "In10.Cu"
			"In16.Cu"
		)
		(hatch none 0.5)
		(connect_pads
			(clearance 0)
		)
		(min_thickness 0.25)
		(keepout
			(tracks not_allowed)
			(vias allowed)
			(pads allowed)
			(copperpour not_allowed)
			(footprints allowed)
		)
		(placement
			(enabled no)
			(sheetname "")
		)
		(fill yes
			(thermal_gap 0.5)
			(thermal_bridge_width 0.5)
			(island_removal_mode 0)
		)
		(polygon
			(pts
				(arc
					(start 387.24205 -436.160418)
					(mid 387.264368 -436.2143)
					(end 387.31825 -436.236618)
				)
				(arc
					(start 388.25805 -436.236618)
					(mid 388.311932 -436.2143)
					(end 388.33425 -436.160418)
				)
				(arc
					(start 388.33425 -433.618894)
					(mid 388.311932 -433.565012)
					(end 388.25805 -433.542694)
				)
				(arc
					(start 387.31825 -433.542694)
					(mid 387.264368 -433.565012)
					(end 387.24205 -433.618894)
				)
			)
		)
	)
	(zone
		(layers "In1.Cu" "In3.Cu" "In5.Cu" "In7.Cu" "In8.Cu" "In9.Cu" "In10.Cu"
			"In16.Cu"
		)
		(hatch none 0.5)
		(connect_pads
			(clearance 0)
		)
		(min_thickness 0.25)
		(keepout
			(tracks not_allowed)
			(vias allowed)
			(pads allowed)
			(copperpour not_allowed)
			(footprints allowed)
		)
		(placement
			(enabled no)
			(sheetname "")
		)
		(fill yes
			(thermal_gap 0.5)
			(thermal_bridge_width 0.5)
			(island_removal_mode 0)
		)
		(polygon
			(pts
				(arc
					(start 398.242028 -435.16042)
					(mid 398.264346 -435.214302)
					(end 398.318228 -435.23662)
				)
				(arc
					(start 399.258028 -435.23662)
					(mid 399.31191 -435.214302)
					(end 399.334228 -435.16042)
				)
				(arc
					(start 399.334228 -432.618896)
					(mid 399.31191 -432.565014)
					(end 399.258028 -432.542696)
				)
				(arc
					(start 398.318228 -432.542696)
					(mid 398.264346 -432.565014)
					(end 398.242028 -432.618896)
				)
			)
		)
	)
	(zone
		(layers "In1.Cu" "In3.Cu" "In5.Cu" "In7.Cu" "In8.Cu" "In9.Cu" "In10.Cu"
			"In16.Cu"
		)
		(hatch none 0.5)
		(connect_pads
			(clearance 0)
		)
		(min_thickness 0.25)
		(keepout
			(tracks not_allowed)
			(vias allowed)
			(pads allowed)
			(copperpour not_allowed)
			(footprints allowed)
		)
		(placement
			(enabled no)
			(sheetname "")
		)
		(fill yes
			(thermal_gap 0.5)
			(thermal_bridge_width 0.5)
			(island_removal_mode 0)
		)
		(polygon
			(pts
				(arc
					(start 391.242042 -436.160418)
					(mid 391.26436 -436.2143)
					(end 391.318242 -436.236618)
				)
				(arc
					(start 392.258042 -436.236618)
					(mid 392.311924 -436.2143)
					(end 392.334242 -436.160418)
				)
				(arc
					(start 392.334242 -433.618894)
					(mid 392.311924 -433.565012)
					(end 392.258042 -433.542694)
				)
				(arc
					(start 391.318242 -433.542694)
					(mid 391.26436 -433.565012)
					(end 391.242042 -433.618894)
				)
			)
		)
	)
	(zone
		(layers "In1.Cu" "In3.Cu" "In5.Cu" "In7.Cu" "In8.Cu" "In9.Cu" "In10.Cu"
			"In16.Cu"
		)
		(hatch none 0.5)
		(connect_pads
			(clearance 0)
		)
		(min_thickness 0.25)
		(keepout
			(tracks not_allowed)
			(vias allowed)
			(pads allowed)
			(copperpour not_allowed)
			(footprints allowed)
		)
		(placement
			(enabled no)
			(sheetname "")
		)
		(fill yes
			(thermal_gap 0.5)
			(thermal_bridge_width 0.5)
			(island_removal_mode 0)
		)
		(polygon
			(pts
				(arc
					(start 129.242058 -435.16042)
					(mid 129.264376 -435.214302)
					(end 129.318258 -435.23662)
				)
				(arc
					(start 130.258058 -435.23662)
					(mid 130.31194 -435.214302)
					(end 130.334258 -435.16042)
				)
				(arc
					(start 130.334258 -432.618896)
					(mid 130.31194 -432.565014)
					(end 130.258058 -432.542696)
				)
				(arc
					(start 129.318258 -432.542696)
					(mid 129.264376 -432.565014)
					(end 129.242058 -432.618896)
				)
			)
		)
	)
	(zone
		(layers "In1.Cu" "In3.Cu" "In5.Cu" "In7.Cu" "In8.Cu" "In9.Cu" "In10.Cu"
			"In16.Cu"
		)
		(hatch none 0.5)
		(connect_pads
			(clearance 0)
		)
		(min_thickness 0.25)
		(keepout
			(tracks not_allowed)
			(vias allowed)
			(pads allowed)
			(copperpour not_allowed)
			(footprints allowed)
		)
		(placement
			(enabled no)
			(sheetname "")
		)
		(fill yes
			(thermal_gap 0.5)
			(thermal_bridge_width 0.5)
			(island_removal_mode 0)
		)
		(polygon
			(pts
				(arc
					(start 395.242034 -436.160418)
					(mid 395.264352 -436.2143)
					(end 395.318234 -436.236618)
				)
				(arc
					(start 396.258034 -436.236618)
					(mid 396.311916 -436.2143)
					(end 396.334234 -436.160418)
				)
				(arc
					(start 396.334234 -433.618894)
					(mid 396.311916 -433.565012)
					(end 396.258034 -433.542694)
				)
				(arc
					(start 395.318234 -433.542694)
					(mid 395.264352 -433.565012)
					(end 395.242034 -433.618894)
				)
			)
		)
	)
	(zone
		(layers "In1.Cu" "In3.Cu" "In5.Cu" "In7.Cu" "In8.Cu" "In9.Cu" "In10.Cu"
			"In16.Cu"
		)
		(hatch none 0.5)
		(connect_pads
			(clearance 0)
		)
		(min_thickness 0.25)
		(keepout
			(tracks not_allowed)
			(vias allowed)
			(pads allowed)
			(copperpour not_allowed)
			(footprints allowed)
		)
		(placement
			(enabled no)
			(sheetname "")
		)
		(fill yes
			(thermal_gap 0.5)
			(thermal_bridge_width 0.5)
			(island_removal_mode 0)
		)
		(polygon
			(pts
				(arc
					(start 404.242016 -436.160418)
					(mid 404.264334 -436.2143)
					(end 404.318216 -436.236618)
				)
				(arc
					(start 405.258016 -436.236618)
					(mid 405.311898 -436.2143)
					(end 405.334216 -436.160418)
				)
				(arc
					(start 405.334216 -433.618894)
					(mid 405.311898 -433.565012)
					(end 405.258016 -433.542694)
				)
				(arc
					(start 404.318216 -433.542694)
					(mid 404.264334 -433.565012)
					(end 404.242016 -433.618894)
				)
			)
		)
	)
	(zone
		(layers "In1.Cu" "In3.Cu" "In5.Cu" "In7.Cu" "In8.Cu" "In9.Cu" "In10.Cu"
			"In16.Cu"
		)
		(hatch none 0.5)
		(connect_pads
			(clearance 0)
		)
		(min_thickness 0.25)
		(keepout
			(tracks not_allowed)
			(vias allowed)
			(pads allowed)
			(copperpour not_allowed)
			(footprints allowed)
		)
		(placement
			(enabled no)
			(sheetname "")
		)
		(fill yes
			(thermal_gap 0.5)
			(thermal_bridge_width 0.5)
			(island_removal_mode 0)
		)
		(polygon
			(pts
				(arc
					(start 400.242024 -436.160418)
					(mid 400.264342 -436.2143)
					(end 400.318224 -436.236618)
				)
				(arc
					(start 401.258024 -436.236618)
					(mid 401.311906 -436.2143)
					(end 401.334224 -436.160418)
				)
				(arc
					(start 401.334224 -433.618894)
					(mid 401.311906 -433.565012)
					(end 401.258024 -433.542694)
				)
				(arc
					(start 400.318224 -433.542694)
					(mid 400.264342 -433.565012)
					(end 400.242024 -433.618894)
				)
			)
		)
	)
	(zone
		(layers "In1.Cu" "In3.Cu" "In5.Cu" "In7.Cu" "In8.Cu" "In9.Cu" "In10.Cu"
			"In16.Cu"
		)
		(hatch none 0.5)
		(connect_pads
			(clearance 0)
		)
		(min_thickness 0.25)
		(keepout
			(tracks not_allowed)
			(vias allowed)
			(pads allowed)
			(copperpour not_allowed)
			(footprints allowed)
		)
		(placement
			(enabled no)
			(sheetname "")
		)
		(fill yes
			(thermal_gap 0.5)
			(thermal_bridge_width 0.5)
			(island_removal_mode 0)
		)
		(polygon
			(pts
				(arc
					(start 154.242008 -435.16042)
					(mid 154.264326 -435.214302)
					(end 154.318208 -435.23662)
				)
				(arc
					(start 155.258008 -435.23662)
					(mid 155.31189 -435.214302)
					(end 155.334208 -435.16042)
				)
				(arc
					(start 155.334208 -432.618896)
					(mid 155.31189 -432.565014)
					(end 155.258008 -432.542696)
				)
				(arc
					(start 154.318208 -432.542696)
					(mid 154.264326 -432.565014)
					(end 154.242008 -432.618896)
				)
			)
		)
	)
	(zone
		(layers "In1.Cu" "In3.Cu" "In5.Cu" "In7.Cu" "In8.Cu" "In9.Cu" "In10.Cu"
			"In16.Cu"
		)
		(hatch none 0.5)
		(connect_pads
			(clearance 0)
		)
		(min_thickness 0.25)
		(keepout
			(tracks not_allowed)
			(vias allowed)
			(pads allowed)
			(copperpour not_allowed)
			(footprints allowed)
		)
		(placement
			(enabled no)
			(sheetname "")
		)
		(fill yes
			(thermal_gap 0.5)
			(thermal_bridge_width 0.5)
			(island_removal_mode 0)
		)
		(polygon
			(pts
				(arc
					(start 135.242046 -436.160418)
					(mid 135.264364 -436.2143)
					(end 135.318246 -436.236618)
				)
				(arc
					(start 136.258046 -436.236618)
					(mid 136.311928 -436.2143)
					(end 136.334246 -436.160418)
				)
				(arc
					(start 136.334246 -433.618894)
					(mid 136.311928 -433.565012)
					(end 136.258046 -433.542694)
				)
				(arc
					(start 135.318246 -433.542694)
					(mid 135.264364 -433.565012)
					(end 135.242046 -433.618894)
				)
			)
		)
	)
	(zone
		(layers "In1.Cu" "In3.Cu" "In5.Cu" "In7.Cu" "In8.Cu" "In9.Cu" "In10.Cu"
			"In16.Cu"
		)
		(hatch none 0.5)
		(connect_pads
			(clearance 0)
		)
		(min_thickness 0.25)
		(keepout
			(tracks not_allowed)
			(vias allowed)
			(pads allowed)
			(copperpour not_allowed)
			(footprints allowed)
		)
		(placement
			(enabled no)
			(sheetname "")
		)
		(fill yes
			(thermal_gap 0.5)
			(thermal_bridge_width 0.5)
			(island_removal_mode 0)
		)
		(polygon
			(pts
				(arc
					(start 139.242038 -436.160418)
					(mid 139.264356 -436.2143)
					(end 139.318238 -436.236618)
				)
				(arc
					(start 140.258038 -436.236618)
					(mid 140.31192 -436.2143)
					(end 140.334238 -436.160418)
				)
				(arc
					(start 140.334238 -433.618894)
					(mid 140.31192 -433.565012)
					(end 140.258038 -433.542694)
				)
				(arc
					(start 139.318238 -433.542694)
					(mid 139.264356 -433.565012)
					(end 139.242038 -433.618894)
				)
			)
		)
	)
	(zone
		(layers "In1.Cu" "In3.Cu" "In5.Cu" "In7.Cu" "In8.Cu" "In9.Cu" "In10.Cu"
			"In16.Cu"
		)
		(hatch none 0.5)
		(connect_pads
			(clearance 0)
		)
		(min_thickness 0.25)
		(keepout
			(tracks not_allowed)
			(vias allowed)
			(pads allowed)
			(copperpour not_allowed)
			(footprints allowed)
		)
		(placement
			(enabled no)
			(sheetname "")
		)
		(fill yes
			(thermal_gap 0.5)
			(thermal_bridge_width 0.5)
			(island_removal_mode 0)
		)
		(polygon
			(pts
				(arc
					(start 142.242032 -435.16042)
					(mid 142.26435 -435.214302)
					(end 142.318232 -435.23662)
				)
				(arc
					(start 143.258032 -435.23662)
					(mid 143.311914 -435.214302)
					(end 143.334232 -435.16042)
				)
				(arc
					(start 143.334232 -432.618896)
					(mid 143.311914 -432.565014)
					(end 143.258032 -432.542696)
				)
				(arc
					(start 142.318232 -432.542696)
					(mid 142.26435 -432.565014)
					(end 142.242032 -432.618896)
				)
			)
		)
	)
	(zone
		(layers "In1.Cu" "In3.Cu" "In5.Cu" "In7.Cu" "In8.Cu" "In9.Cu" "In10.Cu"
			"In16.Cu"
		)
		(hatch none 0.5)
		(connect_pads
			(clearance 0)
		)
		(min_thickness 0.25)
		(keepout
			(tracks not_allowed)
			(vias allowed)
			(pads allowed)
			(copperpour not_allowed)
			(footprints allowed)
		)
		(placement
			(enabled no)
			(sheetname "")
		)
		(fill yes
			(thermal_gap 0.5)
			(thermal_bridge_width 0.5)
			(island_removal_mode 0)
		)
		(polygon
			(pts
				(arc
					(start 389.242046 -435.16042)
					(mid 389.264364 -435.214302)
					(end 389.318246 -435.23662)
				)
				(arc
					(start 390.258046 -435.23662)
					(mid 390.311928 -435.214302)
					(end 390.334246 -435.16042)
				)
				(arc
					(start 390.334246 -432.618896)
					(mid 390.311928 -432.565014)
					(end 390.258046 -432.542696)
				)
				(arc
					(start 389.318246 -432.542696)
					(mid 389.264364 -432.565014)
					(end 389.242046 -432.618896)
				)
			)
		)
	)
	(zone
		(layers "In1.Cu" "In3.Cu" "In5.Cu" "In7.Cu" "In8.Cu" "In9.Cu" "In13.Cu"
			"In14.Cu" "In16.Cu"
		)
		(hatch none 0.5)
		(connect_pads
			(clearance 0)
		)
		(min_thickness 0.25)
		(keepout
			(tracks not_allowed)
			(vias allowed)
			(pads allowed)
			(copperpour not_allowed)
			(footprints allowed)
		)
		(placement
			(enabled no)
			(sheetname "")
		)
		(fill yes
			(thermal_gap 0.5)
			(thermal_bridge_width 0.5)
			(island_removal_mode 0)
		)
		(polygon
			(pts
				(arc
					(start 385.242054 -427.960536)
					(mid 385.264372 -428.014418)
					(end 385.318254 -428.036736)
				)
				(arc
					(start 386.258054 -428.036736)
					(mid 386.311936 -428.014418)
					(end 386.334254 -427.960536)
				)
				(arc
					(start 386.334254 -425.419012)
					(mid 386.311936 -425.36513)
					(end 386.258054 -425.342812)
				)
				(arc
					(start 385.318254 -425.342812)
					(mid 385.264372 -425.36513)
					(end 385.242054 -425.419012)
				)
			)
		)
	)
	(zone
		(layers "In1.Cu" "In3.Cu" "In5.Cu" "In7.Cu" "In8.Cu" "In9.Cu" "In13.Cu"
			"In14.Cu" "In16.Cu"
		)
		(hatch none 0.5)
		(connect_pads
			(clearance 0)
		)
		(min_thickness 0.25)
		(keepout
			(tracks not_allowed)
			(vias allowed)
			(pads allowed)
			(copperpour not_allowed)
			(footprints allowed)
		)
		(placement
			(enabled no)
			(sheetname "")
		)
		(fill yes
			(thermal_gap 0.5)
			(thermal_bridge_width 0.5)
			(island_removal_mode 0)
		)
		(polygon
			(pts
				(arc
					(start 393.242038 -427.960536)
					(mid 393.264356 -428.014418)
					(end 393.318238 -428.036736)
				)
				(arc
					(start 394.258038 -428.036736)
					(mid 394.31192 -428.014418)
					(end 394.334238 -427.960536)
				)
				(arc
					(start 394.334238 -425.419012)
					(mid 394.31192 -425.36513)
					(end 394.258038 -425.342812)
				)
				(arc
					(start 393.318238 -425.342812)
					(mid 393.264356 -425.36513)
					(end 393.242038 -425.419012)
				)
			)
		)
	)
	(zone
		(layers "In1.Cu" "In3.Cu" "In5.Cu" "In7.Cu" "In8.Cu" "In9.Cu" "In13.Cu"
			"In14.Cu" "In16.Cu"
		)
		(hatch none 0.5)
		(connect_pads
			(clearance 0)
		)
		(min_thickness 0.25)
		(keepout
			(tracks not_allowed)
			(vias allowed)
			(pads allowed)
			(copperpour not_allowed)
			(footprints allowed)
		)
		(placement
			(enabled no)
			(sheetname "")
		)
		(fill yes
			(thermal_gap 0.5)
			(thermal_bridge_width 0.5)
			(island_removal_mode 0)
		)
		(polygon
			(pts
				(arc
					(start 410.242004 -427.960536)
					(mid 410.264322 -428.014418)
					(end 410.318204 -428.036736)
				)
				(arc
					(start 411.258004 -428.036736)
					(mid 411.311886 -428.014418)
					(end 411.334204 -427.960536)
				)
				(arc
					(start 411.334204 -425.419012)
					(mid 411.311886 -425.36513)
					(end 411.258004 -425.342812)
				)
				(arc
					(start 410.318204 -425.342812)
					(mid 410.264322 -425.36513)
					(end 410.242004 -425.419012)
				)
			)
		)
	)
	(zone
		(layers "In1.Cu" "In3.Cu" "In5.Cu" "In7.Cu" "In8.Cu" "In9.Cu" "In13.Cu"
			"In14.Cu" "In16.Cu"
		)
		(hatch none 0.5)
		(connect_pads
			(clearance 0)
		)
		(min_thickness 0.25)
		(keepout
			(tracks not_allowed)
			(vias allowed)
			(pads allowed)
			(copperpour not_allowed)
			(footprints allowed)
		)
		(placement
			(enabled no)
			(sheetname "")
		)
		(fill yes
			(thermal_gap 0.5)
			(thermal_bridge_width 0.5)
			(island_removal_mode 0)
		)
		(polygon
			(pts
				(arc
					(start 146.242024 -427.960536)
					(mid 146.264342 -428.014418)
					(end 146.318224 -428.036736)
				)
				(arc
					(start 147.258024 -428.036736)
					(mid 147.311906 -428.014418)
					(end 147.334224 -427.960536)
				)
				(arc
					(start 147.334224 -425.419012)
					(mid 147.311906 -425.36513)
					(end 147.258024 -425.342812)
				)
				(arc
					(start 146.318224 -425.342812)
					(mid 146.264342 -425.36513)
					(end 146.242024 -425.419012)
				)
			)
		)
	)
	(zone
		(layers "In1.Cu" "In3.Cu" "In5.Cu" "In7.Cu" "In8.Cu" "In9.Cu" "In13.Cu"
			"In14.Cu" "In16.Cu"
		)
		(hatch none 0.5)
		(connect_pads
			(clearance 0)
		)
		(min_thickness 0.25)
		(keepout
			(tracks not_allowed)
			(vias allowed)
			(pads allowed)
			(copperpour not_allowed)
			(footprints allowed)
		)
		(placement
			(enabled no)
			(sheetname "")
		)
		(fill yes
			(thermal_gap 0.5)
			(thermal_bridge_width 0.5)
			(island_removal_mode 0)
		)
		(polygon
			(pts
				(arc
					(start 137.242042 -427.960536)
					(mid 137.26436 -428.014418)
					(end 137.318242 -428.036736)
				)
				(arc
					(start 138.258042 -428.036736)
					(mid 138.311924 -428.014418)
					(end 138.334242 -427.960536)
				)
				(arc
					(start 138.334242 -425.419012)
					(mid 138.311924 -425.36513)
					(end 138.258042 -425.342812)
				)
				(arc
					(start 137.318242 -425.342812)
					(mid 137.26436 -425.36513)
					(end 137.242042 -425.419012)
				)
			)
		)
	)
	(zone
		(layers "In1.Cu" "In3.Cu" "In5.Cu" "In7.Cu" "In8.Cu" "In9.Cu" "In13.Cu"
			"In14.Cu" "In16.Cu"
		)
		(hatch none 0.5)
		(connect_pads
			(clearance 0)
		)
		(min_thickness 0.25)
		(keepout
			(tracks not_allowed)
			(vias allowed)
			(pads allowed)
			(copperpour not_allowed)
			(footprints allowed)
		)
		(placement
			(enabled no)
			(sheetname "")
		)
		(fill yes
			(thermal_gap 0.5)
			(thermal_bridge_width 0.5)
			(island_removal_mode 0)
		)
		(polygon
			(pts
				(arc
					(start 398.242028 -427.960536)
					(mid 398.264346 -428.014418)
					(end 398.318228 -428.036736)
				)
				(arc
					(start 399.258028 -428.036736)
					(mid 399.31191 -428.014418)
					(end 399.334228 -427.960536)
				)
				(arc
					(start 399.334228 -425.419012)
					(mid 399.31191 -425.36513)
					(end 399.258028 -425.342812)
				)
				(arc
					(start 398.318228 -425.342812)
					(mid 398.264346 -425.36513)
					(end 398.242028 -425.419012)
				)
			)
		)
	)
	(zone
		(layers "In1.Cu" "In3.Cu" "In5.Cu" "In7.Cu" "In8.Cu" "In9.Cu" "In13.Cu"
			"In14.Cu" "In16.Cu"
		)
		(hatch none 0.5)
		(connect_pads
			(clearance 0)
		)
		(min_thickness 0.25)
		(keepout
			(tracks not_allowed)
			(vias allowed)
			(pads allowed)
			(copperpour not_allowed)
			(footprints allowed)
		)
		(placement
			(enabled no)
			(sheetname "")
		)
		(fill yes
			(thermal_gap 0.5)
			(thermal_bridge_width 0.5)
			(island_removal_mode 0)
		)
		(polygon
			(pts
				(arc
					(start 402.24202 -427.960536)
					(mid 402.264338 -428.014418)
					(end 402.31822 -428.036736)
				)
				(arc
					(start 403.25802 -428.036736)
					(mid 403.311902 -428.014418)
					(end 403.33422 -427.960536)
				)
				(arc
					(start 403.33422 -425.419012)
					(mid 403.311902 -425.36513)
					(end 403.25802 -425.342812)
				)
				(arc
					(start 402.31822 -425.342812)
					(mid 402.264338 -425.36513)
					(end 402.24202 -425.419012)
				)
			)
		)
	)
	(zone
		(layers "In1.Cu" "In3.Cu" "In5.Cu" "In7.Cu" "In8.Cu" "In9.Cu" "In13.Cu"
			"In14.Cu" "In16.Cu"
		)
		(hatch none 0.5)
		(connect_pads
			(clearance 0)
		)
		(min_thickness 0.25)
		(keepout
			(tracks not_allowed)
			(vias allowed)
			(pads allowed)
			(copperpour not_allowed)
			(footprints allowed)
		)
		(placement
			(enabled no)
			(sheetname "")
		)
		(fill yes
			(thermal_gap 0.5)
			(thermal_bridge_width 0.5)
			(island_removal_mode 0)
		)
		(polygon
			(pts
				(arc
					(start 406.242012 -427.960536)
					(mid 406.26433 -428.014418)
					(end 406.318212 -428.036736)
				)
				(arc
					(start 407.258012 -428.036736)
					(mid 407.311894 -428.014418)
					(end 407.334212 -427.960536)
				)
				(arc
					(start 407.334212 -425.419012)
					(mid 407.311894 -425.36513)
					(end 407.258012 -425.342812)
				)
				(arc
					(start 406.318212 -425.342812)
					(mid 406.26433 -425.36513)
					(end 406.242012 -425.419012)
				)
			)
		)
	)
	(zone
		(layers "In1.Cu" "In3.Cu" "In5.Cu" "In7.Cu" "In8.Cu" "In9.Cu" "In13.Cu"
			"In14.Cu" "In16.Cu"
		)
		(hatch none 0.5)
		(connect_pads
			(clearance 0)
		)
		(min_thickness 0.25)
		(keepout
			(tracks not_allowed)
			(vias allowed)
			(pads allowed)
			(copperpour not_allowed)
			(footprints allowed)
		)
		(placement
			(enabled no)
			(sheetname "")
		)
		(fill yes
			(thermal_gap 0.5)
			(thermal_bridge_width 0.5)
			(island_removal_mode 0)
		)
		(polygon
			(pts
				(arc
					(start 150.242016 -427.960536)
					(mid 150.264334 -428.014418)
					(end 150.318216 -428.036736)
				)
				(arc
					(start 151.258016 -428.036736)
					(mid 151.311898 -428.014418)
					(end 151.334216 -427.960536)
				)
				(arc
					(start 151.334216 -425.419012)
					(mid 151.311898 -425.36513)
					(end 151.258016 -425.342812)
				)
				(arc
					(start 150.318216 -425.342812)
					(mid 150.264334 -425.36513)
					(end 150.242016 -425.419012)
				)
			)
		)
	)
	(zone
		(layers "In1.Cu" "In3.Cu" "In5.Cu" "In7.Cu" "In8.Cu" "In9.Cu" "In13.Cu"
			"In14.Cu" "In16.Cu"
		)
		(hatch none 0.5)
		(connect_pads
			(clearance 0)
		)
		(min_thickness 0.25)
		(keepout
			(tracks not_allowed)
			(vias allowed)
			(pads allowed)
			(copperpour not_allowed)
			(footprints allowed)
		)
		(placement
			(enabled no)
			(sheetname "")
		)
		(fill yes
			(thermal_gap 0.5)
			(thermal_bridge_width 0.5)
			(island_removal_mode 0)
		)
		(polygon
			(pts
				(arc
					(start 133.24205 -427.960536)
					(mid 133.264368 -428.014418)
					(end 133.31825 -428.036736)
				)
				(arc
					(start 134.25805 -428.036736)
					(mid 134.311932 -428.014418)
					(end 134.33425 -427.960536)
				)
				(arc
					(start 134.33425 -425.419012)
					(mid 134.311932 -425.36513)
					(end 134.25805 -425.342812)
				)
				(arc
					(start 133.31825 -425.342812)
					(mid 133.264368 -425.36513)
					(end 133.24205 -425.419012)
				)
			)
		)
	)
	(zone
		(layers "In1.Cu" "In3.Cu" "In5.Cu" "In7.Cu" "In8.Cu" "In9.Cu" "In13.Cu"
			"In14.Cu" "In16.Cu"
		)
		(hatch none 0.5)
		(connect_pads
			(clearance 0)
		)
		(min_thickness 0.25)
		(keepout
			(tracks not_allowed)
			(vias allowed)
			(pads allowed)
			(copperpour not_allowed)
			(footprints allowed)
		)
		(placement
			(enabled no)
			(sheetname "")
		)
		(fill yes
			(thermal_gap 0.5)
			(thermal_bridge_width 0.5)
			(island_removal_mode 0)
		)
		(polygon
			(pts
				(arc
					(start 154.242008 -427.960536)
					(mid 154.264326 -428.014418)
					(end 154.318208 -428.036736)
				)
				(arc
					(start 155.258008 -428.036736)
					(mid 155.31189 -428.014418)
					(end 155.334208 -427.960536)
				)
				(arc
					(start 155.334208 -425.419012)
					(mid 155.31189 -425.36513)
					(end 155.258008 -425.342812)
				)
				(arc
					(start 154.318208 -425.342812)
					(mid 154.264326 -425.36513)
					(end 154.242008 -425.419012)
				)
			)
		)
	)
	(zone
		(layers "In1.Cu" "In3.Cu" "In5.Cu" "In7.Cu" "In8.Cu" "In9.Cu" "In13.Cu"
			"In14.Cu" "In16.Cu"
		)
		(hatch none 0.5)
		(connect_pads
			(clearance 0)
		)
		(min_thickness 0.25)
		(keepout
			(tracks not_allowed)
			(vias allowed)
			(pads allowed)
			(copperpour not_allowed)
			(footprints allowed)
		)
		(placement
			(enabled no)
			(sheetname "")
		)
		(fill yes
			(thermal_gap 0.5)
			(thermal_bridge_width 0.5)
			(island_removal_mode 0)
		)
		(polygon
			(pts
				(arc
					(start 381.242062 -427.960536)
					(mid 381.26438 -428.014418)
					(end 381.318262 -428.036736)
				)
				(arc
					(start 382.258062 -428.036736)
					(mid 382.311944 -428.014418)
					(end 382.334262 -427.960536)
				)
				(arc
					(start 382.334262 -425.419012)
					(mid 382.311944 -425.36513)
					(end 382.258062 -425.342812)
				)
				(arc
					(start 381.318262 -425.342812)
					(mid 381.26438 -425.36513)
					(end 381.242062 -425.419012)
				)
			)
		)
	)
	(zone
		(layers "In1.Cu" "In3.Cu" "In5.Cu" "In7.Cu" "In8.Cu" "In9.Cu" "In13.Cu"
			"In14.Cu" "In16.Cu"
		)
		(hatch none 0.5)
		(connect_pads
			(clearance 0)
		)
		(min_thickness 0.25)
		(keepout
			(tracks not_allowed)
			(vias allowed)
			(pads allowed)
			(copperpour not_allowed)
			(footprints allowed)
		)
		(placement
			(enabled no)
			(sheetname "")
		)
		(fill yes
			(thermal_gap 0.5)
			(thermal_bridge_width 0.5)
			(island_removal_mode 0)
		)
		(polygon
			(pts
				(arc
					(start 389.242046 -427.960536)
					(mid 389.264364 -428.014418)
					(end 389.318246 -428.036736)
				)
				(arc
					(start 390.258046 -428.036736)
					(mid 390.311928 -428.014418)
					(end 390.334246 -427.960536)
				)
				(arc
					(start 390.334246 -425.419012)
					(mid 390.311928 -425.36513)
					(end 390.258046 -425.342812)
				)
				(arc
					(start 389.318246 -425.342812)
					(mid 389.264364 -425.36513)
					(end 389.242046 -425.419012)
				)
			)
		)
	)
	(zone
		(layers "In1.Cu" "In3.Cu" "In5.Cu" "In7.Cu" "In8.Cu" "In9.Cu" "In13.Cu"
			"In14.Cu" "In16.Cu"
		)
		(hatch none 0.5)
		(connect_pads
			(clearance 0)
		)
		(min_thickness 0.25)
		(keepout
			(tracks not_allowed)
			(vias allowed)
			(pads allowed)
			(copperpour not_allowed)
			(footprints allowed)
		)
		(placement
			(enabled no)
			(sheetname "")
		)
		(fill yes
			(thermal_gap 0.5)
			(thermal_bridge_width 0.5)
			(island_removal_mode 0)
		)
		(polygon
			(pts
				(arc
					(start 142.242032 -427.960536)
					(mid 142.26435 -428.014418)
					(end 142.318232 -428.036736)
				)
				(arc
					(start 143.258032 -428.036736)
					(mid 143.311914 -428.014418)
					(end 143.334232 -427.960536)
				)
				(arc
					(start 143.334232 -425.419012)
					(mid 143.311914 -425.36513)
					(end 143.258032 -425.342812)
				)
				(arc
					(start 142.318232 -425.342812)
					(mid 142.26435 -425.36513)
					(end 142.242032 -425.419012)
				)
			)
		)
	)
	(zone
		(layers "In1.Cu" "In3.Cu" "In5.Cu" "In7.Cu" "In8.Cu" "In9.Cu" "In13.Cu"
			"In14.Cu" "In16.Cu"
		)
		(hatch none 0.5)
		(connect_pads
			(clearance 0)
		)
		(min_thickness 0.25)
		(keepout
			(tracks not_allowed)
			(vias allowed)
			(pads allowed)
			(copperpour not_allowed)
			(footprints allowed)
		)
		(placement
			(enabled no)
			(sheetname "")
		)
		(fill yes
			(thermal_gap 0.5)
			(thermal_bridge_width 0.5)
			(island_removal_mode 0)
		)
		(polygon
			(pts
				(arc
					(start 125.242066 -427.960536)
					(mid 125.264384 -428.014418)
					(end 125.318266 -428.036736)
				)
				(arc
					(start 126.258066 -428.036736)
					(mid 126.311948 -428.014418)
					(end 126.334266 -427.960536)
				)
				(arc
					(start 126.334266 -425.419012)
					(mid 126.311948 -425.36513)
					(end 126.258066 -425.342812)
				)
				(arc
					(start 125.318266 -425.342812)
					(mid 125.264384 -425.36513)
					(end 125.242066 -425.419012)
				)
			)
		)
	)
	(zone
		(layers "In1.Cu" "In3.Cu" "In5.Cu" "In7.Cu" "In8.Cu" "In9.Cu" "In13.Cu"
			"In14.Cu" "In16.Cu"
		)
		(hatch none 0.5)
		(connect_pads
			(clearance 0)
		)
		(min_thickness 0.25)
		(keepout
			(tracks not_allowed)
			(vias allowed)
			(pads allowed)
			(copperpour not_allowed)
			(footprints allowed)
		)
		(placement
			(enabled no)
			(sheetname "")
		)
		(fill yes
			(thermal_gap 0.5)
			(thermal_bridge_width 0.5)
			(island_removal_mode 0)
		)
		(polygon
			(pts
				(arc
					(start 129.242058 -427.960536)
					(mid 129.264376 -428.014418)
					(end 129.318258 -428.036736)
				)
				(arc
					(start 130.258058 -428.036736)
					(mid 130.31194 -428.014418)
					(end 130.334258 -427.960536)
				)
				(arc
					(start 130.334258 -425.419012)
					(mid 130.31194 -425.36513)
					(end 130.258058 -425.342812)
				)
				(arc
					(start 129.318258 -425.342812)
					(mid 129.264376 -425.36513)
					(end 129.242058 -425.419012)
				)
			)
		)
	)
	(zone
		(layers "In1.Cu" "In3.Cu" "In5.Cu" "In7.Cu" "In8.Cu" "In9.Cu" "In14.Cu"
			"In16.Cu"
		)
		(hatch none 0.5)
		(connect_pads
			(clearance 0)
		)
		(min_thickness 0.25)
		(keepout
			(tracks not_allowed)
			(vias allowed)
			(pads allowed)
			(copperpour not_allowed)
			(footprints allowed)
		)
		(placement
			(enabled no)
			(sheetname "")
		)
		(fill yes
			(thermal_gap 0.5)
			(thermal_bridge_width 0.5)
			(island_removal_mode 0)
		)
		(polygon
			(pts
				(arc
					(start 66.142108 -431.560478)
					(mid 66.164426 -431.61436)
					(end 66.218308 -431.636678)
				)
				(arc
					(start 67.158108 -431.636678)
					(mid 67.21199 -431.61436)
					(end 67.234308 -431.560478)
				)
				(arc
					(start 67.234308 -429.018954)
					(mid 67.21199 -428.965072)
					(end 67.158108 -428.942754)
				)
				(arc
					(start 66.218308 -428.942754)
					(mid 66.164426 -428.965072)
					(end 66.142108 -429.018954)
				)
			)
		)
	)
	(zone
		(layers "In1.Cu" "In3.Cu" "In5.Cu" "In7.Cu" "In8.Cu" "In9.Cu" "In14.Cu"
			"In16.Cu"
		)
		(hatch none 0.5)
		(connect_pads
			(clearance 0)
		)
		(min_thickness 0.25)
		(keepout
			(tracks not_allowed)
			(vias allowed)
			(pads allowed)
			(copperpour not_allowed)
			(footprints allowed)
		)
		(placement
			(enabled no)
			(sheetname "")
		)
		(fill yes
			(thermal_gap 0.5)
			(thermal_bridge_width 0.5)
			(island_removal_mode 0)
		)
		(polygon
			(pts
				(arc
					(start 345.142058 -432.560476)
					(mid 345.164376 -432.614358)
					(end 345.218258 -432.636676)
				)
				(arc
					(start 346.158058 -432.636676)
					(mid 346.21194 -432.614358)
					(end 346.234258 -432.560476)
				)
				(arc
					(start 346.234258 -430.018952)
					(mid 346.21194 -429.96507)
					(end 346.158058 -429.942752)
				)
				(arc
					(start 345.218258 -429.942752)
					(mid 345.164376 -429.96507)
					(end 345.142058 -430.018952)
				)
			)
		)
	)
	(zone
		(layers "In1.Cu" "In3.Cu" "In5.Cu" "In7.Cu" "In8.Cu" "In9.Cu" "In14.Cu"
			"In16.Cu"
		)
		(hatch none 0.5)
		(connect_pads
			(clearance 0)
		)
		(min_thickness 0.25)
		(keepout
			(tracks not_allowed)
			(vias allowed)
			(pads allowed)
			(copperpour not_allowed)
			(footprints allowed)
		)
		(placement
			(enabled no)
			(sheetname "")
		)
		(fill yes
			(thermal_gap 0.5)
			(thermal_bridge_width 0.5)
			(island_removal_mode 0)
		)
		(polygon
			(pts
				(arc
					(start 89.142062 -432.560476)
					(mid 89.16438 -432.614358)
					(end 89.218262 -432.636676)
				)
				(arc
					(start 90.158062 -432.636676)
					(mid 90.211944 -432.614358)
					(end 90.234262 -432.560476)
				)
				(arc
					(start 90.234262 -430.018952)
					(mid 90.211944 -429.96507)
					(end 90.158062 -429.942752)
				)
				(arc
					(start 89.218262 -429.942752)
					(mid 89.16438 -429.96507)
					(end 89.142062 -430.018952)
				)
			)
		)
	)
	(zone
		(layers "In1.Cu" "In3.Cu" "In5.Cu" "In7.Cu" "In8.Cu" "In9.Cu" "In14.Cu"
			"In16.Cu"
		)
		(hatch none 0.5)
		(connect_pads
			(clearance 0)
		)
		(min_thickness 0.25)
		(keepout
			(tracks not_allowed)
			(vias allowed)
			(pads allowed)
			(copperpour not_allowed)
			(footprints allowed)
		)
		(placement
			(enabled no)
			(sheetname "")
		)
		(fill yes
			(thermal_gap 0.5)
			(thermal_bridge_width 0.5)
			(island_removal_mode 0)
		)
		(polygon
			(pts
				(arc
					(start 341.142066 -432.560476)
					(mid 341.164384 -432.614358)
					(end 341.218266 -432.636676)
				)
				(arc
					(start 342.158066 -432.636676)
					(mid 342.211948 -432.614358)
					(end 342.234266 -432.560476)
				)
				(arc
					(start 342.234266 -430.018952)
					(mid 342.211948 -429.96507)
					(end 342.158066 -429.942752)
				)
				(arc
					(start 341.218266 -429.942752)
					(mid 341.164384 -429.96507)
					(end 341.142066 -430.018952)
				)
			)
		)
	)
	(zone
		(layers "In1.Cu" "In3.Cu" "In5.Cu" "In7.Cu" "In8.Cu" "In9.Cu" "In14.Cu"
			"In16.Cu"
		)
		(hatch none 0.5)
		(connect_pads
			(clearance 0)
		)
		(min_thickness 0.25)
		(keepout
			(tracks not_allowed)
			(vias allowed)
			(pads allowed)
			(copperpour not_allowed)
			(footprints allowed)
		)
		(placement
			(enabled no)
			(sheetname "")
		)
		(fill yes
			(thermal_gap 0.5)
			(thermal_bridge_width 0.5)
			(island_removal_mode 0)
		)
		(polygon
			(pts
				(arc
					(start 68.142104 -432.560476)
					(mid 68.164422 -432.614358)
					(end 68.218304 -432.636676)
				)
				(arc
					(start 69.158104 -432.636676)
					(mid 69.211986 -432.614358)
					(end 69.234304 -432.560476)
				)
				(arc
					(start 69.234304 -430.018952)
					(mid 69.211986 -429.96507)
					(end 69.158104 -429.942752)
				)
				(arc
					(start 68.218304 -429.942752)
					(mid 68.164422 -429.96507)
					(end 68.142104 -430.018952)
				)
			)
		)
	)
	(zone
		(layers "In1.Cu" "In3.Cu" "In5.Cu" "In7.Cu" "In8.Cu" "In9.Cu" "In14.Cu"
			"In16.Cu"
		)
		(hatch none 0.5)
		(connect_pads
			(clearance 0)
		)
		(min_thickness 0.25)
		(keepout
			(tracks not_allowed)
			(vias allowed)
			(pads allowed)
			(copperpour not_allowed)
			(footprints allowed)
		)
		(placement
			(enabled no)
			(sheetname "")
		)
		(fill yes
			(thermal_gap 0.5)
			(thermal_bridge_width 0.5)
			(island_removal_mode 0)
		)
		(polygon
			(pts
				(arc
					(start 79.142082 -431.560478)
					(mid 79.1644 -431.61436)
					(end 79.218282 -431.636678)
				)
				(arc
					(start 80.158082 -431.636678)
					(mid 80.211964 -431.61436)
					(end 80.234282 -431.560478)
				)
				(arc
					(start 80.234282 -429.018954)
					(mid 80.211964 -428.965072)
					(end 80.158082 -428.942754)
				)
				(arc
					(start 79.218282 -428.942754)
					(mid 79.1644 -428.965072)
					(end 79.142082 -429.018954)
				)
			)
		)
	)
	(zone
		(layers "In1.Cu" "In3.Cu" "In5.Cu" "In7.Cu" "In8.Cu" "In9.Cu" "In14.Cu"
			"In16.Cu"
		)
		(hatch none 0.5)
		(connect_pads
			(clearance 0)
		)
		(min_thickness 0.25)
		(keepout
			(tracks not_allowed)
			(vias allowed)
			(pads allowed)
			(copperpour not_allowed)
			(footprints allowed)
		)
		(placement
			(enabled no)
			(sheetname "")
		)
		(fill yes
			(thermal_gap 0.5)
			(thermal_bridge_width 0.5)
			(island_removal_mode 0)
		)
		(polygon
			(pts
				(arc
					(start 326.142096 -431.560478)
					(mid 326.164414 -431.61436)
					(end 326.218296 -431.636678)
				)
				(arc
					(start 327.158096 -431.636678)
					(mid 327.211978 -431.61436)
					(end 327.234296 -431.560478)
				)
				(arc
					(start 327.234296 -429.018954)
					(mid 327.211978 -428.965072)
					(end 327.158096 -428.942754)
				)
				(arc
					(start 326.218296 -428.942754)
					(mid 326.164414 -428.965072)
					(end 326.142096 -429.018954)
				)
			)
		)
	)
	(zone
		(layers "In1.Cu" "In3.Cu" "In5.Cu" "In7.Cu" "In8.Cu" "In9.Cu" "In14.Cu"
			"In16.Cu"
		)
		(hatch none 0.5)
		(connect_pads
			(clearance 0)
		)
		(min_thickness 0.25)
		(keepout
			(tracks not_allowed)
			(vias allowed)
			(pads allowed)
			(copperpour not_allowed)
			(footprints allowed)
		)
		(placement
			(enabled no)
			(sheetname "")
		)
		(fill yes
			(thermal_gap 0.5)
			(thermal_bridge_width 0.5)
			(island_removal_mode 0)
		)
		(polygon
			(pts
				(arc
					(start 77.142086 -432.560476)
					(mid 77.164404 -432.614358)
					(end 77.218286 -432.636676)
				)
				(arc
					(start 78.158086 -432.636676)
					(mid 78.211968 -432.614358)
					(end 78.234286 -432.560476)
				)
				(arc
					(start 78.234286 -430.018952)
					(mid 78.211968 -429.96507)
					(end 78.158086 -429.942752)
				)
				(arc
					(start 77.218286 -429.942752)
					(mid 77.164404 -429.96507)
					(end 77.142086 -430.018952)
				)
			)
		)
	)
	(zone
		(layers "In1.Cu" "In3.Cu" "In5.Cu" "In7.Cu" "In8.Cu" "In9.Cu" "In14.Cu"
			"In16.Cu"
		)
		(hatch none 0.5)
		(connect_pads
			(clearance 0)
		)
		(min_thickness 0.25)
		(keepout
			(tracks not_allowed)
			(vias allowed)
			(pads allowed)
			(copperpour not_allowed)
			(footprints allowed)
		)
		(placement
			(enabled no)
			(sheetname "")
		)
		(fill yes
			(thermal_gap 0.5)
			(thermal_bridge_width 0.5)
			(island_removal_mode 0)
		)
		(polygon
			(pts
				(arc
					(start 320.142108 -432.560476)
					(mid 320.164426 -432.614358)
					(end 320.218308 -432.636676)
				)
				(arc
					(start 321.158108 -432.636676)
					(mid 321.21199 -432.614358)
					(end 321.234308 -432.560476)
				)
				(arc
					(start 321.234308 -430.018952)
					(mid 321.21199 -429.96507)
					(end 321.158108 -429.942752)
				)
				(arc
					(start 320.218308 -429.942752)
					(mid 320.164426 -429.96507)
					(end 320.142108 -430.018952)
				)
			)
		)
	)
	(zone
		(layers "In1.Cu" "In3.Cu" "In5.Cu" "In7.Cu" "In8.Cu" "In9.Cu" "In14.Cu"
			"In16.Cu"
		)
		(hatch none 0.5)
		(connect_pads
			(clearance 0)
		)
		(min_thickness 0.25)
		(keepout
			(tracks not_allowed)
			(vias allowed)
			(pads allowed)
			(copperpour not_allowed)
			(footprints allowed)
		)
		(placement
			(enabled no)
			(sheetname "")
		)
		(fill yes
			(thermal_gap 0.5)
			(thermal_bridge_width 0.5)
			(island_removal_mode 0)
		)
		(polygon
			(pts
				(arc
					(start 62.142116 -431.560478)
					(mid 62.164434 -431.61436)
					(end 62.218316 -431.636678)
				)
				(arc
					(start 63.158116 -431.636678)
					(mid 63.211998 -431.61436)
					(end 63.234316 -431.560478)
				)
				(arc
					(start 63.234316 -429.018954)
					(mid 63.211998 -428.965072)
					(end 63.158116 -428.942754)
				)
				(arc
					(start 62.218316 -428.942754)
					(mid 62.164434 -428.965072)
					(end 62.142116 -429.018954)
				)
			)
		)
	)
	(zone
		(layers "In1.Cu" "In3.Cu" "In5.Cu" "In7.Cu" "In8.Cu" "In9.Cu" "In14.Cu"
			"In16.Cu"
		)
		(hatch none 0.5)
		(connect_pads
			(clearance 0)
		)
		(min_thickness 0.25)
		(keepout
			(tracks not_allowed)
			(vias allowed)
			(pads allowed)
			(copperpour not_allowed)
			(footprints allowed)
		)
		(placement
			(enabled no)
			(sheetname "")
		)
		(fill yes
			(thermal_gap 0.5)
			(thermal_bridge_width 0.5)
			(island_removal_mode 0)
		)
		(polygon
			(pts
				(arc
					(start 316.142116 -432.560476)
					(mid 316.164434 -432.614358)
					(end 316.218316 -432.636676)
				)
				(arc
					(start 317.158116 -432.636676)
					(mid 317.211998 -432.614358)
					(end 317.234316 -432.560476)
				)
				(arc
					(start 317.234316 -430.018952)
					(mid 317.211998 -429.96507)
					(end 317.158116 -429.942752)
				)
				(arc
					(start 316.218316 -429.942752)
					(mid 316.164434 -429.96507)
					(end 316.142116 -430.018952)
				)
			)
		)
	)
	(zone
		(layers "In1.Cu" "In3.Cu" "In5.Cu" "In7.Cu" "In8.Cu" "In9.Cu" "In14.Cu"
			"In16.Cu"
		)
		(hatch none 0.5)
		(connect_pads
			(clearance 0)
		)
		(min_thickness 0.25)
		(keepout
			(tracks not_allowed)
			(vias allowed)
			(pads allowed)
			(copperpour not_allowed)
			(footprints allowed)
		)
		(placement
			(enabled no)
			(sheetname "")
		)
		(fill yes
			(thermal_gap 0.5)
			(thermal_bridge_width 0.5)
			(island_removal_mode 0)
		)
		(polygon
			(pts
				(arc
					(start 64.142112 -432.560476)
					(mid 64.16443 -432.614358)
					(end 64.218312 -432.636676)
				)
				(arc
					(start 65.158112 -432.636676)
					(mid 65.211994 -432.614358)
					(end 65.234312 -432.560476)
				)
				(arc
					(start 65.234312 -430.018952)
					(mid 65.211994 -429.96507)
					(end 65.158112 -429.942752)
				)
				(arc
					(start 64.218312 -429.942752)
					(mid 64.16443 -429.96507)
					(end 64.142112 -430.018952)
				)
			)
		)
	)
	(zone
		(layers "In1.Cu" "In3.Cu" "In5.Cu" "In7.Cu" "In8.Cu" "In9.Cu" "In14.Cu"
			"In16.Cu"
		)
		(hatch none 0.5)
		(connect_pads
			(clearance 0)
		)
		(min_thickness 0.25)
		(keepout
			(tracks not_allowed)
			(vias allowed)
			(pads allowed)
			(copperpour not_allowed)
			(footprints allowed)
		)
		(placement
			(enabled no)
			(sheetname "")
		)
		(fill yes
			(thermal_gap 0.5)
			(thermal_bridge_width 0.5)
			(island_removal_mode 0)
		)
		(polygon
			(pts
				(arc
					(start 343.142062 -431.560478)
					(mid 343.16438 -431.61436)
					(end 343.218262 -431.636678)
				)
				(arc
					(start 344.158062 -431.636678)
					(mid 344.211944 -431.61436)
					(end 344.234262 -431.560478)
				)
				(arc
					(start 344.234262 -429.018954)
					(mid 344.211944 -428.965072)
					(end 344.158062 -428.942754)
				)
				(arc
					(start 343.218262 -428.942754)
					(mid 343.16438 -428.965072)
					(end 343.142062 -429.018954)
				)
			)
		)
	)
	(zone
		(layers "In1.Cu" "In3.Cu" "In5.Cu" "In7.Cu" "In8.Cu" "In9.Cu" "In14.Cu"
			"In16.Cu"
		)
		(hatch none 0.5)
		(connect_pads
			(clearance 0)
		)
		(min_thickness 0.25)
		(keepout
			(tracks not_allowed)
			(vias allowed)
			(pads allowed)
			(copperpour not_allowed)
			(footprints allowed)
		)
		(placement
			(enabled no)
			(sheetname "")
		)
		(fill yes
			(thermal_gap 0.5)
			(thermal_bridge_width 0.5)
			(island_removal_mode 0)
		)
		(polygon
			(pts
				(arc
					(start 58.142124 -431.560478)
					(mid 58.164442 -431.61436)
					(end 58.218324 -431.636678)
				)
				(arc
					(start 59.158124 -431.636678)
					(mid 59.212006 -431.61436)
					(end 59.234324 -431.560478)
				)
				(arc
					(start 59.234324 -429.018954)
					(mid 59.212006 -428.965072)
					(end 59.158124 -428.942754)
				)
				(arc
					(start 58.218324 -428.942754)
					(mid 58.164442 -428.965072)
					(end 58.142124 -429.018954)
				)
			)
		)
	)
	(zone
		(layers "In1.Cu" "In3.Cu" "In5.Cu" "In7.Cu" "In8.Cu" "In9.Cu" "In14.Cu"
			"In16.Cu"
		)
		(hatch none 0.5)
		(connect_pads
			(clearance 0)
		)
		(min_thickness 0.25)
		(keepout
			(tracks not_allowed)
			(vias allowed)
			(pads allowed)
			(copperpour not_allowed)
			(footprints allowed)
		)
		(placement
			(enabled no)
			(sheetname "")
		)
		(fill yes
			(thermal_gap 0.5)
			(thermal_bridge_width 0.5)
			(island_removal_mode 0)
		)
		(polygon
			(pts
				(arc
					(start 333.142082 -432.560476)
					(mid 333.1644 -432.614358)
					(end 333.218282 -432.636676)
				)
				(arc
					(start 334.158082 -432.636676)
					(mid 334.211964 -432.614358)
					(end 334.234282 -432.560476)
				)
				(arc
					(start 334.234282 -430.018952)
					(mid 334.211964 -429.96507)
					(end 334.158082 -429.942752)
				)
				(arc
					(start 333.218282 -429.942752)
					(mid 333.1644 -429.96507)
					(end 333.142082 -430.018952)
				)
			)
		)
	)
	(zone
		(layers "In1.Cu" "In3.Cu" "In5.Cu" "In7.Cu" "In8.Cu" "In9.Cu" "In14.Cu"
			"In16.Cu"
		)
		(hatch none 0.5)
		(connect_pads
			(clearance 0)
		)
		(min_thickness 0.25)
		(keepout
			(tracks not_allowed)
			(vias allowed)
			(pads allowed)
			(copperpour not_allowed)
			(footprints allowed)
		)
		(placement
			(enabled no)
			(sheetname "")
		)
		(fill yes
			(thermal_gap 0.5)
			(thermal_bridge_width 0.5)
			(island_removal_mode 0)
		)
		(polygon
			(pts
				(arc
					(start 324.1421 -432.560476)
					(mid 324.164418 -432.614358)
					(end 324.2183 -432.636676)
				)
				(arc
					(start 325.1581 -432.636676)
					(mid 325.211982 -432.614358)
					(end 325.2343 -432.560476)
				)
				(arc
					(start 325.2343 -430.018952)
					(mid 325.211982 -429.96507)
					(end 325.1581 -429.942752)
				)
				(arc
					(start 324.2183 -429.942752)
					(mid 324.164418 -429.96507)
					(end 324.1421 -430.018952)
				)
			)
		)
	)
	(zone
		(layers "In1.Cu" "In3.Cu" "In5.Cu" "In7.Cu" "In8.Cu" "In9.Cu" "In14.Cu"
			"In16.Cu"
		)
		(hatch none 0.5)
		(connect_pads
			(clearance 0)
		)
		(min_thickness 0.25)
		(keepout
			(tracks not_allowed)
			(vias allowed)
			(pads allowed)
			(copperpour not_allowed)
			(footprints allowed)
		)
		(placement
			(enabled no)
			(sheetname "")
		)
		(fill yes
			(thermal_gap 0.5)
			(thermal_bridge_width 0.5)
			(island_removal_mode 0)
		)
		(polygon
			(pts
				(arc
					(start 339.14207 -431.560478)
					(mid 339.164388 -431.61436)
					(end 339.21827 -431.636678)
				)
				(arc
					(start 340.15807 -431.636678)
					(mid 340.211952 -431.61436)
					(end 340.23427 -431.560478)
				)
				(arc
					(start 340.23427 -429.018954)
					(mid 340.211952 -428.965072)
					(end 340.15807 -428.942754)
				)
				(arc
					(start 339.21827 -428.942754)
					(mid 339.164388 -428.965072)
					(end 339.14207 -429.018954)
				)
			)
		)
	)
	(zone
		(layers "In1.Cu" "In3.Cu" "In5.Cu" "In7.Cu" "In8.Cu" "In9.Cu" "In14.Cu"
			"In16.Cu"
		)
		(hatch none 0.5)
		(connect_pads
			(clearance 0)
		)
		(min_thickness 0.25)
		(keepout
			(tracks not_allowed)
			(vias allowed)
			(pads allowed)
			(copperpour not_allowed)
			(footprints allowed)
		)
		(placement
			(enabled no)
			(sheetname "")
		)
		(fill yes
			(thermal_gap 0.5)
			(thermal_bridge_width 0.5)
			(island_removal_mode 0)
		)
		(polygon
			(pts
				(arc
					(start 331.142086 -431.560478)
					(mid 331.164404 -431.61436)
					(end 331.218286 -431.636678)
				)
				(arc
					(start 332.158086 -431.636678)
					(mid 332.211968 -431.61436)
					(end 332.234286 -431.560478)
				)
				(arc
					(start 332.234286 -429.018954)
					(mid 332.211968 -428.965072)
					(end 332.158086 -428.942754)
				)
				(arc
					(start 331.218286 -428.942754)
					(mid 331.164404 -428.965072)
					(end 331.142086 -429.018954)
				)
			)
		)
	)
	(zone
		(layers "In1.Cu" "In3.Cu" "In5.Cu" "In7.Cu" "In8.Cu" "In9.Cu" "In14.Cu"
			"In16.Cu"
		)
		(hatch none 0.5)
		(connect_pads
			(clearance 0)
		)
		(min_thickness 0.25)
		(keepout
			(tracks not_allowed)
			(vias allowed)
			(pads allowed)
			(copperpour not_allowed)
			(footprints allowed)
		)
		(placement
			(enabled no)
			(sheetname "")
		)
		(fill yes
			(thermal_gap 0.5)
			(thermal_bridge_width 0.5)
			(island_removal_mode 0)
		)
		(polygon
			(pts
				(arc
					(start 314.14212 -431.560478)
					(mid 314.164438 -431.61436)
					(end 314.21832 -431.636678)
				)
				(arc
					(start 315.15812 -431.636678)
					(mid 315.212002 -431.61436)
					(end 315.23432 -431.560478)
				)
				(arc
					(start 315.23432 -429.018954)
					(mid 315.212002 -428.965072)
					(end 315.15812 -428.942754)
				)
				(arc
					(start 314.21832 -428.942754)
					(mid 314.164438 -428.965072)
					(end 314.14212 -429.018954)
				)
			)
		)
	)
	(zone
		(layers "In1.Cu" "In3.Cu" "In5.Cu" "In7.Cu" "In8.Cu" "In9.Cu" "In14.Cu"
			"In16.Cu"
		)
		(hatch none 0.5)
		(connect_pads
			(clearance 0)
		)
		(min_thickness 0.25)
		(keepout
			(tracks not_allowed)
			(vias allowed)
			(pads allowed)
			(copperpour not_allowed)
			(footprints allowed)
		)
		(placement
			(enabled no)
			(sheetname "")
		)
		(fill yes
			(thermal_gap 0.5)
			(thermal_bridge_width 0.5)
			(island_removal_mode 0)
		)
		(polygon
			(pts
				(arc
					(start 322.142104 -431.560478)
					(mid 322.164422 -431.61436)
					(end 322.218304 -431.636678)
				)
				(arc
					(start 323.158104 -431.636678)
					(mid 323.211986 -431.61436)
					(end 323.234304 -431.560478)
				)
				(arc
					(start 323.234304 -429.018954)
					(mid 323.211986 -428.965072)
					(end 323.158104 -428.942754)
				)
				(arc
					(start 322.218304 -428.942754)
					(mid 322.164422 -428.965072)
					(end 322.142104 -429.018954)
				)
			)
		)
	)
	(zone
		(layers "In1.Cu" "In3.Cu" "In5.Cu" "In7.Cu" "In8.Cu" "In9.Cu" "In14.Cu"
			"In16.Cu"
		)
		(hatch none 0.5)
		(connect_pads
			(clearance 0)
		)
		(min_thickness 0.25)
		(keepout
			(tracks not_allowed)
			(vias allowed)
			(pads allowed)
			(copperpour not_allowed)
			(footprints allowed)
		)
		(placement
			(enabled no)
			(sheetname "")
		)
		(fill yes
			(thermal_gap 0.5)
			(thermal_bridge_width 0.5)
			(island_removal_mode 0)
		)
		(polygon
			(pts
				(arc
					(start 337.142074 -432.560476)
					(mid 337.164392 -432.614358)
					(end 337.218274 -432.636676)
				)
				(arc
					(start 338.158074 -432.636676)
					(mid 338.211956 -432.614358)
					(end 338.234274 -432.560476)
				)
				(arc
					(start 338.234274 -430.018952)
					(mid 338.211956 -429.96507)
					(end 338.158074 -429.942752)
				)
				(arc
					(start 337.218274 -429.942752)
					(mid 337.164392 -429.96507)
					(end 337.142074 -430.018952)
				)
			)
		)
	)
	(zone
		(layers "In1.Cu" "In3.Cu" "In5.Cu" "In7.Cu" "In8.Cu" "In9.Cu" "In14.Cu"
			"In16.Cu"
		)
		(hatch none 0.5)
		(connect_pads
			(clearance 0)
		)
		(min_thickness 0.25)
		(keepout
			(tracks not_allowed)
			(vias allowed)
			(pads allowed)
			(copperpour not_allowed)
			(footprints allowed)
		)
		(placement
			(enabled no)
			(sheetname "")
		)
		(fill yes
			(thermal_gap 0.5)
			(thermal_bridge_width 0.5)
			(island_removal_mode 0)
		)
		(polygon
			(pts
				(arc
					(start 83.142074 -431.560478)
					(mid 83.164392 -431.61436)
					(end 83.218274 -431.636678)
				)
				(arc
					(start 84.158074 -431.636678)
					(mid 84.211956 -431.61436)
					(end 84.234274 -431.560478)
				)
				(arc
					(start 84.234274 -429.018954)
					(mid 84.211956 -428.965072)
					(end 84.158074 -428.942754)
				)
				(arc
					(start 83.218274 -428.942754)
					(mid 83.164392 -428.965072)
					(end 83.142074 -429.018954)
				)
			)
		)
	)
	(zone
		(layers "In1.Cu" "In3.Cu" "In5.Cu" "In7.Cu" "In8.Cu" "In9.Cu" "In14.Cu"
			"In16.Cu"
		)
		(hatch none 0.5)
		(connect_pads
			(clearance 0)
		)
		(min_thickness 0.25)
		(keepout
			(tracks not_allowed)
			(vias allowed)
			(pads allowed)
			(copperpour not_allowed)
			(footprints allowed)
		)
		(placement
			(enabled no)
			(sheetname "")
		)
		(fill yes
			(thermal_gap 0.5)
			(thermal_bridge_width 0.5)
			(island_removal_mode 0)
		)
		(polygon
			(pts
				(arc
					(start 60.14212 -432.560476)
					(mid 60.164438 -432.614358)
					(end 60.21832 -432.636676)
				)
				(arc
					(start 61.15812 -432.636676)
					(mid 61.212002 -432.614358)
					(end 61.23432 -432.560476)
				)
				(arc
					(start 61.23432 -430.018952)
					(mid 61.212002 -429.96507)
					(end 61.15812 -429.942752)
				)
				(arc
					(start 60.21832 -429.942752)
					(mid 60.164438 -429.96507)
					(end 60.14212 -430.018952)
				)
			)
		)
	)
	(zone
		(layers "In1.Cu" "In3.Cu" "In5.Cu" "In7.Cu" "In8.Cu" "In9.Cu" "In14.Cu"
			"In16.Cu"
		)
		(hatch none 0.5)
		(connect_pads
			(clearance 0)
		)
		(min_thickness 0.25)
		(keepout
			(tracks not_allowed)
			(vias allowed)
			(pads allowed)
			(copperpour not_allowed)
			(footprints allowed)
		)
		(placement
			(enabled no)
			(sheetname "")
		)
		(fill yes
			(thermal_gap 0.5)
			(thermal_bridge_width 0.5)
			(island_removal_mode 0)
		)
		(polygon
			(pts
				(arc
					(start 87.142066 -431.560478)
					(mid 87.164384 -431.61436)
					(end 87.218266 -431.636678)
				)
				(arc
					(start 88.158066 -431.636678)
					(mid 88.211948 -431.61436)
					(end 88.234266 -431.560478)
				)
				(arc
					(start 88.234266 -429.018954)
					(mid 88.211948 -428.965072)
					(end 88.158066 -428.942754)
				)
				(arc
					(start 87.218266 -428.942754)
					(mid 87.164384 -428.965072)
					(end 87.142066 -429.018954)
				)
			)
		)
	)
	(zone
		(layers "In1.Cu" "In3.Cu" "In5.Cu" "In7.Cu" "In8.Cu" "In9.Cu" "In14.Cu"
			"In16.Cu"
		)
		(hatch none 0.5)
		(connect_pads
			(clearance 0)
		)
		(min_thickness 0.25)
		(keepout
			(tracks not_allowed)
			(vias allowed)
			(pads allowed)
			(copperpour not_allowed)
			(footprints allowed)
		)
		(placement
			(enabled no)
			(sheetname "")
		)
		(fill yes
			(thermal_gap 0.5)
			(thermal_bridge_width 0.5)
			(island_removal_mode 0)
		)
		(polygon
			(pts
				(arc
					(start 81.142078 -432.560476)
					(mid 81.164396 -432.614358)
					(end 81.218278 -432.636676)
				)
				(arc
					(start 82.158078 -432.636676)
					(mid 82.21196 -432.614358)
					(end 82.234278 -432.560476)
				)
				(arc
					(start 82.234278 -430.018952)
					(mid 82.21196 -429.96507)
					(end 82.158078 -429.942752)
				)
				(arc
					(start 81.218278 -429.942752)
					(mid 81.164396 -429.96507)
					(end 81.142078 -430.018952)
				)
			)
		)
	)
	(zone
		(layers "In1.Cu" "In3.Cu" "In5.Cu" "In7.Cu" "In8.Cu" "In9.Cu" "In14.Cu"
			"In16.Cu"
		)
		(hatch none 0.5)
		(connect_pads
			(clearance 0)
		)
		(min_thickness 0.25)
		(keepout
			(tracks not_allowed)
			(vias allowed)
			(pads allowed)
			(copperpour not_allowed)
			(footprints allowed)
		)
		(placement
			(enabled no)
			(sheetname "")
		)
		(fill yes
			(thermal_gap 0.5)
			(thermal_bridge_width 0.5)
			(island_removal_mode 0)
		)
		(polygon
			(pts
				(arc
					(start 72.142096 -432.560476)
					(mid 72.164414 -432.614358)
					(end 72.218296 -432.636676)
				)
				(arc
					(start 73.158096 -432.636676)
					(mid 73.211978 -432.614358)
					(end 73.234296 -432.560476)
				)
				(arc
					(start 73.234296 -430.018952)
					(mid 73.211978 -429.96507)
					(end 73.158096 -429.942752)
				)
				(arc
					(start 72.218296 -429.942752)
					(mid 72.164414 -429.96507)
					(end 72.142096 -430.018952)
				)
			)
		)
	)
	(zone
		(layers "In1.Cu" "In3.Cu" "In5.Cu" "In7.Cu" "In8.Cu" "In9.Cu" "In14.Cu"
			"In16.Cu"
		)
		(hatch none 0.5)
		(connect_pads
			(clearance 0)
		)
		(min_thickness 0.25)
		(keepout
			(tracks not_allowed)
			(vias allowed)
			(pads allowed)
			(copperpour not_allowed)
			(footprints allowed)
		)
		(placement
			(enabled no)
			(sheetname "")
		)
		(fill yes
			(thermal_gap 0.5)
			(thermal_bridge_width 0.5)
			(island_removal_mode 0)
		)
		(polygon
			(pts
				(arc
					(start 70.1421 -431.560478)
					(mid 70.164418 -431.61436)
					(end 70.2183 -431.636678)
				)
				(arc
					(start 71.1581 -431.636678)
					(mid 71.211982 -431.61436)
					(end 71.2343 -431.560478)
				)
				(arc
					(start 71.2343 -429.018954)
					(mid 71.211982 -428.965072)
					(end 71.1581 -428.942754)
				)
				(arc
					(start 70.2183 -428.942754)
					(mid 70.164418 -428.965072)
					(end 70.1421 -429.018954)
				)
			)
		)
	)
	(zone
		(layers "In1.Cu" "In3.Cu" "In5.Cu" "In7.Cu" "In8.Cu" "In9.Cu" "In14.Cu"
			"In16.Cu"
		)
		(hatch none 0.5)
		(connect_pads
			(clearance 0)
		)
		(min_thickness 0.25)
		(keepout
			(tracks not_allowed)
			(vias allowed)
			(pads allowed)
			(copperpour not_allowed)
			(footprints allowed)
		)
		(placement
			(enabled no)
			(sheetname "")
		)
		(fill yes
			(thermal_gap 0.5)
			(thermal_bridge_width 0.5)
			(island_removal_mode 0)
		)
		(polygon
			(pts
				(arc
					(start 85.14207 -432.560476)
					(mid 85.164388 -432.614358)
					(end 85.21827 -432.636676)
				)
				(arc
					(start 86.15807 -432.636676)
					(mid 86.211952 -432.614358)
					(end 86.23427 -432.560476)
				)
				(arc
					(start 86.23427 -430.018952)
					(mid 86.211952 -429.96507)
					(end 86.15807 -429.942752)
				)
				(arc
					(start 85.21827 -429.942752)
					(mid 85.164388 -429.96507)
					(end 85.14207 -430.018952)
				)
			)
		)
	)
	(zone
		(layers "In1.Cu" "In3.Cu" "In5.Cu" "In7.Cu" "In8.Cu" "In9.Cu" "In14.Cu"
			"In16.Cu"
		)
		(hatch none 0.5)
		(connect_pads
			(clearance 0)
		)
		(min_thickness 0.25)
		(keepout
			(tracks not_allowed)
			(vias allowed)
			(pads allowed)
			(copperpour not_allowed)
			(footprints allowed)
		)
		(placement
			(enabled no)
			(sheetname "")
		)
		(fill yes
			(thermal_gap 0.5)
			(thermal_bridge_width 0.5)
			(island_removal_mode 0)
		)
		(polygon
			(pts
				(arc
					(start 318.142112 -431.560478)
					(mid 318.16443 -431.61436)
					(end 318.218312 -431.636678)
				)
				(arc
					(start 319.158112 -431.636678)
					(mid 319.211994 -431.61436)
					(end 319.234312 -431.560478)
				)
				(arc
					(start 319.234312 -429.018954)
					(mid 319.211994 -428.965072)
					(end 319.158112 -428.942754)
				)
				(arc
					(start 318.218312 -428.942754)
					(mid 318.16443 -428.965072)
					(end 318.142112 -429.018954)
				)
			)
		)
	)
	(zone
		(layers "In1.Cu" "In3.Cu" "In5.Cu" "In7.Cu" "In8.Cu" "In9.Cu" "In14.Cu"
			"In16.Cu"
		)
		(hatch none 0.5)
		(connect_pads
			(clearance 0)
		)
		(min_thickness 0.25)
		(keepout
			(tracks not_allowed)
			(vias allowed)
			(pads allowed)
			(copperpour not_allowed)
			(footprints allowed)
		)
		(placement
			(enabled no)
			(sheetname "")
		)
		(fill yes
			(thermal_gap 0.5)
			(thermal_bridge_width 0.5)
			(island_removal_mode 0)
		)
		(polygon
			(pts
				(arc
					(start 335.142078 -431.560478)
					(mid 335.164396 -431.61436)
					(end 335.218278 -431.636678)
				)
				(arc
					(start 336.158078 -431.636678)
					(mid 336.21196 -431.61436)
					(end 336.234278 -431.560478)
				)
				(arc
					(start 336.234278 -429.018954)
					(mid 336.21196 -428.965072)
					(end 336.158078 -428.942754)
				)
				(arc
					(start 335.218278 -428.942754)
					(mid 335.164396 -428.965072)
					(end 335.142078 -429.018954)
				)
			)
		)
	)
	(zone
		(layers "In1.Cu" "In3.Cu" "In5.Cu" "In7.Cu" "In8.Cu" "In9.Cu" "In14.Cu"
			"In16.Cu"
		)
		(hatch none 0.5)
		(connect_pads
			(clearance 0)
		)
		(min_thickness 0.25)
		(keepout
			(tracks not_allowed)
			(vias allowed)
			(pads allowed)
			(copperpour not_allowed)
			(footprints allowed)
		)
		(placement
			(enabled no)
			(sheetname "")
		)
		(fill yes
			(thermal_gap 0.5)
			(thermal_bridge_width 0.5)
			(island_removal_mode 0)
		)
		(polygon
			(pts
				(arc
					(start 328.142092 -432.560476)
					(mid 328.16441 -432.614358)
					(end 328.218292 -432.636676)
				)
				(arc
					(start 329.158092 -432.636676)
					(mid 329.211974 -432.614358)
					(end 329.234292 -432.560476)
				)
				(arc
					(start 329.234292 -430.018952)
					(mid 329.211974 -429.96507)
					(end 329.158092 -429.942752)
				)
				(arc
					(start 328.218292 -429.942752)
					(mid 328.16441 -429.96507)
					(end 328.142092 -430.018952)
				)
			)
		)
	)
	(zone
		(layers "In1.Cu" "In3.Cu" "In5.Cu" "In7.Cu" "In8.Cu" "In9.Cu" "In14.Cu"
			"In16.Cu"
		)
		(hatch none 0.5)
		(connect_pads
			(clearance 0)
		)
		(min_thickness 0.25)
		(keepout
			(tracks not_allowed)
			(vias allowed)
			(pads allowed)
			(copperpour not_allowed)
			(footprints allowed)
		)
		(placement
			(enabled no)
			(sheetname "")
		)
		(fill yes
			(thermal_gap 0.5)
			(thermal_bridge_width 0.5)
			(island_removal_mode 0)
		)
		(polygon
			(pts
				(arc
					(start 75.14209 -431.560478)
					(mid 75.164408 -431.61436)
					(end 75.21829 -431.636678)
				)
				(arc
					(start 76.15809 -431.636678)
					(mid 76.211972 -431.61436)
					(end 76.23429 -431.560478)
				)
				(arc
					(start 76.23429 -429.018954)
					(mid 76.211972 -428.965072)
					(end 76.15809 -428.942754)
				)
				(arc
					(start 75.21829 -428.942754)
					(mid 75.164408 -428.965072)
					(end 75.14209 -429.018954)
				)
			)
		)
	)
	(zone
		(layers "In1.Cu" "In3.Cu" "In5.Cu" "In8.Cu" "In9.Cu" "In12.Cu" "In14.Cu"
			"In16.Cu"
		)
		(hatch none 0.5)
		(connect_pads
			(clearance 0)
		)
		(min_thickness 0.25)
		(keepout
			(tracks allowed)
			(vias allowed)
			(pads allowed)
			(copperpour allowed)
			(footprints allowed)
		)
		(placement
			(enabled no)
			(sheetname "")
		)
		(fill yes
			(thermal_gap 0.5)
			(thermal_bridge_width 0.5)
			(island_removal_mode 0)
		)
		(polygon
			(pts
				(xy 333.82966 -292.57498) (xy 385.06146 -292.574218) (xy 388.744206 -288.890964) (xy 388.742936 -216.729564)
				(xy 384.094736 -212.081618) (xy 335.733136 -212.08238) (xy 329.94219 -217.873834) (xy 329.943206 -288.689034)
			)
		)
	)
	(zone
		(layers "In1.Cu" "In3.Cu" "In5.Cu" "In8.Cu" "In9.Cu" "In12.Cu" "In14.Cu"
			"In16.Cu"
		)
		(hatch none 0.5)
		(connect_pads
			(clearance 0)
		)
		(min_thickness 0.25)
		(keepout
			(tracks allowed)
			(vias allowed)
			(pads allowed)
			(copperpour allowed)
			(footprints allowed)
		)
		(placement
			(enabled no)
			(sheetname "")
		)
		(fill yes
			(thermal_gap 0.5)
			(thermal_bridge_width 0.5)
			(island_removal_mode 0)
		)
		(polygon
			(pts
				(xy 85.889592 -292.57498) (xy 137.121392 -292.574218) (xy 140.804138 -288.890964) (xy 140.802868 -216.729564)
				(xy 136.154668 -212.081618) (xy 87.793068 -212.08238) (xy 82.002122 -217.873834) (xy 82.003138 -288.689034)
			)
		)
	)
	(zone
		(layers "In1.Cu" "In3.Cu" "In8.Cu" "In9.Cu" "In10.Cu" "In12.Cu" "In13.Cu"
			"In14.Cu" "In16.Cu"
		)
		(hatch none 0.5)
		(connect_pads
			(clearance 0)
		)
		(min_thickness 0.25)
		(keepout
			(tracks not_allowed)
			(vias allowed)
			(pads allowed)
			(copperpour not_allowed)
			(footprints allowed)
		)
		(placement
			(enabled no)
			(sheetname "")
		)
		(fill yes
			(thermal_gap 0.5)
			(thermal_bridge_width 0.5)
			(island_removal_mode 0)
		)
		(polygon
			(pts
				(arc
					(start 62.142116 -427.960536)
					(mid 62.164434 -428.014418)
					(end 62.218316 -428.036736)
				)
				(arc
					(start 63.158116 -428.036736)
					(mid 63.211998 -428.014418)
					(end 63.234316 -427.960536)
				)
				(arc
					(start 63.234316 -425.419012)
					(mid 63.211998 -425.36513)
					(end 63.158116 -425.342812)
				)
				(arc
					(start 62.218316 -425.342812)
					(mid 62.164434 -425.36513)
					(end 62.142116 -425.419012)
				)
			)
		)
	)
	(zone
		(layers "In1.Cu" "In3.Cu" "In8.Cu" "In9.Cu" "In10.Cu" "In12.Cu" "In13.Cu"
			"In14.Cu" "In16.Cu"
		)
		(hatch none 0.5)
		(connect_pads
			(clearance 0)
		)
		(min_thickness 0.25)
		(keepout
			(tracks not_allowed)
			(vias allowed)
			(pads allowed)
			(copperpour not_allowed)
			(footprints allowed)
		)
		(placement
			(enabled no)
			(sheetname "")
		)
		(fill yes
			(thermal_gap 0.5)
			(thermal_bridge_width 0.5)
			(island_removal_mode 0)
		)
		(polygon
			(pts
				(arc
					(start 331.142086 -427.960536)
					(mid 331.164404 -428.014418)
					(end 331.218286 -428.036736)
				)
				(arc
					(start 332.158086 -428.036736)
					(mid 332.211968 -428.014418)
					(end 332.234286 -427.960536)
				)
				(arc
					(start 332.234286 -425.419012)
					(mid 332.211968 -425.36513)
					(end 332.158086 -425.342812)
				)
				(arc
					(start 331.218286 -425.342812)
					(mid 331.164404 -425.36513)
					(end 331.142086 -425.419012)
				)
			)
		)
	)
	(zone
		(layers "In1.Cu" "In3.Cu" "In8.Cu" "In9.Cu" "In10.Cu" "In12.Cu" "In13.Cu"
			"In14.Cu" "In16.Cu"
		)
		(hatch none 0.5)
		(connect_pads
			(clearance 0)
		)
		(min_thickness 0.25)
		(keepout
			(tracks not_allowed)
			(vias allowed)
			(pads allowed)
			(copperpour not_allowed)
			(footprints allowed)
		)
		(placement
			(enabled no)
			(sheetname "")
		)
		(fill yes
			(thermal_gap 0.5)
			(thermal_bridge_width 0.5)
			(island_removal_mode 0)
		)
		(polygon
			(pts
				(arc
					(start 314.14212 -427.960536)
					(mid 314.164438 -428.014418)
					(end 314.21832 -428.036736)
				)
				(arc
					(start 315.15812 -428.036736)
					(mid 315.212002 -428.014418)
					(end 315.23432 -427.960536)
				)
				(arc
					(start 315.23432 -425.419012)
					(mid 315.212002 -425.36513)
					(end 315.15812 -425.342812)
				)
				(arc
					(start 314.21832 -425.342812)
					(mid 314.164438 -425.36513)
					(end 314.14212 -425.419012)
				)
			)
		)
	)
	(zone
		(layers "In1.Cu" "In3.Cu" "In8.Cu" "In9.Cu" "In10.Cu" "In12.Cu" "In13.Cu"
			"In14.Cu" "In16.Cu"
		)
		(hatch none 0.5)
		(connect_pads
			(clearance 0)
		)
		(min_thickness 0.25)
		(keepout
			(tracks not_allowed)
			(vias allowed)
			(pads allowed)
			(copperpour not_allowed)
			(footprints allowed)
		)
		(placement
			(enabled no)
			(sheetname "")
		)
		(fill yes
			(thermal_gap 0.5)
			(thermal_bridge_width 0.5)
			(island_removal_mode 0)
		)
		(polygon
			(pts
				(arc
					(start 326.142096 -427.960536)
					(mid 326.164414 -428.014418)
					(end 326.218296 -428.036736)
				)
				(arc
					(start 327.158096 -428.036736)
					(mid 327.211978 -428.014418)
					(end 327.234296 -427.960536)
				)
				(arc
					(start 327.234296 -425.419012)
					(mid 327.211978 -425.36513)
					(end 327.158096 -425.342812)
				)
				(arc
					(start 326.218296 -425.342812)
					(mid 326.164414 -425.36513)
					(end 326.142096 -425.419012)
				)
			)
		)
	)
	(zone
		(layers "In1.Cu" "In3.Cu" "In8.Cu" "In9.Cu" "In10.Cu" "In12.Cu" "In13.Cu"
			"In14.Cu" "In16.Cu"
		)
		(hatch none 0.5)
		(connect_pads
			(clearance 0)
		)
		(min_thickness 0.25)
		(keepout
			(tracks not_allowed)
			(vias allowed)
			(pads allowed)
			(copperpour not_allowed)
			(footprints allowed)
		)
		(placement
			(enabled no)
			(sheetname "")
		)
		(fill yes
			(thermal_gap 0.5)
			(thermal_bridge_width 0.5)
			(island_removal_mode 0)
		)
		(polygon
			(pts
				(arc
					(start 339.14207 -427.960536)
					(mid 339.164388 -428.014418)
					(end 339.21827 -428.036736)
				)
				(arc
					(start 340.15807 -428.036736)
					(mid 340.211952 -428.014418)
					(end 340.23427 -427.960536)
				)
				(arc
					(start 340.23427 -425.419012)
					(mid 340.211952 -425.36513)
					(end 340.15807 -425.342812)
				)
				(arc
					(start 339.21827 -425.342812)
					(mid 339.164388 -425.36513)
					(end 339.14207 -425.419012)
				)
			)
		)
	)
	(zone
		(layers "In1.Cu" "In3.Cu" "In8.Cu" "In9.Cu" "In10.Cu" "In12.Cu" "In13.Cu"
			"In14.Cu" "In16.Cu"
		)
		(hatch none 0.5)
		(connect_pads
			(clearance 0)
		)
		(min_thickness 0.25)
		(keepout
			(tracks not_allowed)
			(vias allowed)
			(pads allowed)
			(copperpour not_allowed)
			(footprints allowed)
		)
		(placement
			(enabled no)
			(sheetname "")
		)
		(fill yes
			(thermal_gap 0.5)
			(thermal_bridge_width 0.5)
			(island_removal_mode 0)
		)
		(polygon
			(pts
				(arc
					(start 335.142078 -427.960536)
					(mid 335.164396 -428.014418)
					(end 335.218278 -428.036736)
				)
				(arc
					(start 336.158078 -428.036736)
					(mid 336.21196 -428.014418)
					(end 336.234278 -427.960536)
				)
				(arc
					(start 336.234278 -425.419012)
					(mid 336.21196 -425.36513)
					(end 336.158078 -425.342812)
				)
				(arc
					(start 335.218278 -425.342812)
					(mid 335.164396 -425.36513)
					(end 335.142078 -425.419012)
				)
			)
		)
	)
	(zone
		(layers "In1.Cu" "In3.Cu" "In8.Cu" "In9.Cu" "In10.Cu" "In12.Cu" "In13.Cu"
			"In14.Cu" "In16.Cu"
		)
		(hatch none 0.5)
		(connect_pads
			(clearance 0)
		)
		(min_thickness 0.25)
		(keepout
			(tracks not_allowed)
			(vias allowed)
			(pads allowed)
			(copperpour not_allowed)
			(footprints allowed)
		)
		(placement
			(enabled no)
			(sheetname "")
		)
		(fill yes
			(thermal_gap 0.5)
			(thermal_bridge_width 0.5)
			(island_removal_mode 0)
		)
		(polygon
			(pts
				(arc
					(start 83.142074 -427.960536)
					(mid 83.164392 -428.014418)
					(end 83.218274 -428.036736)
				)
				(arc
					(start 84.158074 -428.036736)
					(mid 84.211956 -428.014418)
					(end 84.234274 -427.960536)
				)
				(arc
					(start 84.234274 -425.419012)
					(mid 84.211956 -425.36513)
					(end 84.158074 -425.342812)
				)
				(arc
					(start 83.218274 -425.342812)
					(mid 83.164392 -425.36513)
					(end 83.142074 -425.419012)
				)
			)
		)
	)
	(zone
		(layers "In1.Cu" "In3.Cu" "In8.Cu" "In9.Cu" "In10.Cu" "In12.Cu" "In13.Cu"
			"In14.Cu" "In16.Cu"
		)
		(hatch none 0.5)
		(connect_pads
			(clearance 0)
		)
		(min_thickness 0.25)
		(keepout
			(tracks not_allowed)
			(vias allowed)
			(pads allowed)
			(copperpour not_allowed)
			(footprints allowed)
		)
		(placement
			(enabled no)
			(sheetname "")
		)
		(fill yes
			(thermal_gap 0.5)
			(thermal_bridge_width 0.5)
			(island_removal_mode 0)
		)
		(polygon
			(pts
				(arc
					(start 66.142108 -427.960536)
					(mid 66.164426 -428.014418)
					(end 66.218308 -428.036736)
				)
				(arc
					(start 67.158108 -428.036736)
					(mid 67.21199 -428.014418)
					(end 67.234308 -427.960536)
				)
				(arc
					(start 67.234308 -425.419012)
					(mid 67.21199 -425.36513)
					(end 67.158108 -425.342812)
				)
				(arc
					(start 66.218308 -425.342812)
					(mid 66.164426 -425.36513)
					(end 66.142108 -425.419012)
				)
			)
		)
	)
	(zone
		(layers "In1.Cu" "In3.Cu" "In8.Cu" "In9.Cu" "In10.Cu" "In12.Cu" "In13.Cu"
			"In14.Cu" "In16.Cu"
		)
		(hatch none 0.5)
		(connect_pads
			(clearance 0)
		)
		(min_thickness 0.25)
		(keepout
			(tracks not_allowed)
			(vias allowed)
			(pads allowed)
			(copperpour not_allowed)
			(footprints allowed)
		)
		(placement
			(enabled no)
			(sheetname "")
		)
		(fill yes
			(thermal_gap 0.5)
			(thermal_bridge_width 0.5)
			(island_removal_mode 0)
		)
		(polygon
			(pts
				(arc
					(start 58.142124 -427.960536)
					(mid 58.164442 -428.014418)
					(end 58.218324 -428.036736)
				)
				(arc
					(start 59.158124 -428.036736)
					(mid 59.212006 -428.014418)
					(end 59.234324 -427.960536)
				)
				(arc
					(start 59.234324 -425.419012)
					(mid 59.212006 -425.36513)
					(end 59.158124 -425.342812)
				)
				(arc
					(start 58.218324 -425.342812)
					(mid 58.164442 -425.36513)
					(end 58.142124 -425.419012)
				)
			)
		)
	)
	(zone
		(layers "In1.Cu" "In3.Cu" "In8.Cu" "In9.Cu" "In10.Cu" "In12.Cu" "In13.Cu"
			"In14.Cu" "In16.Cu"
		)
		(hatch none 0.5)
		(connect_pads
			(clearance 0)
		)
		(min_thickness 0.25)
		(keepout
			(tracks not_allowed)
			(vias allowed)
			(pads allowed)
			(copperpour not_allowed)
			(footprints allowed)
		)
		(placement
			(enabled no)
			(sheetname "")
		)
		(fill yes
			(thermal_gap 0.5)
			(thermal_bridge_width 0.5)
			(island_removal_mode 0)
		)
		(polygon
			(pts
				(arc
					(start 79.142082 -427.960536)
					(mid 79.1644 -428.014418)
					(end 79.218282 -428.036736)
				)
				(arc
					(start 80.158082 -428.036736)
					(mid 80.211964 -428.014418)
					(end 80.234282 -427.960536)
				)
				(arc
					(start 80.234282 -425.419012)
					(mid 80.211964 -425.36513)
					(end 80.158082 -425.342812)
				)
				(arc
					(start 79.218282 -425.342812)
					(mid 79.1644 -425.36513)
					(end 79.142082 -425.419012)
				)
			)
		)
	)
	(zone
		(layers "In1.Cu" "In3.Cu" "In8.Cu" "In9.Cu" "In10.Cu" "In12.Cu" "In13.Cu"
			"In14.Cu" "In16.Cu"
		)
		(hatch none 0.5)
		(connect_pads
			(clearance 0)
		)
		(min_thickness 0.25)
		(keepout
			(tracks not_allowed)
			(vias allowed)
			(pads allowed)
			(copperpour not_allowed)
			(footprints allowed)
		)
		(placement
			(enabled no)
			(sheetname "")
		)
		(fill yes
			(thermal_gap 0.5)
			(thermal_bridge_width 0.5)
			(island_removal_mode 0)
		)
		(polygon
			(pts
				(arc
					(start 70.1421 -427.960536)
					(mid 70.164418 -428.014418)
					(end 70.2183 -428.036736)
				)
				(arc
					(start 71.1581 -428.036736)
					(mid 71.211982 -428.014418)
					(end 71.2343 -427.960536)
				)
				(arc
					(start 71.2343 -425.419012)
					(mid 71.211982 -425.36513)
					(end 71.1581 -425.342812)
				)
				(arc
					(start 70.2183 -425.342812)
					(mid 70.164418 -425.36513)
					(end 70.1421 -425.419012)
				)
			)
		)
	)
	(zone
		(layers "In1.Cu" "In3.Cu" "In8.Cu" "In9.Cu" "In10.Cu" "In12.Cu" "In13.Cu"
			"In14.Cu" "In16.Cu"
		)
		(hatch none 0.5)
		(connect_pads
			(clearance 0)
		)
		(min_thickness 0.25)
		(keepout
			(tracks not_allowed)
			(vias allowed)
			(pads allowed)
			(copperpour not_allowed)
			(footprints allowed)
		)
		(placement
			(enabled no)
			(sheetname "")
		)
		(fill yes
			(thermal_gap 0.5)
			(thermal_bridge_width 0.5)
			(island_removal_mode 0)
		)
		(polygon
			(pts
				(arc
					(start 343.142062 -427.960536)
					(mid 343.16438 -428.014418)
					(end 343.218262 -428.036736)
				)
				(arc
					(start 344.158062 -428.036736)
					(mid 344.211944 -428.014418)
					(end 344.234262 -427.960536)
				)
				(arc
					(start 344.234262 -425.419012)
					(mid 344.211944 -425.36513)
					(end 344.158062 -425.342812)
				)
				(arc
					(start 343.218262 -425.342812)
					(mid 343.16438 -425.36513)
					(end 343.142062 -425.419012)
				)
			)
		)
	)
	(zone
		(layers "In1.Cu" "In3.Cu" "In8.Cu" "In9.Cu" "In10.Cu" "In12.Cu" "In13.Cu"
			"In14.Cu" "In16.Cu"
		)
		(hatch none 0.5)
		(connect_pads
			(clearance 0)
		)
		(min_thickness 0.25)
		(keepout
			(tracks not_allowed)
			(vias allowed)
			(pads allowed)
			(copperpour not_allowed)
			(footprints allowed)
		)
		(placement
			(enabled no)
			(sheetname "")
		)
		(fill yes
			(thermal_gap 0.5)
			(thermal_bridge_width 0.5)
			(island_removal_mode 0)
		)
		(polygon
			(pts
				(arc
					(start 87.142066 -427.960536)
					(mid 87.164384 -428.014418)
					(end 87.218266 -428.036736)
				)
				(arc
					(start 88.158066 -428.036736)
					(mid 88.211948 -428.014418)
					(end 88.234266 -427.960536)
				)
				(arc
					(start 88.234266 -425.419012)
					(mid 88.211948 -425.36513)
					(end 88.158066 -425.342812)
				)
				(arc
					(start 87.218266 -425.342812)
					(mid 87.164384 -425.36513)
					(end 87.142066 -425.419012)
				)
			)
		)
	)
	(zone
		(layers "In1.Cu" "In3.Cu" "In8.Cu" "In9.Cu" "In10.Cu" "In12.Cu" "In13.Cu"
			"In14.Cu" "In16.Cu"
		)
		(hatch none 0.5)
		(connect_pads
			(clearance 0)
		)
		(min_thickness 0.25)
		(keepout
			(tracks not_allowed)
			(vias allowed)
			(pads allowed)
			(copperpour not_allowed)
			(footprints allowed)
		)
		(placement
			(enabled no)
			(sheetname "")
		)
		(fill yes
			(thermal_gap 0.5)
			(thermal_bridge_width 0.5)
			(island_removal_mode 0)
		)
		(polygon
			(pts
				(arc
					(start 75.14209 -427.960536)
					(mid 75.164408 -428.014418)
					(end 75.21829 -428.036736)
				)
				(arc
					(start 76.15809 -428.036736)
					(mid 76.211972 -428.014418)
					(end 76.23429 -427.960536)
				)
				(arc
					(start 76.23429 -425.419012)
					(mid 76.211972 -425.36513)
					(end 76.15809 -425.342812)
				)
				(arc
					(start 75.21829 -425.342812)
					(mid 75.164408 -425.36513)
					(end 75.14209 -425.419012)
				)
			)
		)
	)
	(zone
		(layers "In1.Cu" "In3.Cu" "In8.Cu" "In9.Cu" "In10.Cu" "In12.Cu" "In13.Cu"
			"In14.Cu" "In16.Cu"
		)
		(hatch none 0.5)
		(connect_pads
			(clearance 0)
		)
		(min_thickness 0.25)
		(keepout
			(tracks not_allowed)
			(vias allowed)
			(pads allowed)
			(copperpour not_allowed)
			(footprints allowed)
		)
		(placement
			(enabled no)
			(sheetname "")
		)
		(fill yes
			(thermal_gap 0.5)
			(thermal_bridge_width 0.5)
			(island_removal_mode 0)
		)
		(polygon
			(pts
				(arc
					(start 318.142112 -427.960536)
					(mid 318.16443 -428.014418)
					(end 318.218312 -428.036736)
				)
				(arc
					(start 319.158112 -428.036736)
					(mid 319.211994 -428.014418)
					(end 319.234312 -427.960536)
				)
				(arc
					(start 319.234312 -425.419012)
					(mid 319.211994 -425.36513)
					(end 319.158112 -425.342812)
				)
				(arc
					(start 318.218312 -425.342812)
					(mid 318.16443 -425.36513)
					(end 318.142112 -425.419012)
				)
			)
		)
	)
	(zone
		(layers "In1.Cu" "In3.Cu" "In8.Cu" "In9.Cu" "In10.Cu" "In12.Cu" "In13.Cu"
			"In14.Cu" "In16.Cu"
		)
		(hatch none 0.5)
		(connect_pads
			(clearance 0)
		)
		(min_thickness 0.25)
		(keepout
			(tracks not_allowed)
			(vias allowed)
			(pads allowed)
			(copperpour not_allowed)
			(footprints allowed)
		)
		(placement
			(enabled no)
			(sheetname "")
		)
		(fill yes
			(thermal_gap 0.5)
			(thermal_bridge_width 0.5)
			(island_removal_mode 0)
		)
		(polygon
			(pts
				(arc
					(start 322.142104 -427.960536)
					(mid 322.164422 -428.014418)
					(end 322.218304 -428.036736)
				)
				(arc
					(start 323.158104 -428.036736)
					(mid 323.211986 -428.014418)
					(end 323.234304 -427.960536)
				)
				(arc
					(start 323.234304 -425.419012)
					(mid 323.211986 -425.36513)
					(end 323.158104 -425.342812)
				)
				(arc
					(start 322.218304 -425.342812)
					(mid 322.164422 -425.36513)
					(end 322.142104 -425.419012)
				)
			)
		)
	)
	(zone
		(layers "In1.Cu" "In3.Cu" "In8.Cu" "In9.Cu" "In10.Cu" "In12.Cu" "In14.Cu"
			"In16.Cu"
		)
		(hatch none 0.5)
		(connect_pads
			(clearance 0)
		)
		(min_thickness 0.25)
		(keepout
			(tracks not_allowed)
			(vias allowed)
			(pads allowed)
			(copperpour not_allowed)
			(footprints allowed)
		)
		(placement
			(enabled no)
			(sheetname "")
		)
		(fill yes
			(thermal_gap 0.5)
			(thermal_bridge_width 0.5)
			(island_removal_mode 0)
		)
		(polygon
			(pts
				(arc
					(start 410.242004 -431.560478)
					(mid 410.264322 -431.61436)
					(end 410.318204 -431.636678)
				)
				(arc
					(start 411.258004 -431.636678)
					(mid 411.311886 -431.61436)
					(end 411.334204 -431.560478)
				)
				(arc
					(start 411.334204 -429.018954)
					(mid 411.311886 -428.965072)
					(end 411.258004 -428.942754)
				)
				(arc
					(start 410.318204 -428.942754)
					(mid 410.264322 -428.965072)
					(end 410.242004 -429.018954)
				)
			)
		)
	)
	(zone
		(layers "In1.Cu" "In3.Cu" "In8.Cu" "In9.Cu" "In10.Cu" "In12.Cu" "In14.Cu"
			"In16.Cu"
		)
		(hatch none 0.5)
		(connect_pads
			(clearance 0)
		)
		(min_thickness 0.25)
		(keepout
			(tracks not_allowed)
			(vias allowed)
			(pads allowed)
			(copperpour not_allowed)
			(footprints allowed)
		)
		(placement
			(enabled no)
			(sheetname "")
		)
		(fill yes
			(thermal_gap 0.5)
			(thermal_bridge_width 0.5)
			(island_removal_mode 0)
		)
		(polygon
			(pts
				(arc
					(start 408.242008 -432.560476)
					(mid 408.264326 -432.614358)
					(end 408.318208 -432.636676)
				)
				(arc
					(start 409.258008 -432.636676)
					(mid 409.31189 -432.614358)
					(end 409.334208 -432.560476)
				)
				(arc
					(start 409.334208 -430.018952)
					(mid 409.31189 -429.96507)
					(end 409.258008 -429.942752)
				)
				(arc
					(start 408.318208 -429.942752)
					(mid 408.264326 -429.96507)
					(end 408.242008 -430.018952)
				)
			)
		)
	)
	(zone
		(layers "In1.Cu" "In3.Cu" "In8.Cu" "In9.Cu" "In10.Cu" "In12.Cu" "In14.Cu"
			"In16.Cu"
		)
		(hatch none 0.5)
		(connect_pads
			(clearance 0)
		)
		(min_thickness 0.25)
		(keepout
			(tracks not_allowed)
			(vias allowed)
			(pads allowed)
			(copperpour not_allowed)
			(footprints allowed)
		)
		(placement
			(enabled no)
			(sheetname "")
		)
		(fill yes
			(thermal_gap 0.5)
			(thermal_bridge_width 0.5)
			(island_removal_mode 0)
		)
		(polygon
			(pts
				(arc
					(start 154.242008 -431.560478)
					(mid 154.264326 -431.61436)
					(end 154.318208 -431.636678)
				)
				(arc
					(start 155.258008 -431.636678)
					(mid 155.31189 -431.61436)
					(end 155.334208 -431.560478)
				)
				(arc
					(start 155.334208 -429.018954)
					(mid 155.31189 -428.965072)
					(end 155.258008 -428.942754)
				)
				(arc
					(start 154.318208 -428.942754)
					(mid 154.264326 -428.965072)
					(end 154.242008 -429.018954)
				)
			)
		)
	)
	(zone
		(layers "In1.Cu" "In3.Cu" "In8.Cu" "In9.Cu" "In10.Cu" "In12.Cu" "In14.Cu"
			"In16.Cu"
		)
		(hatch none 0.5)
		(connect_pads
			(clearance 0)
		)
		(min_thickness 0.25)
		(keepout
			(tracks not_allowed)
			(vias allowed)
			(pads allowed)
			(copperpour not_allowed)
			(footprints allowed)
		)
		(placement
			(enabled no)
			(sheetname "")
		)
		(fill yes
			(thermal_gap 0.5)
			(thermal_bridge_width 0.5)
			(island_removal_mode 0)
		)
		(polygon
			(pts
				(arc
					(start 125.242066 -431.560478)
					(mid 125.264384 -431.61436)
					(end 125.318266 -431.636678)
				)
				(arc
					(start 126.258066 -431.636678)
					(mid 126.311948 -431.61436)
					(end 126.334266 -431.560478)
				)
				(arc
					(start 126.334266 -429.018954)
					(mid 126.311948 -428.965072)
					(end 126.258066 -428.942754)
				)
				(arc
					(start 125.318266 -428.942754)
					(mid 125.264384 -428.965072)
					(end 125.242066 -429.018954)
				)
			)
		)
	)
	(zone
		(layers "In1.Cu" "In3.Cu" "In8.Cu" "In9.Cu" "In10.Cu" "In12.Cu" "In14.Cu"
			"In16.Cu"
		)
		(hatch none 0.5)
		(connect_pads
			(clearance 0)
		)
		(min_thickness 0.25)
		(keepout
			(tracks not_allowed)
			(vias allowed)
			(pads allowed)
			(copperpour not_allowed)
			(footprints allowed)
		)
		(placement
			(enabled no)
			(sheetname "")
		)
		(fill yes
			(thermal_gap 0.5)
			(thermal_bridge_width 0.5)
			(island_removal_mode 0)
		)
		(polygon
			(pts
				(arc
					(start 131.242054 -432.560476)
					(mid 131.264372 -432.614358)
					(end 131.318254 -432.636676)
				)
				(arc
					(start 132.258054 -432.636676)
					(mid 132.311936 -432.614358)
					(end 132.334254 -432.560476)
				)
				(arc
					(start 132.334254 -430.018952)
					(mid 132.311936 -429.96507)
					(end 132.258054 -429.942752)
				)
				(arc
					(start 131.318254 -429.942752)
					(mid 131.264372 -429.96507)
					(end 131.242054 -430.018952)
				)
			)
		)
	)
	(zone
		(layers "In1.Cu" "In3.Cu" "In8.Cu" "In9.Cu" "In10.Cu" "In12.Cu" "In14.Cu"
			"In16.Cu"
		)
		(hatch none 0.5)
		(connect_pads
			(clearance 0)
		)
		(min_thickness 0.25)
		(keepout
			(tracks not_allowed)
			(vias allowed)
			(pads allowed)
			(copperpour not_allowed)
			(footprints allowed)
		)
		(placement
			(enabled no)
			(sheetname "")
		)
		(fill yes
			(thermal_gap 0.5)
			(thermal_bridge_width 0.5)
			(island_removal_mode 0)
		)
		(polygon
			(pts
				(arc
					(start 406.242012 -431.560478)
					(mid 406.26433 -431.61436)
					(end 406.318212 -431.636678)
				)
				(arc
					(start 407.258012 -431.636678)
					(mid 407.311894 -431.61436)
					(end 407.334212 -431.560478)
				)
				(arc
					(start 407.334212 -429.018954)
					(mid 407.311894 -428.965072)
					(end 407.258012 -428.942754)
				)
				(arc
					(start 406.318212 -428.942754)
					(mid 406.26433 -428.965072)
					(end 406.242012 -429.018954)
				)
			)
		)
	)
	(zone
		(layers "In1.Cu" "In3.Cu" "In8.Cu" "In9.Cu" "In10.Cu" "In12.Cu" "In14.Cu"
			"In16.Cu"
		)
		(hatch none 0.5)
		(connect_pads
			(clearance 0)
		)
		(min_thickness 0.25)
		(keepout
			(tracks not_allowed)
			(vias allowed)
			(pads allowed)
			(copperpour not_allowed)
			(footprints allowed)
		)
		(placement
			(enabled no)
			(sheetname "")
		)
		(fill yes
			(thermal_gap 0.5)
			(thermal_bridge_width 0.5)
			(island_removal_mode 0)
		)
		(polygon
			(pts
				(arc
					(start 148.24202 -432.560476)
					(mid 148.264338 -432.614358)
					(end 148.31822 -432.636676)
				)
				(arc
					(start 149.25802 -432.636676)
					(mid 149.311902 -432.614358)
					(end 149.33422 -432.560476)
				)
				(arc
					(start 149.33422 -430.018952)
					(mid 149.311902 -429.96507)
					(end 149.25802 -429.942752)
				)
				(arc
					(start 148.31822 -429.942752)
					(mid 148.264338 -429.96507)
					(end 148.24202 -430.018952)
				)
			)
		)
	)
	(zone
		(layers "In1.Cu" "In3.Cu" "In8.Cu" "In9.Cu" "In10.Cu" "In12.Cu" "In14.Cu"
			"In16.Cu"
		)
		(hatch none 0.5)
		(connect_pads
			(clearance 0)
		)
		(min_thickness 0.25)
		(keepout
			(tracks not_allowed)
			(vias allowed)
			(pads allowed)
			(copperpour not_allowed)
			(footprints allowed)
		)
		(placement
			(enabled no)
			(sheetname "")
		)
		(fill yes
			(thermal_gap 0.5)
			(thermal_bridge_width 0.5)
			(island_removal_mode 0)
		)
		(polygon
			(pts
				(arc
					(start 127.242062 -432.560476)
					(mid 127.26438 -432.614358)
					(end 127.318262 -432.636676)
				)
				(arc
					(start 128.258062 -432.636676)
					(mid 128.311944 -432.614358)
					(end 128.334262 -432.560476)
				)
				(arc
					(start 128.334262 -430.018952)
					(mid 128.311944 -429.96507)
					(end 128.258062 -429.942752)
				)
				(arc
					(start 127.318262 -429.942752)
					(mid 127.26438 -429.96507)
					(end 127.242062 -430.018952)
				)
			)
		)
	)
	(zone
		(layers "In1.Cu" "In3.Cu" "In8.Cu" "In9.Cu" "In10.Cu" "In12.Cu" "In14.Cu"
			"In16.Cu"
		)
		(hatch none 0.5)
		(connect_pads
			(clearance 0)
		)
		(min_thickness 0.25)
		(keepout
			(tracks not_allowed)
			(vias allowed)
			(pads allowed)
			(copperpour not_allowed)
			(footprints allowed)
		)
		(placement
			(enabled no)
			(sheetname "")
		)
		(fill yes
			(thermal_gap 0.5)
			(thermal_bridge_width 0.5)
			(island_removal_mode 0)
		)
		(polygon
			(pts
				(arc
					(start 398.242028 -431.560478)
					(mid 398.264346 -431.61436)
					(end 398.318228 -431.636678)
				)
				(arc
					(start 399.258028 -431.636678)
					(mid 399.31191 -431.61436)
					(end 399.334228 -431.560478)
				)
				(arc
					(start 399.334228 -429.018954)
					(mid 399.31191 -428.965072)
					(end 399.258028 -428.942754)
				)
				(arc
					(start 398.318228 -428.942754)
					(mid 398.264346 -428.965072)
					(end 398.242028 -429.018954)
				)
			)
		)
	)
	(zone
		(layers "In1.Cu" "In3.Cu" "In8.Cu" "In9.Cu" "In10.Cu" "In12.Cu" "In14.Cu"
			"In16.Cu"
		)
		(hatch none 0.5)
		(connect_pads
			(clearance 0)
		)
		(min_thickness 0.25)
		(keepout
			(tracks not_allowed)
			(vias allowed)
			(pads allowed)
			(copperpour not_allowed)
			(footprints allowed)
		)
		(placement
			(enabled no)
			(sheetname "")
		)
		(fill yes
			(thermal_gap 0.5)
			(thermal_bridge_width 0.5)
			(island_removal_mode 0)
		)
		(polygon
			(pts
				(arc
					(start 412.242 -432.560476)
					(mid 412.264318 -432.614358)
					(end 412.3182 -432.636676)
				)
				(arc
					(start 413.258 -432.636676)
					(mid 413.311882 -432.614358)
					(end 413.3342 -432.560476)
				)
				(arc
					(start 413.3342 -430.018952)
					(mid 413.311882 -429.96507)
					(end 413.258 -429.942752)
				)
				(arc
					(start 412.3182 -429.942752)
					(mid 412.264318 -429.96507)
					(end 412.242 -430.018952)
				)
			)
		)
	)
	(zone
		(layers "In1.Cu" "In3.Cu" "In8.Cu" "In9.Cu" "In10.Cu" "In12.Cu" "In14.Cu"
			"In16.Cu"
		)
		(hatch none 0.5)
		(connect_pads
			(clearance 0)
		)
		(min_thickness 0.25)
		(keepout
			(tracks not_allowed)
			(vias allowed)
			(pads allowed)
			(copperpour not_allowed)
			(footprints allowed)
		)
		(placement
			(enabled no)
			(sheetname "")
		)
		(fill yes
			(thermal_gap 0.5)
			(thermal_bridge_width 0.5)
			(island_removal_mode 0)
		)
		(polygon
			(pts
				(arc
					(start 144.242028 -432.560476)
					(mid 144.264346 -432.614358)
					(end 144.318228 -432.636676)
				)
				(arc
					(start 145.258028 -432.636676)
					(mid 145.31191 -432.614358)
					(end 145.334228 -432.560476)
				)
				(arc
					(start 145.334228 -430.018952)
					(mid 145.31191 -429.96507)
					(end 145.258028 -429.942752)
				)
				(arc
					(start 144.318228 -429.942752)
					(mid 144.264346 -429.96507)
					(end 144.242028 -430.018952)
				)
			)
		)
	)
	(zone
		(layers "In1.Cu" "In3.Cu" "In8.Cu" "In9.Cu" "In10.Cu" "In12.Cu" "In14.Cu"
			"In16.Cu"
		)
		(hatch none 0.5)
		(connect_pads
			(clearance 0)
		)
		(min_thickness 0.25)
		(keepout
			(tracks not_allowed)
			(vias allowed)
			(pads allowed)
			(copperpour not_allowed)
			(footprints allowed)
		)
		(placement
			(enabled no)
			(sheetname "")
		)
		(fill yes
			(thermal_gap 0.5)
			(thermal_bridge_width 0.5)
			(island_removal_mode 0)
		)
		(polygon
			(pts
				(arc
					(start 150.242016 -431.560478)
					(mid 150.264334 -431.61436)
					(end 150.318216 -431.636678)
				)
				(arc
					(start 151.258016 -431.636678)
					(mid 151.311898 -431.61436)
					(end 151.334216 -431.560478)
				)
				(arc
					(start 151.334216 -429.018954)
					(mid 151.311898 -428.965072)
					(end 151.258016 -428.942754)
				)
				(arc
					(start 150.318216 -428.942754)
					(mid 150.264334 -428.965072)
					(end 150.242016 -429.018954)
				)
			)
		)
	)
	(zone
		(layers "In1.Cu" "In3.Cu" "In8.Cu" "In9.Cu" "In10.Cu" "In12.Cu" "In14.Cu"
			"In16.Cu"
		)
		(hatch none 0.5)
		(connect_pads
			(clearance 0)
		)
		(min_thickness 0.25)
		(keepout
			(tracks not_allowed)
			(vias allowed)
			(pads allowed)
			(copperpour not_allowed)
			(footprints allowed)
		)
		(placement
			(enabled no)
			(sheetname "")
		)
		(fill yes
			(thermal_gap 0.5)
			(thermal_bridge_width 0.5)
			(island_removal_mode 0)
		)
		(polygon
			(pts
				(arc
					(start 389.242046 -431.560478)
					(mid 389.264364 -431.61436)
					(end 389.318246 -431.636678)
				)
				(arc
					(start 390.258046 -431.636678)
					(mid 390.311928 -431.61436)
					(end 390.334246 -431.560478)
				)
				(arc
					(start 390.334246 -429.018954)
					(mid 390.311928 -428.965072)
					(end 390.258046 -428.942754)
				)
				(arc
					(start 389.318246 -428.942754)
					(mid 389.264364 -428.965072)
					(end 389.242046 -429.018954)
				)
			)
		)
	)
	(zone
		(layers "In1.Cu" "In3.Cu" "In8.Cu" "In9.Cu" "In10.Cu" "In12.Cu" "In14.Cu"
			"In16.Cu"
		)
		(hatch none 0.5)
		(connect_pads
			(clearance 0)
		)
		(min_thickness 0.25)
		(keepout
			(tracks not_allowed)
			(vias allowed)
			(pads allowed)
			(copperpour not_allowed)
			(footprints allowed)
		)
		(placement
			(enabled no)
			(sheetname "")
		)
		(fill yes
			(thermal_gap 0.5)
			(thermal_bridge_width 0.5)
			(island_removal_mode 0)
		)
		(polygon
			(pts
				(arc
					(start 383.242058 -432.560476)
					(mid 383.264376 -432.614358)
					(end 383.318258 -432.636676)
				)
				(arc
					(start 384.258058 -432.636676)
					(mid 384.31194 -432.614358)
					(end 384.334258 -432.560476)
				)
				(arc
					(start 384.334258 -430.018952)
					(mid 384.31194 -429.96507)
					(end 384.258058 -429.942752)
				)
				(arc
					(start 383.318258 -429.942752)
					(mid 383.264376 -429.96507)
					(end 383.242058 -430.018952)
				)
			)
		)
	)
	(zone
		(layers "In1.Cu" "In3.Cu" "In8.Cu" "In9.Cu" "In10.Cu" "In12.Cu" "In14.Cu"
			"In16.Cu"
		)
		(hatch none 0.5)
		(connect_pads
			(clearance 0)
		)
		(min_thickness 0.25)
		(keepout
			(tracks not_allowed)
			(vias allowed)
			(pads allowed)
			(copperpour not_allowed)
			(footprints allowed)
		)
		(placement
			(enabled no)
			(sheetname "")
		)
		(fill yes
			(thermal_gap 0.5)
			(thermal_bridge_width 0.5)
			(island_removal_mode 0)
		)
		(polygon
			(pts
				(arc
					(start 387.24205 -432.560476)
					(mid 387.264368 -432.614358)
					(end 387.31825 -432.636676)
				)
				(arc
					(start 388.25805 -432.636676)
					(mid 388.311932 -432.614358)
					(end 388.33425 -432.560476)
				)
				(arc
					(start 388.33425 -430.018952)
					(mid 388.311932 -429.96507)
					(end 388.25805 -429.942752)
				)
				(arc
					(start 387.31825 -429.942752)
					(mid 387.264368 -429.96507)
					(end 387.24205 -430.018952)
				)
			)
		)
	)
	(zone
		(layers "In1.Cu" "In3.Cu" "In8.Cu" "In9.Cu" "In10.Cu" "In12.Cu" "In14.Cu"
			"In16.Cu"
		)
		(hatch none 0.5)
		(connect_pads
			(clearance 0)
		)
		(min_thickness 0.25)
		(keepout
			(tracks not_allowed)
			(vias allowed)
			(pads allowed)
			(copperpour not_allowed)
			(footprints allowed)
		)
		(placement
			(enabled no)
			(sheetname "")
		)
		(fill yes
			(thermal_gap 0.5)
			(thermal_bridge_width 0.5)
			(island_removal_mode 0)
		)
		(polygon
			(pts
				(arc
					(start 404.242016 -432.560476)
					(mid 404.264334 -432.614358)
					(end 404.318216 -432.636676)
				)
				(arc
					(start 405.258016 -432.636676)
					(mid 405.311898 -432.614358)
					(end 405.334216 -432.560476)
				)
				(arc
					(start 405.334216 -430.018952)
					(mid 405.311898 -429.96507)
					(end 405.258016 -429.942752)
				)
				(arc
					(start 404.318216 -429.942752)
					(mid 404.264334 -429.96507)
					(end 404.242016 -430.018952)
				)
			)
		)
	)
	(zone
		(layers "In1.Cu" "In3.Cu" "In8.Cu" "In9.Cu" "In10.Cu" "In12.Cu" "In14.Cu"
			"In16.Cu"
		)
		(hatch none 0.5)
		(connect_pads
			(clearance 0)
		)
		(min_thickness 0.25)
		(keepout
			(tracks not_allowed)
			(vias allowed)
			(pads allowed)
			(copperpour not_allowed)
			(footprints allowed)
		)
		(placement
			(enabled no)
			(sheetname "")
		)
		(fill yes
			(thermal_gap 0.5)
			(thermal_bridge_width 0.5)
			(island_removal_mode 0)
		)
		(polygon
			(pts
				(arc
					(start 146.242024 -431.560478)
					(mid 146.264342 -431.61436)
					(end 146.318224 -431.636678)
				)
				(arc
					(start 147.258024 -431.636678)
					(mid 147.311906 -431.61436)
					(end 147.334224 -431.560478)
				)
				(arc
					(start 147.334224 -429.018954)
					(mid 147.311906 -428.965072)
					(end 147.258024 -428.942754)
				)
				(arc
					(start 146.318224 -428.942754)
					(mid 146.264342 -428.965072)
					(end 146.242024 -429.018954)
				)
			)
		)
	)
	(zone
		(layers "In1.Cu" "In3.Cu" "In8.Cu" "In9.Cu" "In10.Cu" "In12.Cu" "In14.Cu"
			"In16.Cu"
		)
		(hatch none 0.5)
		(connect_pads
			(clearance 0)
		)
		(min_thickness 0.25)
		(keepout
			(tracks not_allowed)
			(vias allowed)
			(pads allowed)
			(copperpour not_allowed)
			(footprints allowed)
		)
		(placement
			(enabled no)
			(sheetname "")
		)
		(fill yes
			(thermal_gap 0.5)
			(thermal_bridge_width 0.5)
			(island_removal_mode 0)
		)
		(polygon
			(pts
				(arc
					(start 152.242012 -432.560476)
					(mid 152.26433 -432.614358)
					(end 152.318212 -432.636676)
				)
				(arc
					(start 153.258012 -432.636676)
					(mid 153.311894 -432.614358)
					(end 153.334212 -432.560476)
				)
				(arc
					(start 153.334212 -430.018952)
					(mid 153.311894 -429.96507)
					(end 153.258012 -429.942752)
				)
				(arc
					(start 152.318212 -429.942752)
					(mid 152.26433 -429.96507)
					(end 152.242012 -430.018952)
				)
			)
		)
	)
	(zone
		(layers "In1.Cu" "In3.Cu" "In8.Cu" "In9.Cu" "In10.Cu" "In12.Cu" "In14.Cu"
			"In16.Cu"
		)
		(hatch none 0.5)
		(connect_pads
			(clearance 0)
		)
		(min_thickness 0.25)
		(keepout
			(tracks not_allowed)
			(vias allowed)
			(pads allowed)
			(copperpour not_allowed)
			(footprints allowed)
		)
		(placement
			(enabled no)
			(sheetname "")
		)
		(fill yes
			(thermal_gap 0.5)
			(thermal_bridge_width 0.5)
			(island_removal_mode 0)
		)
		(polygon
			(pts
				(arc
					(start 135.242046 -432.560476)
					(mid 135.264364 -432.614358)
					(end 135.318246 -432.636676)
				)
				(arc
					(start 136.258046 -432.636676)
					(mid 136.311928 -432.614358)
					(end 136.334246 -432.560476)
				)
				(arc
					(start 136.334246 -430.018952)
					(mid 136.311928 -429.96507)
					(end 136.258046 -429.942752)
				)
				(arc
					(start 135.318246 -429.942752)
					(mid 135.264364 -429.96507)
					(end 135.242046 -430.018952)
				)
			)
		)
	)
	(zone
		(layers "In1.Cu" "In3.Cu" "In8.Cu" "In9.Cu" "In10.Cu" "In12.Cu" "In14.Cu"
			"In16.Cu"
		)
		(hatch none 0.5)
		(connect_pads
			(clearance 0)
		)
		(min_thickness 0.25)
		(keepout
			(tracks not_allowed)
			(vias allowed)
			(pads allowed)
			(copperpour not_allowed)
			(footprints allowed)
		)
		(placement
			(enabled no)
			(sheetname "")
		)
		(fill yes
			(thermal_gap 0.5)
			(thermal_bridge_width 0.5)
			(island_removal_mode 0)
		)
		(polygon
			(pts
				(arc
					(start 137.242042 -431.560478)
					(mid 137.26436 -431.61436)
					(end 137.318242 -431.636678)
				)
				(arc
					(start 138.258042 -431.636678)
					(mid 138.311924 -431.61436)
					(end 138.334242 -431.560478)
				)
				(arc
					(start 138.334242 -429.018954)
					(mid 138.311924 -428.965072)
					(end 138.258042 -428.942754)
				)
				(arc
					(start 137.318242 -428.942754)
					(mid 137.26436 -428.965072)
					(end 137.242042 -429.018954)
				)
			)
		)
	)
	(zone
		(layers "In1.Cu" "In3.Cu" "In8.Cu" "In9.Cu" "In10.Cu" "In12.Cu" "In14.Cu"
			"In16.Cu"
		)
		(hatch none 0.5)
		(connect_pads
			(clearance 0)
		)
		(min_thickness 0.25)
		(keepout
			(tracks not_allowed)
			(vias allowed)
			(pads allowed)
			(copperpour not_allowed)
			(footprints allowed)
		)
		(placement
			(enabled no)
			(sheetname "")
		)
		(fill yes
			(thermal_gap 0.5)
			(thermal_bridge_width 0.5)
			(island_removal_mode 0)
		)
		(polygon
			(pts
				(arc
					(start 400.242024 -432.560476)
					(mid 400.264342 -432.614358)
					(end 400.318224 -432.636676)
				)
				(arc
					(start 401.258024 -432.636676)
					(mid 401.311906 -432.614358)
					(end 401.334224 -432.560476)
				)
				(arc
					(start 401.334224 -430.018952)
					(mid 401.311906 -429.96507)
					(end 401.258024 -429.942752)
				)
				(arc
					(start 400.318224 -429.942752)
					(mid 400.264342 -429.96507)
					(end 400.242024 -430.018952)
				)
			)
		)
	)
	(zone
		(layers "In1.Cu" "In3.Cu" "In8.Cu" "In9.Cu" "In10.Cu" "In12.Cu" "In14.Cu"
			"In16.Cu"
		)
		(hatch none 0.5)
		(connect_pads
			(clearance 0)
		)
		(min_thickness 0.25)
		(keepout
			(tracks not_allowed)
			(vias allowed)
			(pads allowed)
			(copperpour not_allowed)
			(footprints allowed)
		)
		(placement
			(enabled no)
			(sheetname "")
		)
		(fill yes
			(thermal_gap 0.5)
			(thermal_bridge_width 0.5)
			(island_removal_mode 0)
		)
		(polygon
			(pts
				(arc
					(start 129.242058 -431.560478)
					(mid 129.264376 -431.61436)
					(end 129.318258 -431.636678)
				)
				(arc
					(start 130.258058 -431.636678)
					(mid 130.31194 -431.61436)
					(end 130.334258 -431.560478)
				)
				(arc
					(start 130.334258 -429.018954)
					(mid 130.31194 -428.965072)
					(end 130.258058 -428.942754)
				)
				(arc
					(start 129.318258 -428.942754)
					(mid 129.264376 -428.965072)
					(end 129.242058 -429.018954)
				)
			)
		)
	)
	(zone
		(layers "In1.Cu" "In3.Cu" "In8.Cu" "In9.Cu" "In10.Cu" "In12.Cu" "In14.Cu"
			"In16.Cu"
		)
		(hatch none 0.5)
		(connect_pads
			(clearance 0)
		)
		(min_thickness 0.25)
		(keepout
			(tracks not_allowed)
			(vias allowed)
			(pads allowed)
			(copperpour not_allowed)
			(footprints allowed)
		)
		(placement
			(enabled no)
			(sheetname "")
		)
		(fill yes
			(thermal_gap 0.5)
			(thermal_bridge_width 0.5)
			(island_removal_mode 0)
		)
		(polygon
			(pts
				(arc
					(start 391.242042 -432.560476)
					(mid 391.26436 -432.614358)
					(end 391.318242 -432.636676)
				)
				(arc
					(start 392.258042 -432.636676)
					(mid 392.311924 -432.614358)
					(end 392.334242 -432.560476)
				)
				(arc
					(start 392.334242 -430.018952)
					(mid 392.311924 -429.96507)
					(end 392.258042 -429.942752)
				)
				(arc
					(start 391.318242 -429.942752)
					(mid 391.26436 -429.96507)
					(end 391.242042 -430.018952)
				)
			)
		)
	)
	(zone
		(layers "In1.Cu" "In3.Cu" "In8.Cu" "In9.Cu" "In10.Cu" "In12.Cu" "In14.Cu"
			"In16.Cu"
		)
		(hatch none 0.5)
		(connect_pads
			(clearance 0)
		)
		(min_thickness 0.25)
		(keepout
			(tracks not_allowed)
			(vias allowed)
			(pads allowed)
			(copperpour not_allowed)
			(footprints allowed)
		)
		(placement
			(enabled no)
			(sheetname "")
		)
		(fill yes
			(thermal_gap 0.5)
			(thermal_bridge_width 0.5)
			(island_removal_mode 0)
		)
		(polygon
			(pts
				(arc
					(start 393.242038 -431.560478)
					(mid 393.264356 -431.61436)
					(end 393.318238 -431.636678)
				)
				(arc
					(start 394.258038 -431.636678)
					(mid 394.31192 -431.61436)
					(end 394.334238 -431.560478)
				)
				(arc
					(start 394.334238 -429.018954)
					(mid 394.31192 -428.965072)
					(end 394.258038 -428.942754)
				)
				(arc
					(start 393.318238 -428.942754)
					(mid 393.264356 -428.965072)
					(end 393.242038 -429.018954)
				)
			)
		)
	)
	(zone
		(layers "In1.Cu" "In3.Cu" "In8.Cu" "In9.Cu" "In10.Cu" "In12.Cu" "In14.Cu"
			"In16.Cu"
		)
		(hatch none 0.5)
		(connect_pads
			(clearance 0)
		)
		(min_thickness 0.25)
		(keepout
			(tracks not_allowed)
			(vias allowed)
			(pads allowed)
			(copperpour not_allowed)
			(footprints allowed)
		)
		(placement
			(enabled no)
			(sheetname "")
		)
		(fill yes
			(thermal_gap 0.5)
			(thermal_bridge_width 0.5)
			(island_removal_mode 0)
		)
		(polygon
			(pts
				(arc
					(start 402.24202 -431.560478)
					(mid 402.264338 -431.61436)
					(end 402.31822 -431.636678)
				)
				(arc
					(start 403.25802 -431.636678)
					(mid 403.311902 -431.61436)
					(end 403.33422 -431.560478)
				)
				(arc
					(start 403.33422 -429.018954)
					(mid 403.311902 -428.965072)
					(end 403.25802 -428.942754)
				)
				(arc
					(start 402.31822 -428.942754)
					(mid 402.264338 -428.965072)
					(end 402.24202 -429.018954)
				)
			)
		)
	)
	(zone
		(layers "In1.Cu" "In3.Cu" "In8.Cu" "In9.Cu" "In10.Cu" "In12.Cu" "In14.Cu"
			"In16.Cu"
		)
		(hatch none 0.5)
		(connect_pads
			(clearance 0)
		)
		(min_thickness 0.25)
		(keepout
			(tracks not_allowed)
			(vias allowed)
			(pads allowed)
			(copperpour not_allowed)
			(footprints allowed)
		)
		(placement
			(enabled no)
			(sheetname "")
		)
		(fill yes
			(thermal_gap 0.5)
			(thermal_bridge_width 0.5)
			(island_removal_mode 0)
		)
		(polygon
			(pts
				(arc
					(start 142.242032 -431.560478)
					(mid 142.26435 -431.61436)
					(end 142.318232 -431.636678)
				)
				(arc
					(start 143.258032 -431.636678)
					(mid 143.311914 -431.61436)
					(end 143.334232 -431.560478)
				)
				(arc
					(start 143.334232 -429.018954)
					(mid 143.311914 -428.965072)
					(end 143.258032 -428.942754)
				)
				(arc
					(start 142.318232 -428.942754)
					(mid 142.26435 -428.965072)
					(end 142.242032 -429.018954)
				)
			)
		)
	)
	(zone
		(layers "In1.Cu" "In3.Cu" "In8.Cu" "In9.Cu" "In10.Cu" "In12.Cu" "In14.Cu"
			"In16.Cu"
		)
		(hatch none 0.5)
		(connect_pads
			(clearance 0)
		)
		(min_thickness 0.25)
		(keepout
			(tracks not_allowed)
			(vias allowed)
			(pads allowed)
			(copperpour not_allowed)
			(footprints allowed)
		)
		(placement
			(enabled no)
			(sheetname "")
		)
		(fill yes
			(thermal_gap 0.5)
			(thermal_bridge_width 0.5)
			(island_removal_mode 0)
		)
		(polygon
			(pts
				(arc
					(start 395.242034 -432.560476)
					(mid 395.264352 -432.614358)
					(end 395.318234 -432.636676)
				)
				(arc
					(start 396.258034 -432.636676)
					(mid 396.311916 -432.614358)
					(end 396.334234 -432.560476)
				)
				(arc
					(start 396.334234 -430.018952)
					(mid 396.311916 -429.96507)
					(end 396.258034 -429.942752)
				)
				(arc
					(start 395.318234 -429.942752)
					(mid 395.264352 -429.96507)
					(end 395.242034 -430.018952)
				)
			)
		)
	)
	(zone
		(layers "In1.Cu" "In3.Cu" "In8.Cu" "In9.Cu" "In10.Cu" "In12.Cu" "In14.Cu"
			"In16.Cu"
		)
		(hatch none 0.5)
		(connect_pads
			(clearance 0)
		)
		(min_thickness 0.25)
		(keepout
			(tracks not_allowed)
			(vias allowed)
			(pads allowed)
			(copperpour not_allowed)
			(footprints allowed)
		)
		(placement
			(enabled no)
			(sheetname "")
		)
		(fill yes
			(thermal_gap 0.5)
			(thermal_bridge_width 0.5)
			(island_removal_mode 0)
		)
		(polygon
			(pts
				(arc
					(start 381.242062 -431.560478)
					(mid 381.26438 -431.61436)
					(end 381.318262 -431.636678)
				)
				(arc
					(start 382.258062 -431.636678)
					(mid 382.311944 -431.61436)
					(end 382.334262 -431.560478)
				)
				(arc
					(start 382.334262 -429.018954)
					(mid 382.311944 -428.965072)
					(end 382.258062 -428.942754)
				)
				(arc
					(start 381.318262 -428.942754)
					(mid 381.26438 -428.965072)
					(end 381.242062 -429.018954)
				)
			)
		)
	)
	(zone
		(layers "In1.Cu" "In3.Cu" "In8.Cu" "In9.Cu" "In10.Cu" "In12.Cu" "In14.Cu"
			"In16.Cu"
		)
		(hatch none 0.5)
		(connect_pads
			(clearance 0)
		)
		(min_thickness 0.25)
		(keepout
			(tracks not_allowed)
			(vias allowed)
			(pads allowed)
			(copperpour not_allowed)
			(footprints allowed)
		)
		(placement
			(enabled no)
			(sheetname "")
		)
		(fill yes
			(thermal_gap 0.5)
			(thermal_bridge_width 0.5)
			(island_removal_mode 0)
		)
		(polygon
			(pts
				(arc
					(start 156.242004 -432.560476)
					(mid 156.264322 -432.614358)
					(end 156.318204 -432.636676)
				)
				(arc
					(start 157.258004 -432.636676)
					(mid 157.311886 -432.614358)
					(end 157.334204 -432.560476)
				)
				(arc
					(start 157.334204 -430.018952)
					(mid 157.311886 -429.96507)
					(end 157.258004 -429.942752)
				)
				(arc
					(start 156.318204 -429.942752)
					(mid 156.264322 -429.96507)
					(end 156.242004 -430.018952)
				)
			)
		)
	)
	(zone
		(layers "In1.Cu" "In3.Cu" "In8.Cu" "In9.Cu" "In10.Cu" "In12.Cu" "In14.Cu"
			"In16.Cu"
		)
		(hatch none 0.5)
		(connect_pads
			(clearance 0)
		)
		(min_thickness 0.25)
		(keepout
			(tracks not_allowed)
			(vias allowed)
			(pads allowed)
			(copperpour not_allowed)
			(footprints allowed)
		)
		(placement
			(enabled no)
			(sheetname "")
		)
		(fill yes
			(thermal_gap 0.5)
			(thermal_bridge_width 0.5)
			(island_removal_mode 0)
		)
		(polygon
			(pts
				(arc
					(start 133.24205 -431.560478)
					(mid 133.264368 -431.61436)
					(end 133.31825 -431.636678)
				)
				(arc
					(start 134.25805 -431.636678)
					(mid 134.311932 -431.61436)
					(end 134.33425 -431.560478)
				)
				(arc
					(start 134.33425 -429.018954)
					(mid 134.311932 -428.965072)
					(end 134.25805 -428.942754)
				)
				(arc
					(start 133.31825 -428.942754)
					(mid 133.264368 -428.965072)
					(end 133.24205 -429.018954)
				)
			)
		)
	)
	(zone
		(layers "In1.Cu" "In3.Cu" "In8.Cu" "In9.Cu" "In10.Cu" "In12.Cu" "In14.Cu"
			"In16.Cu"
		)
		(hatch none 0.5)
		(connect_pads
			(clearance 0)
		)
		(min_thickness 0.25)
		(keepout
			(tracks not_allowed)
			(vias allowed)
			(pads allowed)
			(copperpour not_allowed)
			(footprints allowed)
		)
		(placement
			(enabled no)
			(sheetname "")
		)
		(fill yes
			(thermal_gap 0.5)
			(thermal_bridge_width 0.5)
			(island_removal_mode 0)
		)
		(polygon
			(pts
				(arc
					(start 385.242054 -431.560478)
					(mid 385.264372 -431.61436)
					(end 385.318254 -431.636678)
				)
				(arc
					(start 386.258054 -431.636678)
					(mid 386.311936 -431.61436)
					(end 386.334254 -431.560478)
				)
				(arc
					(start 386.334254 -429.018954)
					(mid 386.311936 -428.965072)
					(end 386.258054 -428.942754)
				)
				(arc
					(start 385.318254 -428.942754)
					(mid 385.264372 -428.965072)
					(end 385.242054 -429.018954)
				)
			)
		)
	)
	(zone
		(layers "In1.Cu" "In3.Cu" "In8.Cu" "In9.Cu" "In10.Cu" "In12.Cu" "In14.Cu"
			"In16.Cu"
		)
		(hatch none 0.5)
		(connect_pads
			(clearance 0)
		)
		(min_thickness 0.25)
		(keepout
			(tracks not_allowed)
			(vias allowed)
			(pads allowed)
			(copperpour not_allowed)
			(footprints allowed)
		)
		(placement
			(enabled no)
			(sheetname "")
		)
		(fill yes
			(thermal_gap 0.5)
			(thermal_bridge_width 0.5)
			(island_removal_mode 0)
		)
		(polygon
			(pts
				(arc
					(start 139.242038 -432.560476)
					(mid 139.264356 -432.614358)
					(end 139.318238 -432.636676)
				)
				(arc
					(start 140.258038 -432.636676)
					(mid 140.31192 -432.614358)
					(end 140.334238 -432.560476)
				)
				(arc
					(start 140.334238 -430.018952)
					(mid 140.31192 -429.96507)
					(end 140.258038 -429.942752)
				)
				(arc
					(start 139.318238 -429.942752)
					(mid 139.264356 -429.96507)
					(end 139.242038 -430.018952)
				)
			)
		)
	)
	(zone
		(layers "In1.Cu" "In7.Cu" "In8.Cu" "In9.Cu" "In10.Cu" "In12.Cu" "In14.Cu"
			"In16.Cu"
		)
		(hatch none 0.5)
		(connect_pads
			(clearance 0)
		)
		(min_thickness 0.25)
		(keepout
			(tracks not_allowed)
			(vias allowed)
			(pads allowed)
			(copperpour not_allowed)
			(footprints allowed)
		)
		(placement
			(enabled no)
			(sheetname "")
		)
		(fill yes
			(thermal_gap 0.5)
			(thermal_bridge_width 0.5)
			(island_removal_mode 0)
		)
		(polygon
			(pts
				(arc
					(start 314.14212 -435.16042)
					(mid 314.164438 -435.214302)
					(end 314.21832 -435.23662)
				)
				(arc
					(start 315.15812 -435.23662)
					(mid 315.212002 -435.214302)
					(end 315.23432 -435.16042)
				)
				(arc
					(start 315.23432 -432.618896)
					(mid 315.212002 -432.565014)
					(end 315.15812 -432.542696)
				)
				(arc
					(start 314.21832 -432.542696)
					(mid 314.164438 -432.565014)
					(end 314.14212 -432.618896)
				)
			)
		)
	)
	(zone
		(layers "In1.Cu" "In7.Cu" "In8.Cu" "In9.Cu" "In10.Cu" "In12.Cu" "In14.Cu"
			"In16.Cu"
		)
		(hatch none 0.5)
		(connect_pads
			(clearance 0)
		)
		(min_thickness 0.25)
		(keepout
			(tracks not_allowed)
			(vias allowed)
			(pads allowed)
			(copperpour not_allowed)
			(footprints allowed)
		)
		(placement
			(enabled no)
			(sheetname "")
		)
		(fill yes
			(thermal_gap 0.5)
			(thermal_bridge_width 0.5)
			(island_removal_mode 0)
		)
		(polygon
			(pts
				(arc
					(start 58.142124 -435.16042)
					(mid 58.164442 -435.214302)
					(end 58.218324 -435.23662)
				)
				(arc
					(start 59.158124 -435.23662)
					(mid 59.212006 -435.214302)
					(end 59.234324 -435.16042)
				)
				(arc
					(start 59.234324 -432.618896)
					(mid 59.212006 -432.565014)
					(end 59.158124 -432.542696)
				)
				(arc
					(start 58.218324 -432.542696)
					(mid 58.164442 -432.565014)
					(end 58.142124 -432.618896)
				)
			)
		)
	)
	(zone
		(layers "In1.Cu" "In7.Cu" "In8.Cu" "In9.Cu" "In10.Cu" "In12.Cu" "In14.Cu"
			"In16.Cu"
		)
		(hatch none 0.5)
		(connect_pads
			(clearance 0)
		)
		(min_thickness 0.25)
		(keepout
			(tracks not_allowed)
			(vias allowed)
			(pads allowed)
			(copperpour not_allowed)
			(footprints allowed)
		)
		(placement
			(enabled no)
			(sheetname "")
		)
		(fill yes
			(thermal_gap 0.5)
			(thermal_bridge_width 0.5)
			(island_removal_mode 0)
		)
		(polygon
			(pts
				(arc
					(start 62.142116 -435.16042)
					(mid 62.164434 -435.214302)
					(end 62.218316 -435.23662)
				)
				(arc
					(start 63.158116 -435.23662)
					(mid 63.211998 -435.214302)
					(end 63.234316 -435.16042)
				)
				(arc
					(start 63.234316 -432.618896)
					(mid 63.211998 -432.565014)
					(end 63.158116 -432.542696)
				)
				(arc
					(start 62.218316 -432.542696)
					(mid 62.164434 -432.565014)
					(end 62.142116 -432.618896)
				)
			)
		)
	)
	(zone
		(layers "In1.Cu" "In7.Cu" "In8.Cu" "In9.Cu" "In10.Cu" "In12.Cu" "In14.Cu"
			"In16.Cu"
		)
		(hatch none 0.5)
		(connect_pads
			(clearance 0)
		)
		(min_thickness 0.25)
		(keepout
			(tracks not_allowed)
			(vias allowed)
			(pads allowed)
			(copperpour not_allowed)
			(footprints allowed)
		)
		(placement
			(enabled no)
			(sheetname "")
		)
		(fill yes
			(thermal_gap 0.5)
			(thermal_bridge_width 0.5)
			(island_removal_mode 0)
		)
		(polygon
			(pts
				(arc
					(start 339.14207 -435.16042)
					(mid 339.164388 -435.214302)
					(end 339.21827 -435.23662)
				)
				(arc
					(start 340.15807 -435.23662)
					(mid 340.211952 -435.214302)
					(end 340.23427 -435.16042)
				)
				(arc
					(start 340.23427 -432.618896)
					(mid 340.211952 -432.565014)
					(end 340.15807 -432.542696)
				)
				(arc
					(start 339.21827 -432.542696)
					(mid 339.164388 -432.565014)
					(end 339.14207 -432.618896)
				)
			)
		)
	)
	(zone
		(layers "In1.Cu" "In7.Cu" "In8.Cu" "In9.Cu" "In10.Cu" "In12.Cu" "In14.Cu"
			"In16.Cu"
		)
		(hatch none 0.5)
		(connect_pads
			(clearance 0)
		)
		(min_thickness 0.25)
		(keepout
			(tracks not_allowed)
			(vias allowed)
			(pads allowed)
			(copperpour not_allowed)
			(footprints allowed)
		)
		(placement
			(enabled no)
			(sheetname "")
		)
		(fill yes
			(thermal_gap 0.5)
			(thermal_bridge_width 0.5)
			(island_removal_mode 0)
		)
		(polygon
			(pts
				(arc
					(start 60.14212 -436.160418)
					(mid 60.164438 -436.2143)
					(end 60.21832 -436.236618)
				)
				(arc
					(start 61.15812 -436.236618)
					(mid 61.212002 -436.2143)
					(end 61.23432 -436.160418)
				)
				(arc
					(start 61.23432 -433.618894)
					(mid 61.212002 -433.565012)
					(end 61.15812 -433.542694)
				)
				(arc
					(start 60.21832 -433.542694)
					(mid 60.164438 -433.565012)
					(end 60.14212 -433.618894)
				)
			)
		)
	)
	(zone
		(layers "In1.Cu" "In7.Cu" "In8.Cu" "In9.Cu" "In10.Cu" "In12.Cu" "In14.Cu"
			"In16.Cu"
		)
		(hatch none 0.5)
		(connect_pads
			(clearance 0)
		)
		(min_thickness 0.25)
		(keepout
			(tracks not_allowed)
			(vias allowed)
			(pads allowed)
			(copperpour not_allowed)
			(footprints allowed)
		)
		(placement
			(enabled no)
			(sheetname "")
		)
		(fill yes
			(thermal_gap 0.5)
			(thermal_bridge_width 0.5)
			(island_removal_mode 0)
		)
		(polygon
			(pts
				(arc
					(start 331.142086 -435.16042)
					(mid 331.164404 -435.214302)
					(end 331.218286 -435.23662)
				)
				(arc
					(start 332.158086 -435.23662)
					(mid 332.211968 -435.214302)
					(end 332.234286 -435.16042)
				)
				(arc
					(start 332.234286 -432.618896)
					(mid 332.211968 -432.565014)
					(end 332.158086 -432.542696)
				)
				(arc
					(start 331.218286 -432.542696)
					(mid 331.164404 -432.565014)
					(end 331.142086 -432.618896)
				)
			)
		)
	)
	(zone
		(layers "In1.Cu" "In7.Cu" "In8.Cu" "In9.Cu" "In10.Cu" "In12.Cu" "In14.Cu"
			"In16.Cu"
		)
		(hatch none 0.5)
		(connect_pads
			(clearance 0)
		)
		(min_thickness 0.25)
		(keepout
			(tracks not_allowed)
			(vias allowed)
			(pads allowed)
			(copperpour not_allowed)
			(footprints allowed)
		)
		(placement
			(enabled no)
			(sheetname "")
		)
		(fill yes
			(thermal_gap 0.5)
			(thermal_bridge_width 0.5)
			(island_removal_mode 0)
		)
		(polygon
			(pts
				(arc
					(start 318.142112 -435.16042)
					(mid 318.16443 -435.214302)
					(end 318.218312 -435.23662)
				)
				(arc
					(start 319.158112 -435.23662)
					(mid 319.211994 -435.214302)
					(end 319.234312 -435.16042)
				)
				(arc
					(start 319.234312 -432.618896)
					(mid 319.211994 -432.565014)
					(end 319.158112 -432.542696)
				)
				(arc
					(start 318.218312 -432.542696)
					(mid 318.16443 -432.565014)
					(end 318.142112 -432.618896)
				)
			)
		)
	)
	(zone
		(layers "In1.Cu" "In7.Cu" "In8.Cu" "In9.Cu" "In10.Cu" "In12.Cu" "In14.Cu"
			"In16.Cu"
		)
		(hatch none 0.5)
		(connect_pads
			(clearance 0)
		)
		(min_thickness 0.25)
		(keepout
			(tracks not_allowed)
			(vias allowed)
			(pads allowed)
			(copperpour not_allowed)
			(footprints allowed)
		)
		(placement
			(enabled no)
			(sheetname "")
		)
		(fill yes
			(thermal_gap 0.5)
			(thermal_bridge_width 0.5)
			(island_removal_mode 0)
		)
		(polygon
			(pts
				(arc
					(start 324.1421 -436.160418)
					(mid 324.164418 -436.2143)
					(end 324.2183 -436.236618)
				)
				(arc
					(start 325.1581 -436.236618)
					(mid 325.211982 -436.2143)
					(end 325.2343 -436.160418)
				)
				(arc
					(start 325.2343 -433.618894)
					(mid 325.211982 -433.565012)
					(end 325.1581 -433.542694)
				)
				(arc
					(start 324.2183 -433.542694)
					(mid 324.164418 -433.565012)
					(end 324.1421 -433.618894)
				)
			)
		)
	)
	(zone
		(layers "In1.Cu" "In7.Cu" "In8.Cu" "In9.Cu" "In10.Cu" "In12.Cu" "In14.Cu"
			"In16.Cu"
		)
		(hatch none 0.5)
		(connect_pads
			(clearance 0)
		)
		(min_thickness 0.25)
		(keepout
			(tracks not_allowed)
			(vias allowed)
			(pads allowed)
			(copperpour not_allowed)
			(footprints allowed)
		)
		(placement
			(enabled no)
			(sheetname "")
		)
		(fill yes
			(thermal_gap 0.5)
			(thermal_bridge_width 0.5)
			(island_removal_mode 0)
		)
		(polygon
			(pts
				(arc
					(start 87.142066 -435.16042)
					(mid 87.164384 -435.214302)
					(end 87.218266 -435.23662)
				)
				(arc
					(start 88.158066 -435.23662)
					(mid 88.211948 -435.214302)
					(end 88.234266 -435.16042)
				)
				(arc
					(start 88.234266 -432.618896)
					(mid 88.211948 -432.565014)
					(end 88.158066 -432.542696)
				)
				(arc
					(start 87.218266 -432.542696)
					(mid 87.164384 -432.565014)
					(end 87.142066 -432.618896)
				)
			)
		)
	)
	(zone
		(layers "In1.Cu" "In7.Cu" "In8.Cu" "In9.Cu" "In10.Cu" "In12.Cu" "In14.Cu"
			"In16.Cu"
		)
		(hatch none 0.5)
		(connect_pads
			(clearance 0)
		)
		(min_thickness 0.25)
		(keepout
			(tracks not_allowed)
			(vias allowed)
			(pads allowed)
			(copperpour not_allowed)
			(footprints allowed)
		)
		(placement
			(enabled no)
			(sheetname "")
		)
		(fill yes
			(thermal_gap 0.5)
			(thermal_bridge_width 0.5)
			(island_removal_mode 0)
		)
		(polygon
			(pts
				(arc
					(start 326.142096 -435.16042)
					(mid 326.164414 -435.214302)
					(end 326.218296 -435.23662)
				)
				(arc
					(start 327.158096 -435.23662)
					(mid 327.211978 -435.214302)
					(end 327.234296 -435.16042)
				)
				(arc
					(start 327.234296 -432.618896)
					(mid 327.211978 -432.565014)
					(end 327.158096 -432.542696)
				)
				(arc
					(start 326.218296 -432.542696)
					(mid 326.164414 -432.565014)
					(end 326.142096 -432.618896)
				)
			)
		)
	)
	(zone
		(layers "In1.Cu" "In7.Cu" "In8.Cu" "In9.Cu" "In10.Cu" "In12.Cu" "In14.Cu"
			"In16.Cu"
		)
		(hatch none 0.5)
		(connect_pads
			(clearance 0)
		)
		(min_thickness 0.25)
		(keepout
			(tracks not_allowed)
			(vias allowed)
			(pads allowed)
			(copperpour not_allowed)
			(footprints allowed)
		)
		(placement
			(enabled no)
			(sheetname "")
		)
		(fill yes
			(thermal_gap 0.5)
			(thermal_bridge_width 0.5)
			(island_removal_mode 0)
		)
		(polygon
			(pts
				(arc
					(start 345.142058 -436.160418)
					(mid 345.164376 -436.2143)
					(end 345.218258 -436.236618)
				)
				(arc
					(start 346.158058 -436.236618)
					(mid 346.21194 -436.2143)
					(end 346.234258 -436.160418)
				)
				(arc
					(start 346.234258 -433.618894)
					(mid 346.21194 -433.565012)
					(end 346.158058 -433.542694)
				)
				(arc
					(start 345.218258 -433.542694)
					(mid 345.164376 -433.565012)
					(end 345.142058 -433.618894)
				)
			)
		)
	)
	(zone
		(layers "In1.Cu" "In7.Cu" "In8.Cu" "In9.Cu" "In10.Cu" "In12.Cu" "In14.Cu"
			"In16.Cu"
		)
		(hatch none 0.5)
		(connect_pads
			(clearance 0)
		)
		(min_thickness 0.25)
		(keepout
			(tracks not_allowed)
			(vias allowed)
			(pads allowed)
			(copperpour not_allowed)
			(footprints allowed)
		)
		(placement
			(enabled no)
			(sheetname "")
		)
		(fill yes
			(thermal_gap 0.5)
			(thermal_bridge_width 0.5)
			(island_removal_mode 0)
		)
		(polygon
			(pts
				(arc
					(start 320.142108 -436.160418)
					(mid 320.164426 -436.2143)
					(end 320.218308 -436.236618)
				)
				(arc
					(start 321.158108 -436.236618)
					(mid 321.21199 -436.2143)
					(end 321.234308 -436.160418)
				)
				(arc
					(start 321.234308 -433.618894)
					(mid 321.21199 -433.565012)
					(end 321.158108 -433.542694)
				)
				(arc
					(start 320.218308 -433.542694)
					(mid 320.164426 -433.565012)
					(end 320.142108 -433.618894)
				)
			)
		)
	)
	(zone
		(layers "In1.Cu" "In7.Cu" "In8.Cu" "In9.Cu" "In10.Cu" "In12.Cu" "In14.Cu"
			"In16.Cu"
		)
		(hatch none 0.5)
		(connect_pads
			(clearance 0)
		)
		(min_thickness 0.25)
		(keepout
			(tracks not_allowed)
			(vias allowed)
			(pads allowed)
			(copperpour not_allowed)
			(footprints allowed)
		)
		(placement
			(enabled no)
			(sheetname "")
		)
		(fill yes
			(thermal_gap 0.5)
			(thermal_bridge_width 0.5)
			(island_removal_mode 0)
		)
		(polygon
			(pts
				(arc
					(start 68.142104 -436.160418)
					(mid 68.164422 -436.2143)
					(end 68.218304 -436.236618)
				)
				(arc
					(start 69.158104 -436.236618)
					(mid 69.211986 -436.2143)
					(end 69.234304 -436.160418)
				)
				(arc
					(start 69.234304 -433.618894)
					(mid 69.211986 -433.565012)
					(end 69.158104 -433.542694)
				)
				(arc
					(start 68.218304 -433.542694)
					(mid 68.164422 -433.565012)
					(end 68.142104 -433.618894)
				)
			)
		)
	)
	(zone
		(layers "In1.Cu" "In7.Cu" "In8.Cu" "In9.Cu" "In10.Cu" "In12.Cu" "In14.Cu"
			"In16.Cu"
		)
		(hatch none 0.5)
		(connect_pads
			(clearance 0)
		)
		(min_thickness 0.25)
		(keepout
			(tracks not_allowed)
			(vias allowed)
			(pads allowed)
			(copperpour not_allowed)
			(footprints allowed)
		)
		(placement
			(enabled no)
			(sheetname "")
		)
		(fill yes
			(thermal_gap 0.5)
			(thermal_bridge_width 0.5)
			(island_removal_mode 0)
		)
		(polygon
			(pts
				(arc
					(start 70.1421 -435.16042)
					(mid 70.164418 -435.214302)
					(end 70.2183 -435.23662)
				)
				(arc
					(start 71.1581 -435.23662)
					(mid 71.211982 -435.214302)
					(end 71.2343 -435.16042)
				)
				(arc
					(start 71.2343 -432.618896)
					(mid 71.211982 -432.565014)
					(end 71.1581 -432.542696)
				)
				(arc
					(start 70.2183 -432.542696)
					(mid 70.164418 -432.565014)
					(end 70.1421 -432.618896)
				)
			)
		)
	)
	(zone
		(layers "In1.Cu" "In7.Cu" "In8.Cu" "In9.Cu" "In10.Cu" "In12.Cu" "In14.Cu"
			"In16.Cu"
		)
		(hatch none 0.5)
		(connect_pads
			(clearance 0)
		)
		(min_thickness 0.25)
		(keepout
			(tracks not_allowed)
			(vias allowed)
			(pads allowed)
			(copperpour not_allowed)
			(footprints allowed)
		)
		(placement
			(enabled no)
			(sheetname "")
		)
		(fill yes
			(thermal_gap 0.5)
			(thermal_bridge_width 0.5)
			(island_removal_mode 0)
		)
		(polygon
			(pts
				(arc
					(start 322.142104 -435.16042)
					(mid 322.164422 -435.214302)
					(end 322.218304 -435.23662)
				)
				(arc
					(start 323.158104 -435.23662)
					(mid 323.211986 -435.214302)
					(end 323.234304 -435.16042)
				)
				(arc
					(start 323.234304 -432.618896)
					(mid 323.211986 -432.565014)
					(end 323.158104 -432.542696)
				)
				(arc
					(start 322.218304 -432.542696)
					(mid 322.164422 -432.565014)
					(end 322.142104 -432.618896)
				)
			)
		)
	)
	(zone
		(layers "In1.Cu" "In7.Cu" "In8.Cu" "In9.Cu" "In10.Cu" "In12.Cu" "In14.Cu"
			"In16.Cu"
		)
		(hatch none 0.5)
		(connect_pads
			(clearance 0)
		)
		(min_thickness 0.25)
		(keepout
			(tracks not_allowed)
			(vias allowed)
			(pads allowed)
			(copperpour not_allowed)
			(footprints allowed)
		)
		(placement
			(enabled no)
			(sheetname "")
		)
		(fill yes
			(thermal_gap 0.5)
			(thermal_bridge_width 0.5)
			(island_removal_mode 0)
		)
		(polygon
			(pts
				(arc
					(start 337.142074 -436.160418)
					(mid 337.164392 -436.2143)
					(end 337.218274 -436.236618)
				)
				(arc
					(start 338.158074 -436.236618)
					(mid 338.211956 -436.2143)
					(end 338.234274 -436.160418)
				)
				(arc
					(start 338.234274 -433.618894)
					(mid 338.211956 -433.565012)
					(end 338.158074 -433.542694)
				)
				(arc
					(start 337.218274 -433.542694)
					(mid 337.164392 -433.565012)
					(end 337.142074 -433.618894)
				)
			)
		)
	)
	(zone
		(layers "In1.Cu" "In7.Cu" "In8.Cu" "In9.Cu" "In10.Cu" "In12.Cu" "In14.Cu"
			"In16.Cu"
		)
		(hatch none 0.5)
		(connect_pads
			(clearance 0)
		)
		(min_thickness 0.25)
		(keepout
			(tracks not_allowed)
			(vias allowed)
			(pads allowed)
			(copperpour not_allowed)
			(footprints allowed)
		)
		(placement
			(enabled no)
			(sheetname "")
		)
		(fill yes
			(thermal_gap 0.5)
			(thermal_bridge_width 0.5)
			(island_removal_mode 0)
		)
		(polygon
			(pts
				(arc
					(start 72.142096 -436.160418)
					(mid 72.164414 -436.2143)
					(end 72.218296 -436.236618)
				)
				(arc
					(start 73.158096 -436.236618)
					(mid 73.211978 -436.2143)
					(end 73.234296 -436.160418)
				)
				(arc
					(start 73.234296 -433.618894)
					(mid 73.211978 -433.565012)
					(end 73.158096 -433.542694)
				)
				(arc
					(start 72.218296 -433.542694)
					(mid 72.164414 -433.565012)
					(end 72.142096 -433.618894)
				)
			)
		)
	)
	(zone
		(layers "In1.Cu" "In7.Cu" "In8.Cu" "In9.Cu" "In10.Cu" "In12.Cu" "In14.Cu"
			"In16.Cu"
		)
		(hatch none 0.5)
		(connect_pads
			(clearance 0)
		)
		(min_thickness 0.25)
		(keepout
			(tracks not_allowed)
			(vias allowed)
			(pads allowed)
			(copperpour not_allowed)
			(footprints allowed)
		)
		(placement
			(enabled no)
			(sheetname "")
		)
		(fill yes
			(thermal_gap 0.5)
			(thermal_bridge_width 0.5)
			(island_removal_mode 0)
		)
		(polygon
			(pts
				(arc
					(start 83.142074 -435.16042)
					(mid 83.164392 -435.214302)
					(end 83.218274 -435.23662)
				)
				(arc
					(start 84.158074 -435.23662)
					(mid 84.211956 -435.214302)
					(end 84.234274 -435.16042)
				)
				(arc
					(start 84.234274 -432.618896)
					(mid 84.211956 -432.565014)
					(end 84.158074 -432.542696)
				)
				(arc
					(start 83.218274 -432.542696)
					(mid 83.164392 -432.565014)
					(end 83.142074 -432.618896)
				)
			)
		)
	)
	(zone
		(layers "In1.Cu" "In7.Cu" "In8.Cu" "In9.Cu" "In10.Cu" "In12.Cu" "In14.Cu"
			"In16.Cu"
		)
		(hatch none 0.5)
		(connect_pads
			(clearance 0)
		)
		(min_thickness 0.25)
		(keepout
			(tracks not_allowed)
			(vias allowed)
			(pads allowed)
			(copperpour not_allowed)
			(footprints allowed)
		)
		(placement
			(enabled no)
			(sheetname "")
		)
		(fill yes
			(thermal_gap 0.5)
			(thermal_bridge_width 0.5)
			(island_removal_mode 0)
		)
		(polygon
			(pts
				(arc
					(start 85.14207 -436.160418)
					(mid 85.164388 -436.2143)
					(end 85.21827 -436.236618)
				)
				(arc
					(start 86.15807 -436.236618)
					(mid 86.211952 -436.2143)
					(end 86.23427 -436.160418)
				)
				(arc
					(start 86.23427 -433.618894)
					(mid 86.211952 -433.565012)
					(end 86.15807 -433.542694)
				)
				(arc
					(start 85.21827 -433.542694)
					(mid 85.164388 -433.565012)
					(end 85.14207 -433.618894)
				)
			)
		)
	)
	(zone
		(layers "In1.Cu" "In7.Cu" "In8.Cu" "In9.Cu" "In10.Cu" "In12.Cu" "In14.Cu"
			"In16.Cu"
		)
		(hatch none 0.5)
		(connect_pads
			(clearance 0)
		)
		(min_thickness 0.25)
		(keepout
			(tracks not_allowed)
			(vias allowed)
			(pads allowed)
			(copperpour not_allowed)
			(footprints allowed)
		)
		(placement
			(enabled no)
			(sheetname "")
		)
		(fill yes
			(thermal_gap 0.5)
			(thermal_bridge_width 0.5)
			(island_removal_mode 0)
		)
		(polygon
			(pts
				(arc
					(start 316.142116 -436.160418)
					(mid 316.164434 -436.2143)
					(end 316.218316 -436.236618)
				)
				(arc
					(start 317.158116 -436.236618)
					(mid 317.211998 -436.2143)
					(end 317.234316 -436.160418)
				)
				(arc
					(start 317.234316 -433.618894)
					(mid 317.211998 -433.565012)
					(end 317.158116 -433.542694)
				)
				(arc
					(start 316.218316 -433.542694)
					(mid 316.164434 -433.565012)
					(end 316.142116 -433.618894)
				)
			)
		)
	)
	(zone
		(layers "In1.Cu" "In7.Cu" "In8.Cu" "In9.Cu" "In10.Cu" "In12.Cu" "In14.Cu"
			"In16.Cu"
		)
		(hatch none 0.5)
		(connect_pads
			(clearance 0)
		)
		(min_thickness 0.25)
		(keepout
			(tracks not_allowed)
			(vias allowed)
			(pads allowed)
			(copperpour not_allowed)
			(footprints allowed)
		)
		(placement
			(enabled no)
			(sheetname "")
		)
		(fill yes
			(thermal_gap 0.5)
			(thermal_bridge_width 0.5)
			(island_removal_mode 0)
		)
		(polygon
			(pts
				(arc
					(start 89.142062 -436.160418)
					(mid 89.16438 -436.2143)
					(end 89.218262 -436.236618)
				)
				(arc
					(start 90.158062 -436.236618)
					(mid 90.211944 -436.2143)
					(end 90.234262 -436.160418)
				)
				(arc
					(start 90.234262 -433.618894)
					(mid 90.211944 -433.565012)
					(end 90.158062 -433.542694)
				)
				(arc
					(start 89.218262 -433.542694)
					(mid 89.16438 -433.565012)
					(end 89.142062 -433.618894)
				)
			)
		)
	)
	(zone
		(layers "In1.Cu" "In7.Cu" "In8.Cu" "In9.Cu" "In10.Cu" "In12.Cu" "In14.Cu"
			"In16.Cu"
		)
		(hatch none 0.5)
		(connect_pads
			(clearance 0)
		)
		(min_thickness 0.25)
		(keepout
			(tracks not_allowed)
			(vias allowed)
			(pads allowed)
			(copperpour not_allowed)
			(footprints allowed)
		)
		(placement
			(enabled no)
			(sheetname "")
		)
		(fill yes
			(thermal_gap 0.5)
			(thermal_bridge_width 0.5)
			(island_removal_mode 0)
		)
		(polygon
			(pts
				(arc
					(start 79.142082 -435.16042)
					(mid 79.1644 -435.214302)
					(end 79.218282 -435.23662)
				)
				(arc
					(start 80.158082 -435.23662)
					(mid 80.211964 -435.214302)
					(end 80.234282 -435.16042)
				)
				(arc
					(start 80.234282 -432.618896)
					(mid 80.211964 -432.565014)
					(end 80.158082 -432.542696)
				)
				(arc
					(start 79.218282 -432.542696)
					(mid 79.1644 -432.565014)
					(end 79.142082 -432.618896)
				)
			)
		)
	)
	(zone
		(layers "In1.Cu" "In7.Cu" "In8.Cu" "In9.Cu" "In10.Cu" "In12.Cu" "In14.Cu"
			"In16.Cu"
		)
		(hatch none 0.5)
		(connect_pads
			(clearance 0)
		)
		(min_thickness 0.25)
		(keepout
			(tracks not_allowed)
			(vias allowed)
			(pads allowed)
			(copperpour not_allowed)
			(footprints allowed)
		)
		(placement
			(enabled no)
			(sheetname "")
		)
		(fill yes
			(thermal_gap 0.5)
			(thermal_bridge_width 0.5)
			(island_removal_mode 0)
		)
		(polygon
			(pts
				(arc
					(start 343.142062 -435.16042)
					(mid 343.16438 -435.214302)
					(end 343.218262 -435.23662)
				)
				(arc
					(start 344.158062 -435.23662)
					(mid 344.211944 -435.214302)
					(end 344.234262 -435.16042)
				)
				(arc
					(start 344.234262 -432.618896)
					(mid 344.211944 -432.565014)
					(end 344.158062 -432.542696)
				)
				(arc
					(start 343.218262 -432.542696)
					(mid 343.16438 -432.565014)
					(end 343.142062 -432.618896)
				)
			)
		)
	)
	(zone
		(layers "In1.Cu" "In7.Cu" "In8.Cu" "In9.Cu" "In10.Cu" "In12.Cu" "In14.Cu"
			"In16.Cu"
		)
		(hatch none 0.5)
		(connect_pads
			(clearance 0)
		)
		(min_thickness 0.25)
		(keepout
			(tracks not_allowed)
			(vias allowed)
			(pads allowed)
			(copperpour not_allowed)
			(footprints allowed)
		)
		(placement
			(enabled no)
			(sheetname "")
		)
		(fill yes
			(thermal_gap 0.5)
			(thermal_bridge_width 0.5)
			(island_removal_mode 0)
		)
		(polygon
			(pts
				(arc
					(start 81.142078 -436.160418)
					(mid 81.164396 -436.2143)
					(end 81.218278 -436.236618)
				)
				(arc
					(start 82.158078 -436.236618)
					(mid 82.21196 -436.2143)
					(end 82.234278 -436.160418)
				)
				(arc
					(start 82.234278 -433.618894)
					(mid 82.21196 -433.565012)
					(end 82.158078 -433.542694)
				)
				(arc
					(start 81.218278 -433.542694)
					(mid 81.164396 -433.565012)
					(end 81.142078 -433.618894)
				)
			)
		)
	)
	(zone
		(layers "In1.Cu" "In7.Cu" "In8.Cu" "In9.Cu" "In10.Cu" "In12.Cu" "In14.Cu"
			"In16.Cu"
		)
		(hatch none 0.5)
		(connect_pads
			(clearance 0)
		)
		(min_thickness 0.25)
		(keepout
			(tracks not_allowed)
			(vias allowed)
			(pads allowed)
			(copperpour not_allowed)
			(footprints allowed)
		)
		(placement
			(enabled no)
			(sheetname "")
		)
		(fill yes
			(thermal_gap 0.5)
			(thermal_bridge_width 0.5)
			(island_removal_mode 0)
		)
		(polygon
			(pts
				(arc
					(start 77.142086 -436.160418)
					(mid 77.164404 -436.2143)
					(end 77.218286 -436.236618)
				)
				(arc
					(start 78.158086 -436.236618)
					(mid 78.211968 -436.2143)
					(end 78.234286 -436.160418)
				)
				(arc
					(start 78.234286 -433.618894)
					(mid 78.211968 -433.565012)
					(end 78.158086 -433.542694)
				)
				(arc
					(start 77.218286 -433.542694)
					(mid 77.164404 -433.565012)
					(end 77.142086 -433.618894)
				)
			)
		)
	)
	(zone
		(layers "In1.Cu" "In7.Cu" "In8.Cu" "In9.Cu" "In10.Cu" "In12.Cu" "In14.Cu"
			"In16.Cu"
		)
		(hatch none 0.5)
		(connect_pads
			(clearance 0)
		)
		(min_thickness 0.25)
		(keepout
			(tracks not_allowed)
			(vias allowed)
			(pads allowed)
			(copperpour not_allowed)
			(footprints allowed)
		)
		(placement
			(enabled no)
			(sheetname "")
		)
		(fill yes
			(thermal_gap 0.5)
			(thermal_bridge_width 0.5)
			(island_removal_mode 0)
		)
		(polygon
			(pts
				(arc
					(start 333.142082 -436.160418)
					(mid 333.1644 -436.2143)
					(end 333.218282 -436.236618)
				)
				(arc
					(start 334.158082 -436.236618)
					(mid 334.211964 -436.2143)
					(end 334.234282 -436.160418)
				)
				(arc
					(start 334.234282 -433.618894)
					(mid 334.211964 -433.565012)
					(end 334.158082 -433.542694)
				)
				(arc
					(start 333.218282 -433.542694)
					(mid 333.1644 -433.565012)
					(end 333.142082 -433.618894)
				)
			)
		)
	)
	(zone
		(layers "In1.Cu" "In7.Cu" "In8.Cu" "In9.Cu" "In10.Cu" "In12.Cu" "In14.Cu"
			"In16.Cu"
		)
		(hatch none 0.5)
		(connect_pads
			(clearance 0)
		)
		(min_thickness 0.25)
		(keepout
			(tracks not_allowed)
			(vias allowed)
			(pads allowed)
			(copperpour not_allowed)
			(footprints allowed)
		)
		(placement
			(enabled no)
			(sheetname "")
		)
		(fill yes
			(thermal_gap 0.5)
			(thermal_bridge_width 0.5)
			(island_removal_mode 0)
		)
		(polygon
			(pts
				(arc
					(start 341.142066 -436.160418)
					(mid 341.164384 -436.2143)
					(end 341.218266 -436.236618)
				)
				(arc
					(start 342.158066 -436.236618)
					(mid 342.211948 -436.2143)
					(end 342.234266 -436.160418)
				)
				(arc
					(start 342.234266 -433.618894)
					(mid 342.211948 -433.565012)
					(end 342.158066 -433.542694)
				)
				(arc
					(start 341.218266 -433.542694)
					(mid 341.164384 -433.565012)
					(end 341.142066 -433.618894)
				)
			)
		)
	)
	(zone
		(layers "In1.Cu" "In7.Cu" "In8.Cu" "In9.Cu" "In10.Cu" "In12.Cu" "In14.Cu"
			"In16.Cu"
		)
		(hatch none 0.5)
		(connect_pads
			(clearance 0)
		)
		(min_thickness 0.25)
		(keepout
			(tracks not_allowed)
			(vias allowed)
			(pads allowed)
			(copperpour not_allowed)
			(footprints allowed)
		)
		(placement
			(enabled no)
			(sheetname "")
		)
		(fill yes
			(thermal_gap 0.5)
			(thermal_bridge_width 0.5)
			(island_removal_mode 0)
		)
		(polygon
			(pts
				(arc
					(start 66.142108 -435.16042)
					(mid 66.164426 -435.214302)
					(end 66.218308 -435.23662)
				)
				(arc
					(start 67.158108 -435.23662)
					(mid 67.21199 -435.214302)
					(end 67.234308 -435.16042)
				)
				(arc
					(start 67.234308 -432.618896)
					(mid 67.21199 -432.565014)
					(end 67.158108 -432.542696)
				)
				(arc
					(start 66.218308 -432.542696)
					(mid 66.164426 -432.565014)
					(end 66.142108 -432.618896)
				)
			)
		)
	)
	(zone
		(layers "In1.Cu" "In7.Cu" "In8.Cu" "In9.Cu" "In10.Cu" "In12.Cu" "In14.Cu"
			"In16.Cu"
		)
		(hatch none 0.5)
		(connect_pads
			(clearance 0)
		)
		(min_thickness 0.25)
		(keepout
			(tracks not_allowed)
			(vias allowed)
			(pads allowed)
			(copperpour not_allowed)
			(footprints allowed)
		)
		(placement
			(enabled no)
			(sheetname "")
		)
		(fill yes
			(thermal_gap 0.5)
			(thermal_bridge_width 0.5)
			(island_removal_mode 0)
		)
		(polygon
			(pts
				(arc
					(start 328.142092 -436.160418)
					(mid 328.16441 -436.2143)
					(end 328.218292 -436.236618)
				)
				(arc
					(start 329.158092 -436.236618)
					(mid 329.211974 -436.2143)
					(end 329.234292 -436.160418)
				)
				(arc
					(start 329.234292 -433.618894)
					(mid 329.211974 -433.565012)
					(end 329.158092 -433.542694)
				)
				(arc
					(start 328.218292 -433.542694)
					(mid 328.16441 -433.565012)
					(end 328.142092 -433.618894)
				)
			)
		)
	)
	(zone
		(layers "In1.Cu" "In7.Cu" "In8.Cu" "In9.Cu" "In10.Cu" "In12.Cu" "In14.Cu"
			"In16.Cu"
		)
		(hatch none 0.5)
		(connect_pads
			(clearance 0)
		)
		(min_thickness 0.25)
		(keepout
			(tracks not_allowed)
			(vias allowed)
			(pads allowed)
			(copperpour not_allowed)
			(footprints allowed)
		)
		(placement
			(enabled no)
			(sheetname "")
		)
		(fill yes
			(thermal_gap 0.5)
			(thermal_bridge_width 0.5)
			(island_removal_mode 0)
		)
		(polygon
			(pts
				(arc
					(start 75.14209 -435.16042)
					(mid 75.164408 -435.214302)
					(end 75.21829 -435.23662)
				)
				(arc
					(start 76.15809 -435.23662)
					(mid 76.211972 -435.214302)
					(end 76.23429 -435.16042)
				)
				(arc
					(start 76.23429 -432.618896)
					(mid 76.211972 -432.565014)
					(end 76.15809 -432.542696)
				)
				(arc
					(start 75.21829 -432.542696)
					(mid 75.164408 -432.565014)
					(end 75.14209 -432.618896)
				)
			)
		)
	)
	(zone
		(layers "In1.Cu" "In7.Cu" "In8.Cu" "In9.Cu" "In10.Cu" "In12.Cu" "In14.Cu"
			"In16.Cu"
		)
		(hatch none 0.5)
		(connect_pads
			(clearance 0)
		)
		(min_thickness 0.25)
		(keepout
			(tracks not_allowed)
			(vias allowed)
			(pads allowed)
			(copperpour not_allowed)
			(footprints allowed)
		)
		(placement
			(enabled no)
			(sheetname "")
		)
		(fill yes
			(thermal_gap 0.5)
			(thermal_bridge_width 0.5)
			(island_removal_mode 0)
		)
		(polygon
			(pts
				(arc
					(start 335.142078 -435.16042)
					(mid 335.164396 -435.214302)
					(end 335.218278 -435.23662)
				)
				(arc
					(start 336.158078 -435.23662)
					(mid 336.21196 -435.214302)
					(end 336.234278 -435.16042)
				)
				(arc
					(start 336.234278 -432.618896)
					(mid 336.21196 -432.565014)
					(end 336.158078 -432.542696)
				)
				(arc
					(start 335.218278 -432.542696)
					(mid 335.164396 -432.565014)
					(end 335.142078 -432.618896)
				)
			)
		)
	)
	(zone
		(layers "In1.Cu" "In7.Cu" "In8.Cu" "In9.Cu" "In10.Cu" "In12.Cu" "In14.Cu"
			"In16.Cu"
		)
		(hatch none 0.5)
		(connect_pads
			(clearance 0)
		)
		(min_thickness 0.25)
		(keepout
			(tracks not_allowed)
			(vias allowed)
			(pads allowed)
			(copperpour not_allowed)
			(footprints allowed)
		)
		(placement
			(enabled no)
			(sheetname "")
		)
		(fill yes
			(thermal_gap 0.5)
			(thermal_bridge_width 0.5)
			(island_removal_mode 0)
		)
		(polygon
			(pts
				(arc
					(start 64.142112 -436.160418)
					(mid 64.16443 -436.2143)
					(end 64.218312 -436.236618)
				)
				(arc
					(start 65.158112 -436.236618)
					(mid 65.211994 -436.2143)
					(end 65.234312 -436.160418)
				)
				(arc
					(start 65.234312 -433.618894)
					(mid 65.211994 -433.565012)
					(end 65.158112 -433.542694)
				)
				(arc
					(start 64.218312 -433.542694)
					(mid 64.16443 -433.565012)
					(end 64.142112 -433.618894)
				)
			)
		)
	)
	(zone
		(layer "In2.Cu")
		(hatch none 0.5)
		(connect_pads
			(clearance 0)
		)
		(min_thickness 0.25)
		(keepout
			(tracks allowed)
			(vias allowed)
			(pads allowed)
			(copperpour allowed)
			(footprints allowed)
		)
		(placement
			(enabled no)
			(sheetname "")
		)
		(fill
			(thermal_gap 0.5)
			(thermal_bridge_width 0.5)
			(island_removal_mode 0)
		)
		(polygon
			(pts
				(xy 294.59809 -266.430252) (xy 294.59809 -265.886946) (xy 295.152826 -265.886946) (xy 295.152826 -266.430252)
			)
		)
	)
	(zone
		(layer "In2.Cu")
		(hatch none 0.5)
		(connect_pads
			(clearance 0)
		)
		(min_thickness 0.25)
		(keepout
			(tracks allowed)
			(vias allowed)
			(pads allowed)
			(copperpour allowed)
			(footprints allowed)
		)
		(placement
			(enabled no)
			(sheetname "")
		)
		(fill
			(thermal_gap 0.5)
			(thermal_bridge_width 0.5)
			(island_removal_mode 0)
		)
		(polygon
			(pts
				(xy 405.86533 -300.734476) (xy 405.86533 -301.26305) (xy 405.32939 -301.26305) (xy 405.32939 -300.734476)
			)
		)
	)
	(zone
		(layer "In2.Cu")
		(hatch none 0.5)
		(connect_pads
			(clearance 0)
		)
		(min_thickness 0.25)
		(keepout
			(tracks allowed)
			(vias allowed)
			(pads allowed)
			(copperpour allowed)
			(footprints allowed)
		)
		(placement
			(enabled no)
			(sheetname "")
		)
		(fill
			(thermal_gap 0.5)
			(thermal_bridge_width 0.5)
			(island_removal_mode 0)
		)
		(polygon
			(pts
				(xy 298.698158 -205.230222) (xy 298.698158 -204.686916) (xy 299.252894 -204.686916) (xy 299.252894 -205.230222)
			)
		)
	)
	(zone
		(layer "In2.Cu")
		(hatch none 0.5)
		(connect_pads
			(clearance 0)
		)
		(min_thickness 0.25)
		(keepout
			(tracks allowed)
			(vias allowed)
			(pads allowed)
			(copperpour allowed)
			(footprints allowed)
		)
		(placement
			(enabled no)
			(sheetname "")
		)
		(fill
			(thermal_gap 0.5)
			(thermal_bridge_width 0.5)
			(island_removal_mode 0)
		)
		(polygon
			(pts
				(xy 173.038262 -236.134656) (xy 173.038262 -236.66323) (xy 172.502322 -236.66323) (xy 172.502322 -236.134656)
			)
		)
	)
	(zone
		(layer "In2.Cu")
		(hatch none 0.5)
		(connect_pads
			(clearance 0)
		)
		(min_thickness 0.25)
		(keepout
			(tracks allowed)
			(vias allowed)
			(pads allowed)
			(copperpour allowed)
			(footprints allowed)
		)
		(placement
			(enabled no)
			(sheetname "")
		)
		(fill
			(thermal_gap 0.5)
			(thermal_bridge_width 0.5)
			(island_removal_mode 0)
		)
		(polygon
			(pts
				(xy 298.698158 -209.480404) (xy 298.698158 -208.937098) (xy 299.252894 -208.937098) (xy 299.252894 -209.480404)
			)
		)
	)
	(zone
		(layer "In2.Cu")
		(hatch none 0.5)
		(connect_pads
			(clearance 0)
		)
		(min_thickness 0.25)
		(keepout
			(tracks allowed)
			(vias allowed)
			(pads allowed)
			(copperpour allowed)
			(footprints allowed)
		)
		(placement
			(enabled no)
			(sheetname "")
		)
		(fill
			(thermal_gap 0.5)
			(thermal_bridge_width 0.5)
			(island_removal_mode 0)
		)
		(polygon
			(pts
				(xy 298.723558 -311.480454) (xy 298.723558 -310.937148) (xy 299.278294 -310.937148) (xy 299.278294 -311.480454)
			)
		)
	)
	(zone
		(layer "In2.Cu")
		(hatch none 0.5)
		(connect_pads
			(clearance 0)
		)
		(min_thickness 0.25)
		(keepout
			(tracks allowed)
			(vias allowed)
			(pads allowed)
			(copperpour allowed)
			(footprints allowed)
		)
		(placement
			(enabled no)
			(sheetname "")
		)
		(fill
			(thermal_gap 0.5)
			(thermal_bridge_width 0.5)
			(island_removal_mode 0)
		)
		(polygon
			(pts
				(xy 131.376674 -221.351602) (xy 134.054342 -221.351602) (xy 134.404608 -221.701868) (xy 134.404608 -222.452692)
				(xy 134.054342 -222.802958) (xy 131.426712 -222.802958) (xy 131.176522 -222.552768) (xy 131.176522 -221.551754)
			)
		)
	)
	(zone
		(layer "In2.Cu")
		(hatch none 0.5)
		(connect_pads
			(clearance 0)
		)
		(min_thickness 0.25)
		(keepout
			(tracks allowed)
			(vias allowed)
			(pads allowed)
			(copperpour allowed)
			(footprints allowed)
		)
		(placement
			(enabled no)
			(sheetname "")
		)
		(fill
			(thermal_gap 0.5)
			(thermal_bridge_width 0.5)
			(island_removal_mode 0)
		)
		(polygon
			(pts
				(xy 50.75809 -239.230408) (xy 50.75809 -238.687102) (xy 51.312826 -238.687102) (xy 51.654202 -238.687102)
				(xy 51.654202 -239.230408) (xy 51.312826 -239.230408)
			)
		)
	)
	(zone
		(layer "In2.Cu")
		(hatch none 0.5)
		(connect_pads
			(clearance 0)
		)
		(min_thickness 0.25)
		(keepout
			(tracks allowed)
			(vias allowed)
			(pads allowed)
			(copperpour allowed)
			(footprints allowed)
		)
		(placement
			(enabled no)
			(sheetname "")
		)
		(fill
			(thermal_gap 0.5)
			(thermal_bridge_width 0.5)
			(island_removal_mode 0)
		)
		(polygon
			(pts
				(xy 157.950662 -225.084386) (xy 157.950662 -225.61296) (xy 157.414722 -225.61296) (xy 157.414722 -225.084386)
			)
		)
	)
	(zone
		(layer "In2.Cu")
		(hatch none 0.5)
		(connect_pads
			(clearance 0)
		)
		(min_thickness 0.25)
		(keepout
			(tracks allowed)
			(vias allowed)
			(pads allowed)
			(copperpour allowed)
			(footprints allowed)
		)
		(placement
			(enabled no)
			(sheetname "")
		)
		(fill
			(thermal_gap 0.5)
			(thermal_bridge_width 0.5)
			(island_removal_mode 0)
		)
		(polygon
			(pts
				(xy 50.78349 -315.730382) (xy 50.78349 -315.187076) (xy 51.338226 -315.187076) (xy 51.338226 -315.730382)
			)
		)
	)
	(zone
		(layer "In2.Cu")
		(hatch none 0.5)
		(connect_pads
			(clearance 0)
		)
		(min_thickness 0.25)
		(keepout
			(tracks allowed)
			(vias allowed)
			(pads allowed)
			(copperpour allowed)
			(footprints allowed)
		)
		(placement
			(enabled no)
			(sheetname "")
		)
		(fill
			(thermal_gap 0.5)
			(thermal_bridge_width 0.5)
			(island_removal_mode 0)
		)
		(polygon
			(pts
				(xy 173.038262 -208.934812) (xy 173.038262 -209.463386) (xy 172.502322 -209.463386) (xy 172.502322 -208.934812)
			)
		)
	)
	(zone
		(layer "In2.Cu")
		(hatch none 0.5)
		(connect_pads
			(clearance 0)
		)
		(min_thickness 0.25)
		(keepout
			(tracks allowed)
			(vias allowed)
			(pads allowed)
			(copperpour allowed)
			(footprints allowed)
		)
		(placement
			(enabled no)
			(sheetname "")
		)
		(fill
			(thermal_gap 0.5)
			(thermal_bridge_width 0.5)
			(island_removal_mode 0)
		)
		(polygon
			(pts
				(xy 298.723558 -272.380456) (xy 298.723558 -271.83715) (xy 299.278294 -271.83715) (xy 299.278294 -272.380456)
			)
		)
	)
	(zone
		(layer "In2.Cu")
		(hatch none 0.5)
		(connect_pads
			(clearance 0)
		)
		(min_thickness 0.25)
		(keepout
			(tracks allowed)
			(vias allowed)
			(pads allowed)
			(copperpour allowed)
			(footprints allowed)
		)
		(placement
			(enabled no)
			(sheetname "")
		)
		(fill
			(thermal_gap 0.5)
			(thermal_bridge_width 0.5)
			(island_removal_mode 0)
		)
		(polygon
			(pts
				(xy 330.13269 -250.665234) (xy 335.40319 -250.66498) (xy 335.40319 -253.346204) (xy 331.79639 -253.346204)
				(xy 331.589888 -253.346204) (xy 331.589888 -256.97053) (xy 331.381354 -256.97053) (xy 331.381354 -257.974084)
				(xy 331.195426 -258.160012) (xy 329.19924 -260.156198) (xy 328.86142 -260.156198) (xy 323.850508 -260.156198)
				(xy 318.34328 -254.64897) (xy 318.34328 -254.210058) (xy 318.461898 -254.09144) (xy 318.832484 -254.09144)
				(xy 326.706484 -254.09144)
			)
		)
	)
	(zone
		(layer "In2.Cu")
		(hatch none 0.5)
		(connect_pads
			(clearance 0)
		)
		(min_thickness 0.25)
		(keepout
			(tracks allowed)
			(vias allowed)
			(pads allowed)
			(copperpour allowed)
			(footprints allowed)
		)
		(placement
			(enabled no)
			(sheetname "")
		)
		(fill
			(thermal_gap 0.5)
			(thermal_bridge_width 0.5)
			(island_removal_mode 0)
		)
		(polygon
			(pts
				(xy 298.698158 -218.830398) (xy 298.698158 -218.287092) (xy 299.252894 -218.287092) (xy 299.252894 -218.830398)
			)
		)
	)
	(zone
		(layer "In2.Cu")
		(hatch none 0.5)
		(connect_pads
			(clearance 0)
		)
		(min_thickness 0.25)
		(keepout
			(tracks allowed)
			(vias allowed)
			(pads allowed)
			(copperpour allowed)
			(footprints allowed)
		)
		(placement
			(enabled no)
			(sheetname "")
		)
		(fill
			(thermal_gap 0.5)
			(thermal_bridge_width 0.5)
			(island_removal_mode 0)
		)
		(polygon
			(pts
				(xy 420.97833 -208.934812) (xy 420.97833 -209.463386) (xy 420.44239 -209.463386) (xy 420.44239 -208.934812)
			)
		)
	)
	(zone
		(layer "In2.Cu")
		(hatch none 0.5)
		(connect_pads
			(clearance 0)
		)
		(min_thickness 0.25)
		(keepout
			(tracks allowed)
			(vias allowed)
			(pads allowed)
			(copperpour allowed)
			(footprints allowed)
		)
		(placement
			(enabled no)
			(sheetname "")
		)
		(fill
			(thermal_gap 0.5)
			(thermal_bridge_width 0.5)
			(island_removal_mode 0)
		)
		(polygon
			(pts
				(xy 420.97833 -235.284518) (xy 420.97833 -235.813092) (xy 420.44239 -235.813092) (xy 420.44239 -235.284518)
			)
		)
	)
	(zone
		(layer "In2.Cu")
		(hatch none 0.5)
		(connect_pads
			(clearance 0)
		)
		(min_thickness 0.25)
		(keepout
			(tracks allowed)
			(vias allowed)
			(pads allowed)
			(copperpour allowed)
			(footprints allowed)
		)
		(placement
			(enabled no)
			(sheetname "")
		)
		(fill
			(thermal_gap 0.5)
			(thermal_bridge_width 0.5)
			(island_removal_mode 0)
		)
		(polygon
			(pts
				(xy 324.814946 -260.505702) (xy 324.62089 -260.699758) (xy 324.613778 -260.70687) (xy 324.613778 -261.395972)
				(xy 328.22134 -265.003534) (xy 328.305414 -265.087608) (xy 328.355452 -265.087608) (xy 328.867008 -264.576052)
				(xy 329.11796 -264.576052) (xy 329.11796 -263.2329) (xy 328.89444 -263.2329) (xy 328.89444 -261.899908)
				(xy 329.32878 -261.899908) (xy 329.42784 -261.800848) (xy 329.42784 -260.505702)
			)
		)
	)
	(zone
		(layer "In2.Cu")
		(hatch none 0.5)
		(connect_pads
			(clearance 0)
		)
		(min_thickness 0.25)
		(keepout
			(tracks allowed)
			(vias allowed)
			(pads allowed)
			(copperpour allowed)
			(footprints allowed)
		)
		(placement
			(enabled no)
			(sheetname "")
		)
		(fill
			(thermal_gap 0.5)
			(thermal_bridge_width 0.5)
			(island_removal_mode 0)
		)
		(polygon
			(pts
				(xy 330.94168 -244.464586) (xy 321.57543 -244.46484) (xy 321.24523 -244.13464) (xy 321.24523 -243.75364)
				(xy 324.454012 -240.544858) (xy 324.74027 -240.2586) (xy 330.887832 -240.2586) (xy 330.94168 -240.312448)
			)
		)
	)
	(zone
		(layer "In2.Cu")
		(hatch none 0.5)
		(connect_pads
			(clearance 0)
		)
		(min_thickness 0.25)
		(keepout
			(tracks allowed)
			(vias allowed)
			(pads allowed)
			(copperpour allowed)
			(footprints allowed)
		)
		(placement
			(enabled no)
			(sheetname "")
		)
		(fill
			(thermal_gap 0.5)
			(thermal_bridge_width 0.5)
			(island_removal_mode 0)
		)
		(polygon
			(pts
				(xy 157.950662 -307.534564) (xy 157.950662 -308.063138) (xy 157.414722 -308.063138) (xy 157.414722 -307.534564)
			)
		)
	)
	(zone
		(layer "In2.Cu")
		(hatch none 0.5)
		(connect_pads
			(clearance 0)
		)
		(min_thickness 0.25)
		(keepout
			(tracks allowed)
			(vias allowed)
			(pads allowed)
			(copperpour allowed)
			(footprints allowed)
		)
		(placement
			(enabled no)
			(sheetname "")
		)
		(fill
			(thermal_gap 0.5)
			(thermal_bridge_width 0.5)
			(island_removal_mode 0)
		)
		(polygon
			(pts
				(xy 326.129904 -238.883952) (xy 327.606152 -237.407704) (xy 329.714352 -235.299504) (xy 330.64704 -235.29925)
				(xy 330.64704 -239.859312) (xy 330.482194 -240.024158) (xy 326.636126 -240.024412) (xy 325.757032 -240.024412)
				(xy 325.718932 -239.986312) (xy 325.718932 -239.294924)
			)
		)
	)
	(zone
		(layer "In2.Cu")
		(hatch none 0.5)
		(connect_pads
			(clearance 0)
		)
		(min_thickness 0.25)
		(keepout
			(tracks allowed)
			(vias allowed)
			(pads allowed)
			(copperpour allowed)
			(footprints allowed)
		)
		(placement
			(enabled no)
			(sheetname "")
		)
		(fill
			(thermal_gap 0.5)
			(thermal_bridge_width 0.5)
			(island_removal_mode 0)
		)
		(polygon
			(pts
				(xy 173.038262 -267.584682) (xy 173.038262 -268.113256) (xy 172.502322 -268.113256) (xy 172.04055 -268.113256)
				(xy 172.04055 -267.584682) (xy 172.502322 -267.584682)
			)
		)
	)
	(zone
		(layer "In2.Cu")
		(hatch none 0.5)
		(connect_pads
			(clearance 0)
		)
		(min_thickness 0.25)
		(keepout
			(tracks allowed)
			(vias allowed)
			(pads allowed)
			(copperpour allowed)
			(footprints allowed)
		)
		(placement
			(enabled no)
			(sheetname "")
		)
		(fill
			(thermal_gap 0.5)
			(thermal_bridge_width 0.5)
			(island_removal_mode 0)
		)
		(polygon
			(pts
				(xy 405.89073 -229.334568) (xy 405.89073 -229.863142) (xy 405.35479 -229.863142) (xy 405.35479 -229.334568)
			)
		)
	)
	(zone
		(layer "In2.Cu")
		(hatch none 0.5)
		(connect_pads
			(clearance 0)
		)
		(min_thickness 0.25)
		(keepout
			(tracks allowed)
			(vias allowed)
			(pads allowed)
			(copperpour allowed)
			(footprints allowed)
		)
		(placement
			(enabled no)
			(sheetname "")
		)
		(fill
			(thermal_gap 0.5)
			(thermal_bridge_width 0.5)
			(island_removal_mode 0)
		)
		(polygon
			(pts
				(xy 173.038262 -276.934422) (xy 173.038262 -277.462996) (xy 172.502322 -277.462996) (xy 172.502322 -276.934422)
			)
		)
	)
	(zone
		(layer "In2.Cu")
		(hatch none 0.5)
		(connect_pads
			(clearance 0)
		)
		(min_thickness 0.25)
		(keepout
			(tracks allowed)
			(vias allowed)
			(pads allowed)
			(copperpour allowed)
			(footprints allowed)
		)
		(placement
			(enabled no)
			(sheetname "")
		)
		(fill
			(thermal_gap 0.5)
			(thermal_bridge_width 0.5)
			(island_removal_mode 0)
		)
		(polygon
			(pts
				(xy 420.97833 -290.534344) (xy 420.97833 -291.062918) (xy 420.44239 -291.062918) (xy 420.44239 -290.534344)
			)
		)
	)
	(zone
		(layer "In2.Cu")
		(hatch none 0.5)
		(connect_pads
			(clearance 0)
		)
		(min_thickness 0.25)
		(keepout
			(tracks allowed)
			(vias allowed)
			(pads allowed)
			(copperpour allowed)
			(footprints allowed)
		)
		(placement
			(enabled no)
			(sheetname "")
		)
		(fill
			(thermal_gap 0.5)
			(thermal_bridge_width 0.5)
			(island_removal_mode 0)
		)
		(polygon
			(pts
				(xy 173.038262 -231.884728) (xy 173.038262 -232.413302) (xy 172.502322 -232.413302) (xy 172.502322 -231.884728)
			)
		)
	)
	(zone
		(layer "In2.Cu")
		(hatch none 0.5)
		(connect_pads
			(clearance 0)
		)
		(min_thickness 0.25)
		(keepout
			(tracks allowed)
			(vias allowed)
			(pads allowed)
			(copperpour allowed)
			(footprints allowed)
		)
		(placement
			(enabled no)
			(sheetname "")
		)
		(fill
			(thermal_gap 0.5)
			(thermal_bridge_width 0.5)
			(island_removal_mode 0)
		)
		(polygon
			(pts
				(xy 424.60926 -367.094008) (xy 424.60926 -365.697008) (xy 426.20946 -365.697008) (xy 426.20946 -367.094008)
			)
		)
	)
	(zone
		(layer "In2.Cu")
		(hatch none 0.5)
		(connect_pads
			(clearance 0)
		)
		(min_thickness 0.25)
		(keepout
			(tracks allowed)
			(vias allowed)
			(pads allowed)
			(copperpour allowed)
			(footprints allowed)
		)
		(placement
			(enabled no)
			(sheetname "")
		)
		(fill
			(thermal_gap 0.5)
			(thermal_bridge_width 0.5)
			(island_removal_mode 0)
		)
		(polygon
			(pts
				(xy 425.078398 -265.88466) (xy 425.078398 -266.413234) (xy 424.542458 -266.413234) (xy 424.542458 -265.88466)
			)
		)
	)
	(zone
		(layer "In2.Cu")
		(hatch none 0.5)
		(connect_pads
			(clearance 0)
		)
		(min_thickness 0.25)
		(keepout
			(tracks allowed)
			(vias allowed)
			(pads allowed)
			(copperpour allowed)
			(footprints allowed)
		)
		(placement
			(enabled no)
			(sheetname "")
		)
		(fill
			(thermal_gap 0.5)
			(thermal_bridge_width 0.5)
			(island_removal_mode 0)
		)
		(polygon
			(pts
				(xy 420.97833 -261.634478) (xy 420.97833 -262.163052) (xy 420.44239 -262.163052) (xy 420.44239 -261.634478)
			)
		)
	)
	(zone
		(layer "In2.Cu")
		(hatch none 0.5)
		(connect_pads
			(clearance 0)
		)
		(min_thickness 0.25)
		(keepout
			(tracks allowed)
			(vias allowed)
			(pads allowed)
			(copperpour allowed)
			(footprints allowed)
		)
		(placement
			(enabled no)
			(sheetname "")
		)
		(fill
			(thermal_gap 0.5)
			(thermal_bridge_width 0.5)
			(island_removal_mode 0)
		)
		(polygon
			(pts
				(xy 409.990798 -231.884474) (xy 409.990798 -232.413048) (xy 409.454858 -232.413048) (xy 409.454858 -231.884474)
			)
		)
	)
	(zone
		(layer "In2.Cu")
		(hatch none 0.5)
		(connect_pads
			(clearance 0)
		)
		(min_thickness 0.25)
		(keepout
			(tracks allowed)
			(vias allowed)
			(pads allowed)
			(copperpour allowed)
			(footprints allowed)
		)
		(placement
			(enabled no)
			(sheetname "")
		)
		(fill
			(thermal_gap 0.5)
			(thermal_bridge_width 0.5)
			(island_removal_mode 0)
		)
		(polygon
			(pts
				(xy 356.09276 -338.351368) (xy 356.09276 -335.153508) (xy 369.98402 -335.153508) (xy 369.98402 -338.351368)
			)
		)
	)
	(zone
		(layer "In2.Cu")
		(hatch none 0.5)
		(connect_pads
			(clearance 0)
		)
		(min_thickness 0.25)
		(keepout
			(tracks allowed)
			(vias allowed)
			(pads allowed)
			(copperpour allowed)
			(footprints allowed)
		)
		(placement
			(enabled no)
			(sheetname "")
		)
		(fill
			(thermal_gap 0.5)
			(thermal_bridge_width 0.5)
			(island_removal_mode 0)
		)
		(polygon
			(pts
				(xy 157.925262 -224.234756) (xy 157.925262 -224.76333) (xy 157.389322 -224.76333) (xy 157.389322 -224.234756)
			)
		)
	)
	(zone
		(layer "In2.Cu")
		(hatch none 0.5)
		(connect_pads
			(clearance 0)
		)
		(min_thickness 0.25)
		(keepout
			(tracks allowed)
			(vias allowed)
			(pads allowed)
			(copperpour allowed)
			(footprints allowed)
		)
		(placement
			(enabled no)
			(sheetname "")
		)
		(fill
			(thermal_gap 0.5)
			(thermal_bridge_width 0.5)
			(island_removal_mode 0)
		)
		(polygon
			(pts
				(xy 405.89073 -269.284704) (xy 405.89073 -269.813278) (xy 405.35479 -269.813278) (xy 405.35479 -269.284704)
			)
		)
	)
	(zone
		(layer "In2.Cu")
		(hatch none 0.5)
		(connect_pads
			(clearance 0)
		)
		(min_thickness 0.25)
		(keepout
			(tracks allowed)
			(vias allowed)
			(pads allowed)
			(copperpour allowed)
			(footprints allowed)
		)
		(placement
			(enabled no)
			(sheetname "")
		)
		(fill
			(thermal_gap 0.5)
			(thermal_bridge_width 0.5)
			(island_removal_mode 0)
		)
		(polygon
			(pts
				(xy 180.47208 -358.204008) (xy 180.47208 -356.934008) (xy 182.17388 -356.934008) (xy 182.17388 -358.204008)
			)
		)
	)
	(zone
		(layer "In2.Cu")
		(hatch none 0.5)
		(connect_pads
			(clearance 0)
		)
		(min_thickness 0.25)
		(keepout
			(tracks allowed)
			(vias allowed)
			(pads allowed)
			(copperpour allowed)
			(footprints allowed)
		)
		(placement
			(enabled no)
			(sheetname "")
		)
		(fill
			(thermal_gap 0.5)
			(thermal_bridge_width 0.5)
			(island_removal_mode 0)
		)
		(polygon
			(pts
				(xy 173.038262 -260.784594) (xy 173.038262 -261.313168) (xy 172.502322 -261.313168) (xy 172.502322 -260.784594)
			)
		)
	)
	(zone
		(layer "In2.Cu")
		(hatch none 0.5)
		(connect_pads
			(clearance 0)
		)
		(min_thickness 0.25)
		(keepout
			(tracks allowed)
			(vias allowed)
			(pads allowed)
			(copperpour allowed)
			(footprints allowed)
		)
		(placement
			(enabled no)
			(sheetname "")
		)
		(fill
			(thermal_gap 0.5)
			(thermal_bridge_width 0.5)
			(island_removal_mode 0)
		)
		(polygon
			(pts
				(xy 420.97833 -208.084674) (xy 420.97833 -208.613248) (xy 420.44239 -208.613248) (xy 420.44239 -208.084674)
			)
		)
	)
	(zone
		(layer "In2.Cu")
		(hatch none 0.5)
		(connect_pads
			(clearance 0)
		)
		(min_thickness 0.25)
		(keepout
			(tracks allowed)
			(vias allowed)
			(pads allowed)
			(copperpour allowed)
			(footprints allowed)
		)
		(placement
			(enabled no)
			(sheetname "")
		)
		(fill
			(thermal_gap 0.5)
			(thermal_bridge_width 0.5)
			(island_removal_mode 0)
		)
		(polygon
			(pts
				(xy 405.86533 -306.684426) (xy 405.86533 -307.213) (xy 405.32939 -307.213) (xy 404.937722 -307.213)
				(xy 404.937722 -306.397914) (xy 405.86533 -306.397914)
			)
		)
	)
	(zone
		(layer "In2.Cu")
		(hatch none 0.5)
		(connect_pads
			(clearance 0)
		)
		(min_thickness 0.25)
		(keepout
			(tracks allowed)
			(vias allowed)
			(pads allowed)
			(copperpour allowed)
			(footprints allowed)
		)
		(placement
			(enabled no)
			(sheetname "")
		)
		(fill
			(thermal_gap 0.5)
			(thermal_bridge_width 0.5)
			(island_removal_mode 0)
		)
		(polygon
			(pts
				(xy 298.698158 -285.980378) (xy 298.698158 -285.437072) (xy 299.252894 -285.437072) (xy 299.252894 -285.980378)
			)
		)
	)
	(zone
		(layer "In2.Cu")
		(hatch none 0.5)
		(connect_pads
			(clearance 0)
		)
		(min_thickness 0.25)
		(keepout
			(tracks allowed)
			(vias allowed)
			(pads allowed)
			(copperpour allowed)
			(footprints allowed)
		)
		(placement
			(enabled no)
			(sheetname "")
		)
		(fill
			(thermal_gap 0.5)
			(thermal_bridge_width 0.5)
			(island_removal_mode 0)
		)
		(polygon
			(pts
				(xy 309.68569 -232.43032) (xy 309.68569 -231.887014) (xy 309.68569 -231.71531) (xy 310.396128 -231.004872)
				(xy 310.708294 -231.004872) (xy 310.835294 -231.131872) (xy 310.835294 -232.381552) (xy 310.786526 -232.43032)
				(xy 310.521604 -232.43032) (xy 310.240426 -232.43032)
			)
		)
	)
	(zone
		(layer "In2.Cu")
		(hatch none 0.5)
		(connect_pads
			(clearance 0)
		)
		(min_thickness 0.25)
		(keepout
			(tracks allowed)
			(vias allowed)
			(pads allowed)
			(copperpour allowed)
			(footprints allowed)
		)
		(placement
			(enabled no)
			(sheetname "")
		)
		(fill
			(thermal_gap 0.5)
			(thermal_bridge_width 0.5)
			(island_removal_mode 0)
		)
		(polygon
			(pts
				(xy 420.97833 -250.584462) (xy 420.97833 -251.113036) (xy 420.44239 -251.113036) (xy 420.44239 -250.584462)
			)
		)
	)
	(zone
		(layer "In2.Cu")
		(hatch none 0.5)
		(connect_pads
			(clearance 0)
		)
		(min_thickness 0.25)
		(keepout
			(tracks allowed)
			(vias allowed)
			(pads allowed)
			(copperpour allowed)
			(footprints allowed)
		)
		(placement
			(enabled no)
			(sheetname "")
		)
		(fill
			(thermal_gap 0.5)
			(thermal_bridge_width 0.5)
			(island_removal_mode 0)
		)
		(polygon
			(pts
				(xy 173.038262 -273.534378) (xy 173.038262 -274.062952) (xy 172.502322 -274.062952) (xy 172.502322 -273.534378)
			)
		)
	)
	(zone
		(layer "In2.Cu")
		(hatch none 0.5)
		(connect_pads
			(clearance 0)
		)
		(min_thickness 0.25)
		(keepout
			(tracks allowed)
			(vias allowed)
			(pads allowed)
			(copperpour allowed)
			(footprints allowed)
		)
		(placement
			(enabled no)
			(sheetname "")
		)
		(fill
			(thermal_gap 0.5)
			(thermal_bridge_width 0.5)
			(island_removal_mode 0)
		)
		(polygon
			(pts
				(xy 173.038262 -238.684562) (xy 173.038262 -239.213136) (xy 172.502322 -239.213136) (xy 172.502322 -238.684562)
			)
		)
	)
	(zone
		(layer "In2.Cu")
		(hatch none 0.5)
		(connect_pads
			(clearance 0)
		)
		(min_thickness 0.25)
		(keepout
			(tracks allowed)
			(vias allowed)
			(pads allowed)
			(copperpour allowed)
			(footprints allowed)
		)
		(placement
			(enabled no)
			(sheetname "")
		)
		(fill
			(thermal_gap 0.5)
			(thermal_bridge_width 0.5)
			(island_removal_mode 0)
		)
		(polygon
			(pts
				(xy 50.78349 -314.03036) (xy 50.78349 -313.487054) (xy 51.338226 -313.487054) (xy 51.541934 -313.487054)
				(xy 51.781964 -313.487054) (xy 51.961034 -313.487054) (xy 51.998372 -313.524392) (xy 51.998372 -314.302394)
				(xy 51.608736 -314.302394) (xy 51.533806 -314.227464) (xy 51.338226 -314.031884) (xy 51.338226 -314.03036)
			)
		)
	)
	(zone
		(layer "In2.Cu")
		(hatch none 0.5)
		(connect_pads
			(clearance 0)
		)
		(min_thickness 0.25)
		(keepout
			(tracks allowed)
			(vias allowed)
			(pads allowed)
			(copperpour allowed)
			(footprints allowed)
		)
		(placement
			(enabled no)
			(sheetname "")
		)
		(fill
			(thermal_gap 0.5)
			(thermal_bridge_width 0.5)
			(island_removal_mode 0)
		)
		(polygon
			(pts
				(xy 173.038262 -247.184418) (xy 173.038262 -247.712992) (xy 172.502322 -247.712992) (xy 172.502322 -247.184418)
			)
		)
	)
	(zone
		(layer "In2.Cu")
		(hatch none 0.5)
		(connect_pads
			(clearance 0)
		)
		(min_thickness 0.25)
		(keepout
			(tracks allowed)
			(vias allowed)
			(pads allowed)
			(copperpour allowed)
			(footprints allowed)
		)
		(placement
			(enabled no)
			(sheetname "")
		)
		(fill
			(thermal_gap 0.5)
			(thermal_bridge_width 0.5)
			(island_removal_mode 0)
		)
		(polygon
			(pts
				(xy 405.86533 -304.984404) (xy 405.86533 -305.512978) (xy 405.32939 -305.512978) (xy 405.32939 -304.984404)
			)
		)
	)
	(zone
		(layer "In2.Cu")
		(hatch none 0.5)
		(connect_pads
			(clearance 0)
		)
		(min_thickness 0.25)
		(keepout
			(tracks allowed)
			(vias allowed)
			(pads allowed)
			(copperpour allowed)
			(footprints allowed)
		)
		(placement
			(enabled no)
			(sheetname "")
		)
		(fill
			(thermal_gap 0.5)
			(thermal_bridge_width 0.5)
			(island_removal_mode 0)
		)
		(polygon
			(pts
				(xy 93.13164 -338.392008) (xy 93.13164 -335.222088) (xy 97.54362 -335.222088) (xy 97.54362 -338.392008)
			)
		)
	)
	(zone
		(layer "In2.Cu")
		(hatch none 0.5)
		(connect_pads
			(clearance 0)
		)
		(min_thickness 0.25)
		(keepout
			(tracks allowed)
			(vias allowed)
			(pads allowed)
			(copperpour allowed)
			(footprints allowed)
		)
		(placement
			(enabled no)
			(sheetname "")
		)
		(fill
			(thermal_gap 0.5)
			(thermal_bridge_width 0.5)
			(island_removal_mode 0)
		)
		(polygon
			(pts
				(xy 173.038262 -315.184536) (xy 173.038262 -315.71311) (xy 172.502322 -315.71311) (xy 172.502322 -315.184536)
			)
		)
	)
	(zone
		(layer "In2.Cu")
		(hatch none 0.5)
		(connect_pads
			(clearance 0)
		)
		(min_thickness 0.25)
		(keepout
			(tracks allowed)
			(vias allowed)
			(pads allowed)
			(copperpour allowed)
			(footprints allowed)
		)
		(placement
			(enabled no)
			(sheetname "")
		)
		(fill
			(thermal_gap 0.5)
			(thermal_bridge_width 0.5)
			(island_removal_mode 0)
		)
		(polygon
			(pts
				(xy 294.59809 -268.130274) (xy 294.59809 -267.586968) (xy 295.152826 -267.586968) (xy 295.152826 -268.130274)
			)
		)
	)
	(zone
		(layer "In2.Cu")
		(hatch none 0.5)
		(connect_pads
			(clearance 0)
		)
		(min_thickness 0.25)
		(keepout
			(tracks allowed)
			(vias allowed)
			(pads allowed)
			(copperpour allowed)
			(footprints allowed)
		)
		(placement
			(enabled no)
			(sheetname "")
		)
		(fill
			(thermal_gap 0.5)
			(thermal_bridge_width 0.5)
			(island_removal_mode 0)
		)
		(polygon
			(pts
				(xy 420.97833 -214.034624) (xy 420.97833 -214.563198) (xy 420.44239 -214.563198) (xy 420.44239 -214.034624)
			)
		)
	)
	(zone
		(layer "In2.Cu")
		(hatch none 0.5)
		(connect_pads
			(clearance 0)
		)
		(min_thickness 0.25)
		(keepout
			(tracks allowed)
			(vias allowed)
			(pads allowed)
			(copperpour allowed)
			(footprints allowed)
		)
		(placement
			(enabled no)
			(sheetname "")
		)
		(fill
			(thermal_gap 0.5)
			(thermal_bridge_width 0.5)
			(island_removal_mode 0)
		)
		(polygon
			(pts
				(xy 284.80512 -367.795048) (xy 284.80512 -364.838488) (xy 289.08502 -364.838488) (xy 289.08502 -367.795048)
			)
		)
	)
	(zone
		(layer "In2.Cu")
		(hatch none 0.5)
		(connect_pads
			(clearance 0)
		)
		(min_thickness 0.25)
		(keepout
			(tracks allowed)
			(vias allowed)
			(pads allowed)
			(copperpour allowed)
			(footprints allowed)
		)
		(placement
			(enabled no)
			(sheetname "")
		)
		(fill
			(thermal_gap 0.5)
			(thermal_bridge_width 0.5)
			(island_removal_mode 0)
		)
		(polygon
			(pts
				(xy 173.038262 -309.234586) (xy 173.038262 -309.76316) (xy 172.502322 -309.76316) (xy 172.502322 -309.234586)
			)
		)
	)
	(zone
		(layer "In2.Cu")
		(hatch none 0.5)
		(connect_pads
			(clearance 0)
		)
		(min_thickness 0.25)
		(keepout
			(tracks allowed)
			(vias allowed)
			(pads allowed)
			(copperpour allowed)
			(footprints allowed)
		)
		(placement
			(enabled no)
			(sheetname "")
		)
		(fill
			(thermal_gap 0.5)
			(thermal_bridge_width 0.5)
			(island_removal_mode 0)
		)
		(polygon
			(pts
				(xy 157.950662 -226.784408) (xy 157.950662 -227.312982) (xy 157.414722 -227.312982) (xy 157.414722 -226.784408)
			)
		)
	)
	(zone
		(layer "In2.Cu")
		(hatch none 0.5)
		(connect_pads
			(clearance 0)
		)
		(min_thickness 0.25)
		(keepout
			(tracks allowed)
			(vias allowed)
			(pads allowed)
			(copperpour allowed)
			(footprints allowed)
		)
		(placement
			(enabled no)
			(sheetname "")
		)
		(fill
			(thermal_gap 0.5)
			(thermal_bridge_width 0.5)
			(island_removal_mode 0)
		)
		(polygon
			(pts
				(xy 420.97833 -282.884372) (xy 420.97833 -283.412946) (xy 420.44239 -283.412946) (xy 420.44239 -282.884372)
			)
		)
	)
	(zone
		(layer "In2.Cu")
		(hatch none 0.5)
		(connect_pads
			(clearance 0)
		)
		(min_thickness 0.25)
		(keepout
			(tracks allowed)
			(vias allowed)
			(pads allowed)
			(copperpour allowed)
			(footprints allowed)
		)
		(placement
			(enabled no)
			(sheetname "")
		)
		(fill
			(thermal_gap 0.5)
			(thermal_bridge_width 0.5)
			(island_removal_mode 0)
		)
		(polygon
			(pts
				(xy 84.78774 -341.831168) (xy 84.78774 -338.696808) (xy 89.28354 -338.696808) (xy 89.28354 -341.831168)
			)
		)
	)
	(zone
		(layer "In2.Cu")
		(hatch none 0.5)
		(connect_pads
			(clearance 0)
		)
		(min_thickness 0.25)
		(keepout
			(tracks allowed)
			(vias allowed)
			(pads allowed)
			(copperpour allowed)
			(footprints allowed)
		)
		(placement
			(enabled no)
			(sheetname "")
		)
		(fill
			(thermal_gap 0.5)
			(thermal_bridge_width 0.5)
			(island_removal_mode 0)
		)
		(polygon
			(pts
				(xy 82.856578 -244.870986) (xy 72.81037 -244.87124) (xy 72.604376 -245.077234) (xy 72.604376 -245.890034)
				(xy 73.315576 -245.890034) (xy 76.28763 -248.861834) (xy 77.58303 -248.861834) (xy 77.65923 -248.938034)
				(xy 77.65923 -248.96064) (xy 78.24343 -249.54484) (xy 78.868016 -249.54484) (xy 79.621634 -250.298458)
				(xy 84.234528 -250.298204) (xy 84.233004 -250.29668) (xy 84.233004 -248.89587) (xy 84.17052 -248.833386)
				(xy 83.741768 -248.833386) (xy 83.64728 -248.738898) (xy 83.64728 -247.556274) (xy 83.444842 -247.353836)
				(xy 83.11261 -247.353836) (xy 83.01228 -247.253506) (xy 83.01228 -245.026688)
			)
		)
	)
	(zone
		(layer "In2.Cu")
		(hatch none 0.5)
		(connect_pads
			(clearance 0)
		)
		(min_thickness 0.25)
		(keepout
			(tracks allowed)
			(vias allowed)
			(pads allowed)
			(copperpour allowed)
			(footprints allowed)
		)
		(placement
			(enabled no)
			(sheetname "")
		)
		(fill
			(thermal_gap 0.5)
			(thermal_bridge_width 0.5)
			(island_removal_mode 0)
		)
		(polygon
			(pts
				(xy 420.97833 -285.434278) (xy 420.97833 -285.962852) (xy 420.44239 -285.962852) (xy 420.44239 -285.434278)
			)
		)
	)
	(zone
		(layer "In2.Cu")
		(hatch none 0.5)
		(connect_pads
			(clearance 0)
		)
		(min_thickness 0.25)
		(keepout
			(tracks allowed)
			(vias allowed)
			(pads allowed)
			(copperpour allowed)
			(footprints allowed)
		)
		(placement
			(enabled no)
			(sheetname "")
		)
		(fill
			(thermal_gap 0.5)
			(thermal_bridge_width 0.5)
			(island_removal_mode 0)
		)
		(polygon
			(pts
				(xy 173.038262 -306.684426) (xy 173.038262 -307.213) (xy 172.502322 -307.213) (xy 172.502322 -306.684426)
			)
		)
	)
	(zone
		(layer "In2.Cu")
		(hatch none 0.5)
		(connect_pads
			(clearance 0)
		)
		(min_thickness 0.25)
		(keepout
			(tracks allowed)
			(vias allowed)
			(pads allowed)
			(copperpour allowed)
			(footprints allowed)
		)
		(placement
			(enabled no)
			(sheetname "")
		)
		(fill
			(thermal_gap 0.5)
			(thermal_bridge_width 0.5)
			(island_removal_mode 0)
		)
		(polygon
			(pts
				(xy 157.950662 -229.334822) (xy 157.950662 -229.863396) (xy 157.414722 -229.863396) (xy 157.414722 -229.334822)
			)
		)
	)
	(zone
		(layer "In2.Cu")
		(hatch none 0.5)
		(connect_pads
			(clearance 0)
		)
		(min_thickness 0.25)
		(keepout
			(tracks allowed)
			(vias allowed)
			(pads allowed)
			(copperpour allowed)
			(footprints allowed)
		)
		(placement
			(enabled no)
			(sheetname "")
		)
		(fill
			(thermal_gap 0.5)
			(thermal_bridge_width 0.5)
			(island_removal_mode 0)
		)
		(polygon
			(pts
				(xy 420.97833 -232.734866) (xy 420.97833 -233.26344) (xy 420.44239 -233.26344) (xy 420.44239 -232.734866)
			)
		)
	)
	(zone
		(layer "In2.Cu")
		(hatch none 0.5)
		(connect_pads
			(clearance 0)
		)
		(min_thickness 0.25)
		(keepout
			(tracks allowed)
			(vias allowed)
			(pads allowed)
			(copperpour allowed)
			(footprints allowed)
		)
		(placement
			(enabled no)
			(sheetname "")
		)
		(fill
			(thermal_gap 0.5)
			(thermal_bridge_width 0.5)
			(island_removal_mode 0)
		)
		(polygon
			(pts
				(xy 157.950662 -229.334568) (xy 157.950662 -229.863142) (xy 157.414722 -229.863142) (xy 157.414722 -229.334568)
			)
		)
	)
	(zone
		(layer "In2.Cu")
		(hatch none 0.5)
		(connect_pads
			(clearance 0)
		)
		(min_thickness 0.25)
		(keepout
			(tracks allowed)
			(vias allowed)
			(pads allowed)
			(copperpour allowed)
			(footprints allowed)
		)
		(placement
			(enabled no)
			(sheetname "")
		)
		(fill
			(thermal_gap 0.5)
			(thermal_bridge_width 0.5)
			(island_removal_mode 0)
		)
		(polygon
			(pts
				(xy 173.038262 -263.3345) (xy 173.038262 -263.863074) (xy 172.502322 -263.863074) (xy 172.502322 -263.3345)
			)
		)
	)
	(zone
		(layer "In2.Cu")
		(hatch none 0.5)
		(connect_pads
			(clearance 0)
		)
		(min_thickness 0.25)
		(keepout
			(tracks allowed)
			(vias allowed)
			(pads allowed)
			(copperpour allowed)
			(footprints allowed)
		)
		(placement
			(enabled no)
			(sheetname "")
		)
		(fill
			(thermal_gap 0.5)
			(thermal_bridge_width 0.5)
			(island_removal_mode 0)
		)
		(polygon
			(pts
				(xy 405.86533 -223.384618) (xy 405.86533 -223.913192) (xy 405.32939 -223.913192) (xy 405.32939 -223.384618)
			)
		)
	)
	(zone
		(layer "In2.Cu")
		(hatch none 0.5)
		(connect_pads
			(clearance 0)
		)
		(min_thickness 0.25)
		(keepout
			(tracks allowed)
			(vias allowed)
			(pads allowed)
			(copperpour allowed)
			(footprints allowed)
		)
		(placement
			(enabled no)
			(sheetname "")
		)
		(fill
			(thermal_gap 0.5)
			(thermal_bridge_width 0.5)
			(island_removal_mode 0)
		)
		(polygon
			(pts
				(xy 65.84569 -228.180392) (xy 65.84569 -227.637086) (xy 66.400426 -227.637086) (xy 66.400426 -228.180392)
			)
		)
	)
	(zone
		(layer "In2.Cu")
		(hatch none 0.5)
		(connect_pads
			(clearance 0)
		)
		(min_thickness 0.25)
		(keepout
			(tracks allowed)
			(vias allowed)
			(pads allowed)
			(copperpour allowed)
			(footprints allowed)
		)
		(placement
			(enabled no)
			(sheetname "")
		)
		(fill
			(thermal_gap 0.5)
			(thermal_bridge_width 0.5)
			(island_removal_mode 0)
		)
		(polygon
			(pts
				(xy 313.785758 -225.630232) (xy 313.785758 -225.086926) (xy 314.340494 -225.086926) (xy 314.674504 -225.086926)
				(xy 314.674504 -225.630232) (xy 314.340494 -225.630232)
			)
		)
	)
	(zone
		(layer "In2.Cu")
		(hatch none 0.5)
		(connect_pads
			(clearance 0)
		)
		(min_thickness 0.25)
		(keepout
			(tracks allowed)
			(vias allowed)
			(pads allowed)
			(copperpour allowed)
			(footprints allowed)
		)
		(placement
			(enabled no)
			(sheetname "")
		)
		(fill
			(thermal_gap 0.5)
			(thermal_bridge_width 0.5)
			(island_removal_mode 0)
		)
		(polygon
			(pts
				(xy 173.038262 -277.78456) (xy 173.038262 -278.313134) (xy 172.502322 -278.313134) (xy 172.502322 -277.78456)
			)
		)
	)
	(zone
		(layer "In2.Cu")
		(hatch none 0.5)
		(connect_pads
			(clearance 0)
		)
		(min_thickness 0.25)
		(keepout
			(tracks allowed)
			(vias allowed)
			(pads allowed)
			(copperpour allowed)
			(footprints allowed)
		)
		(placement
			(enabled no)
			(sheetname "")
		)
		(fill
			(thermal_gap 0.5)
			(thermal_bridge_width 0.5)
			(island_removal_mode 0)
		)
		(polygon
			(pts
				(xy 50.75809 -236.680248) (xy 50.75809 -236.136942) (xy 51.312826 -236.136942) (xy 51.312826 -236.680248)
			)
		)
	)
	(zone
		(layer "In2.Cu")
		(hatch none 0.5)
		(connect_pads
			(clearance 0)
		)
		(min_thickness 0.25)
		(keepout
			(tracks allowed)
			(vias allowed)
			(pads allowed)
			(copperpour allowed)
			(footprints allowed)
		)
		(placement
			(enabled no)
			(sheetname "")
		)
		(fill
			(thermal_gap 0.5)
			(thermal_bridge_width 0.5)
			(island_removal_mode 0)
		)
		(polygon
			(pts
				(xy 173.038262 -239.5347) (xy 173.038262 -240.063274) (xy 172.502322 -240.063274) (xy 172.502322 -239.5347)
			)
		)
	)
	(zone
		(layer "In2.Cu")
		(hatch none 0.5)
		(connect_pads
			(clearance 0)
		)
		(min_thickness 0.25)
		(keepout
			(tracks allowed)
			(vias allowed)
			(pads allowed)
			(copperpour allowed)
			(footprints allowed)
		)
		(placement
			(enabled no)
			(sheetname "")
		)
		(fill
			(thermal_gap 0.5)
			(thermal_bridge_width 0.5)
			(island_removal_mode 0)
		)
		(polygon
			(pts
				(xy 405.89073 -305.834542) (xy 405.89073 -306.363116) (xy 405.35479 -306.363116) (xy 405.35479 -305.834542)
			)
		)
	)
	(zone
		(layer "In2.Cu")
		(hatch none 0.5)
		(connect_pads
			(clearance 0)
		)
		(min_thickness 0.25)
		(keepout
			(tracks allowed)
			(vias allowed)
			(pads allowed)
			(copperpour allowed)
			(footprints allowed)
		)
		(placement
			(enabled no)
			(sheetname "")
		)
		(fill
			(thermal_gap 0.5)
			(thermal_bridge_width 0.5)
			(island_removal_mode 0)
		)
		(polygon
			(pts
				(xy 405.86533 -303.284382) (xy 405.86533 -303.812956) (xy 405.32939 -303.812956) (xy 405.32939 -303.284382)
			)
		)
	)
	(zone
		(layer "In2.Cu")
		(hatch none 0.5)
		(connect_pads
			(clearance 0)
		)
		(min_thickness 0.25)
		(keepout
			(tracks allowed)
			(vias allowed)
			(pads allowed)
			(copperpour allowed)
			(footprints allowed)
		)
		(placement
			(enabled no)
			(sheetname "")
		)
		(fill
			(thermal_gap 0.5)
			(thermal_bridge_width 0.5)
			(island_removal_mode 0)
		)
		(polygon
			(pts
				(xy 405.89073 -270.134588) (xy 405.89073 -270.663162) (xy 405.35479 -270.663162) (xy 405.35479 -270.134588)
			)
		)
	)
	(zone
		(layer "In2.Cu")
		(hatch none 0.5)
		(connect_pads
			(clearance 0)
		)
		(min_thickness 0.25)
		(keepout
			(tracks allowed)
			(vias allowed)
			(pads allowed)
			(copperpour allowed)
			(footprints allowed)
		)
		(placement
			(enabled no)
			(sheetname "")
		)
		(fill
			(thermal_gap 0.5)
			(thermal_bridge_width 0.5)
			(island_removal_mode 0)
		)
		(polygon
			(pts
				(xy 420.97833 -222.534734) (xy 420.97833 -223.063308) (xy 420.44239 -223.063308) (xy 420.44239 -222.534734)
			)
		)
	)
	(zone
		(layer "In2.Cu")
		(hatch none 0.5)
		(connect_pads
			(clearance 0)
		)
		(min_thickness 0.25)
		(keepout
			(tracks allowed)
			(vias allowed)
			(pads allowed)
			(copperpour allowed)
			(footprints allowed)
		)
		(placement
			(enabled no)
			(sheetname "")
		)
		(fill
			(thermal_gap 0.5)
			(thermal_bridge_width 0.5)
			(island_removal_mode 0)
		)
		(polygon
			(pts
				(xy 157.925262 -224.234502) (xy 157.925262 -224.763076) (xy 157.389322 -224.763076) (xy 157.2006 -224.763076)
				(xy 157.152848 -224.715324) (xy 157.152848 -224.308416) (xy 157.226762 -224.234502) (xy 157.389322 -224.234502)
			)
		)
	)
	(zone
		(layer "In2.Cu")
		(hatch none 0.5)
		(connect_pads
			(clearance 0)
		)
		(min_thickness 0.25)
		(keepout
			(tracks allowed)
			(vias allowed)
			(pads allowed)
			(copperpour allowed)
			(footprints allowed)
		)
		(placement
			(enabled no)
			(sheetname "")
		)
		(fill
			(thermal_gap 0.5)
			(thermal_bridge_width 0.5)
			(island_removal_mode 0)
		)
		(polygon
			(pts
				(xy 405.89073 -231.03459) (xy 405.89073 -231.563164) (xy 405.35479 -231.563164) (xy 405.35479 -231.03459)
			)
		)
	)
	(zone
		(layer "In2.Cu")
		(hatch none 0.5)
		(connect_pads
			(clearance 0)
		)
		(min_thickness 0.25)
		(keepout
			(tracks allowed)
			(vias allowed)
			(pads allowed)
			(copperpour allowed)
			(footprints allowed)
		)
		(placement
			(enabled no)
			(sheetname "")
		)
		(fill
			(thermal_gap 0.5)
			(thermal_bridge_width 0.5)
			(island_removal_mode 0)
		)
		(polygon
			(pts
				(xy 173.038262 -296.484548) (xy 173.038262 -297.013122) (xy 172.502322 -297.013122) (xy 172.502322 -296.484548)
			)
		)
	)
	(zone
		(layer "In2.Cu")
		(hatch none 0.5)
		(connect_pads
			(clearance 0)
		)
		(min_thickness 0.25)
		(keepout
			(tracks allowed)
			(vias allowed)
			(pads allowed)
			(copperpour allowed)
			(footprints allowed)
		)
		(placement
			(enabled no)
			(sheetname "")
		)
		(fill
			(thermal_gap 0.5)
			(thermal_bridge_width 0.5)
			(island_removal_mode 0)
		)
		(polygon
			(pts
				(xy 50.75809 -251.980446) (xy 50.75809 -251.43714) (xy 51.312826 -251.43714) (xy 51.312826 -251.980446)
			)
		)
	)
	(zone
		(layer "In2.Cu")
		(hatch none 0.5)
		(connect_pads
			(clearance 0)
		)
		(min_thickness 0.25)
		(keepout
			(tracks allowed)
			(vias allowed)
			(pads allowed)
			(copperpour allowed)
			(footprints allowed)
		)
		(placement
			(enabled no)
			(sheetname "")
		)
		(fill
			(thermal_gap 0.5)
			(thermal_bridge_width 0.5)
			(island_removal_mode 0)
		)
		(polygon
			(pts
				(xy 420.97833 -291.384482) (xy 420.97833 -291.913056) (xy 420.44239 -291.913056) (xy 420.44239 -291.384482)
			)
		)
	)
	(zone
		(layer "In2.Cu")
		(hatch none 0.5)
		(connect_pads
			(clearance 0)
		)
		(min_thickness 0.25)
		(keepout
			(tracks allowed)
			(vias allowed)
			(pads allowed)
			(copperpour allowed)
			(footprints allowed)
		)
		(placement
			(enabled no)
			(sheetname "")
		)
		(fill
			(thermal_gap 0.5)
			(thermal_bridge_width 0.5)
			(island_removal_mode 0)
		)
		(polygon
			(pts
				(xy 420.97833 -231.884728) (xy 420.97833 -232.413302) (xy 420.44239 -232.413302) (xy 420.44239 -231.884728)
			)
		)
	)
	(zone
		(layer "In2.Cu")
		(hatch none 0.5)
		(connect_pads
			(clearance 0)
		)
		(min_thickness 0.25)
		(keepout
			(tracks allowed)
			(vias allowed)
			(pads allowed)
			(copperpour allowed)
			(footprints allowed)
		)
		(placement
			(enabled no)
			(sheetname "")
		)
		(fill
			(thermal_gap 0.5)
			(thermal_bridge_width 0.5)
			(island_removal_mode 0)
		)
		(polygon
			(pts
				(xy 386.79374 -347.749368) (xy 386.79374 -343.731088) (xy 381.50546 -343.731088) (xy 381.50546 -347.749368)
			)
		)
	)
	(zone
		(layer "In2.Cu")
		(hatch none 0.5)
		(connect_pads
			(clearance 0)
		)
		(min_thickness 0.25)
		(keepout
			(tracks allowed)
			(vias allowed)
			(pads allowed)
			(copperpour allowed)
			(footprints allowed)
		)
		(placement
			(enabled no)
			(sheetname "")
		)
		(fill
			(thermal_gap 0.5)
			(thermal_bridge_width 0.5)
			(island_removal_mode 0)
		)
		(polygon
			(pts
				(xy 420.97833 -283.73451) (xy 420.97833 -284.263084) (xy 420.44239 -284.263084) (xy 420.44239 -283.73451)
			)
		)
	)
	(zone
		(layer "In2.Cu")
		(hatch none 0.5)
		(connect_pads
			(clearance 0)
		)
		(min_thickness 0.25)
		(keepout
			(tracks allowed)
			(vias allowed)
			(pads allowed)
			(copperpour allowed)
			(footprints allowed)
		)
		(placement
			(enabled no)
			(sheetname "")
		)
		(fill
			(thermal_gap 0.5)
			(thermal_bridge_width 0.5)
			(island_removal_mode 0)
		)
		(polygon
			(pts
				(xy 173.038262 -242.93449) (xy 173.038262 -243.463064) (xy 172.502322 -243.463064) (xy 172.502322 -242.93449)
			)
		)
	)
	(zone
		(layer "In2.Cu")
		(hatch none 0.5)
		(connect_pads
			(clearance 0)
		)
		(min_thickness 0.25)
		(keepout
			(tracks allowed)
			(vias allowed)
			(pads allowed)
			(copperpour allowed)
			(footprints allowed)
		)
		(placement
			(enabled no)
			(sheetname "")
		)
		(fill
			(thermal_gap 0.5)
			(thermal_bridge_width 0.5)
			(island_removal_mode 0)
		)
		(polygon
			(pts
				(xy 420.97833 -237.834678) (xy 420.97833 -238.363252) (xy 420.44239 -238.363252) (xy 420.44239 -237.834678)
			)
		)
	)
	(zone
		(layer "In2.Cu")
		(hatch none 0.5)
		(connect_pads
			(clearance 0)
		)
		(min_thickness 0.25)
		(keepout
			(tracks allowed)
			(vias allowed)
			(pads allowed)
			(copperpour allowed)
			(footprints allowed)
		)
		(placement
			(enabled no)
			(sheetname "")
		)
		(fill
			(thermal_gap 0.5)
			(thermal_bridge_width 0.5)
			(island_removal_mode 0)
		)
		(polygon
			(pts
				(xy 148.81606 -404.853648) (xy 148.81606 -402.971508) (xy 150.18512 -402.971508) (xy 150.18512 -404.853648)
			)
		)
	)
	(zone
		(layer "In2.Cu")
		(hatch none 0.5)
		(connect_pads
			(clearance 0)
		)
		(min_thickness 0.25)
		(keepout
			(tracks allowed)
			(vias allowed)
			(pads allowed)
			(copperpour allowed)
			(footprints allowed)
		)
		(placement
			(enabled no)
			(sheetname "")
		)
		(fill
			(thermal_gap 0.5)
			(thermal_bridge_width 0.5)
			(island_removal_mode 0)
		)
		(polygon
			(pts
				(xy 50.75809 -220.53042) (xy 50.75809 -219.987114) (xy 51.312826 -219.987114) (xy 51.312826 -220.53042)
			)
		)
	)
	(zone
		(layer "In2.Cu")
		(hatch none 0.5)
		(connect_pads
			(clearance 0)
		)
		(min_thickness 0.25)
		(keepout
			(tracks allowed)
			(vias allowed)
			(pads allowed)
			(copperpour allowed)
			(footprints allowed)
		)
		(placement
			(enabled no)
			(sheetname "")
		)
		(fill
			(thermal_gap 0.5)
			(thermal_bridge_width 0.5)
			(island_removal_mode 0)
		)
		(polygon
			(pts
				(xy 298.723558 -297.030394) (xy 298.723558 -296.487088) (xy 299.278294 -296.487088) (xy 299.278294 -297.030394)
			)
		)
	)
	(zone
		(layer "In2.Cu")
		(hatch none 0.5)
		(connect_pads
			(clearance 0)
		)
		(min_thickness 0.25)
		(keepout
			(tracks allowed)
			(vias allowed)
			(pads allowed)
			(copperpour allowed)
			(footprints allowed)
		)
		(placement
			(enabled no)
			(sheetname "")
		)
		(fill
			(thermal_gap 0.5)
			(thermal_bridge_width 0.5)
			(island_removal_mode 0)
		)
		(polygon
			(pts
				(xy 173.038262 -222.534734) (xy 173.038262 -223.063308) (xy 172.502322 -223.063308) (xy 172.502322 -222.534734)
			)
		)
	)
	(zone
		(layer "In2.Cu")
		(hatch none 0.5)
		(connect_pads
			(clearance 0)
		)
		(min_thickness 0.25)
		(keepout
			(tracks allowed)
			(vias allowed)
			(pads allowed)
			(copperpour allowed)
			(footprints allowed)
		)
		(placement
			(enabled no)
			(sheetname "")
		)
		(fill
			(thermal_gap 0.5)
			(thermal_bridge_width 0.5)
			(island_removal_mode 0)
		)
		(polygon
			(pts
				(xy 420.97833 -242.93449) (xy 420.97833 -243.463064) (xy 420.44239 -243.463064) (xy 420.44239 -242.93449)
			)
		)
	)
	(zone
		(layer "In2.Cu")
		(hatch none 0.5)
		(connect_pads
			(clearance 0)
		)
		(min_thickness 0.25)
		(keepout
			(tracks allowed)
			(vias allowed)
			(pads allowed)
			(copperpour allowed)
			(footprints allowed)
		)
		(placement
			(enabled no)
			(sheetname "")
		)
		(fill
			(thermal_gap 0.5)
			(thermal_bridge_width 0.5)
			(island_removal_mode 0)
		)
		(polygon
			(pts
				(xy 61.745622 -232.43032) (xy 61.745622 -231.887014) (xy 61.745622 -231.71531) (xy 62.45606 -231.004872)
				(xy 62.768226 -231.004872) (xy 62.895226 -231.131872) (xy 62.895226 -232.381552) (xy 62.846458 -232.43032)
				(xy 62.581536 -232.43032) (xy 62.300358 -232.43032)
			)
		)
	)
	(zone
		(layer "In2.Cu")
		(hatch none 0.5)
		(connect_pads
			(clearance 0)
		)
		(min_thickness 0.25)
		(keepout
			(tracks allowed)
			(vias allowed)
			(pads allowed)
			(copperpour allowed)
			(footprints allowed)
		)
		(placement
			(enabled no)
			(sheetname "")
		)
		(fill
			(thermal_gap 0.5)
			(thermal_bridge_width 0.5)
			(island_removal_mode 0)
		)
		(polygon
			(pts
				(xy 156.89326 -404.853648) (xy 156.89326 -402.971508) (xy 158.26232 -402.971508) (xy 158.26232 -404.853648)
			)
		)
	)
	(zone
		(layer "In2.Cu")
		(hatch none 0.5)
		(connect_pads
			(clearance 0)
		)
		(min_thickness 0.25)
		(keepout
			(tracks allowed)
			(vias allowed)
			(pads allowed)
			(copperpour allowed)
			(footprints allowed)
		)
		(placement
			(enabled no)
			(sheetname "")
		)
		(fill
			(thermal_gap 0.5)
			(thermal_bridge_width 0.5)
			(island_removal_mode 0)
		)
		(polygon
			(pts
				(xy 76.874878 -260.505702) (xy 76.680822 -260.699758) (xy 76.67371 -260.70687) (xy 76.67371 -261.395972)
				(xy 80.281272 -265.003534) (xy 80.365346 -265.087608) (xy 80.415384 -265.087608) (xy 80.92694 -264.576052)
				(xy 81.15808 -264.576052) (xy 81.15808 -263.2329) (xy 80.95488 -263.2329) (xy 80.95488 -261.899908)
				(xy 81.262474 -261.899908) (xy 81.378806 -261.783576) (xy 81.378806 -260.505702)
			)
		)
	)
	(zone
		(layer "In2.Cu")
		(hatch none 0.5)
		(connect_pads
			(clearance 0)
		)
		(min_thickness 0.25)
		(keepout
			(tracks allowed)
			(vias allowed)
			(pads allowed)
			(copperpour allowed)
			(footprints allowed)
		)
		(placement
			(enabled no)
			(sheetname "")
		)
		(fill
			(thermal_gap 0.5)
			(thermal_bridge_width 0.5)
			(island_removal_mode 0)
		)
		(polygon
			(pts
				(xy 40.19042 -358.503728) (xy 40.19042 -357.055928) (xy 42.44594 -357.055928) (xy 42.44594 -358.503728)
			)
		)
	)
	(zone
		(layer "In2.Cu")
		(hatch none 0.5)
		(connect_pads
			(clearance 0)
		)
		(min_thickness 0.25)
		(keepout
			(tracks allowed)
			(vias allowed)
			(pads allowed)
			(copperpour allowed)
			(footprints allowed)
		)
		(placement
			(enabled no)
			(sheetname "")
		)
		(fill
			(thermal_gap 0.5)
			(thermal_bridge_width 0.5)
			(island_removal_mode 0)
		)
		(polygon
			(pts
				(xy 157.925262 -227.634546) (xy 157.925262 -228.16312) (xy 157.389322 -228.16312) (xy 157.389322 -227.634546)
			)
		)
	)
	(zone
		(layer "In2.Cu")
		(hatch none 0.5)
		(connect_pads
			(clearance 0)
		)
		(min_thickness 0.25)
		(keepout
			(tracks allowed)
			(vias allowed)
			(pads allowed)
			(copperpour allowed)
			(footprints allowed)
		)
		(placement
			(enabled no)
			(sheetname "")
		)
		(fill
			(thermal_gap 0.5)
			(thermal_bridge_width 0.5)
			(island_removal_mode 0)
		)
		(polygon
			(pts
				(xy 425.078398 -244.634512) (xy 425.078398 -245.163086) (xy 424.542458 -245.163086) (xy 424.542458 -244.634512)
			)
		)
	)
	(zone
		(layer "In2.Cu")
		(hatch none 0.5)
		(connect_pads
			(clearance 0)
		)
		(min_thickness 0.25)
		(keepout
			(tracks allowed)
			(vias allowed)
			(pads allowed)
			(copperpour allowed)
			(footprints allowed)
		)
		(placement
			(enabled no)
			(sheetname "")
		)
		(fill
			(thermal_gap 0.5)
			(thermal_bridge_width 0.5)
			(island_removal_mode 0)
		)
		(polygon
			(pts
				(xy 157.950662 -224.234502) (xy 157.950662 -224.763076) (xy 157.414722 -224.763076) (xy 157.414722 -224.234502)
			)
		)
	)
	(zone
		(layer "In2.Cu")
		(hatch none 0.5)
		(connect_pads
			(clearance 0)
		)
		(min_thickness 0.25)
		(keepout
			(tracks allowed)
			(vias allowed)
			(pads allowed)
			(copperpour allowed)
			(footprints allowed)
		)
		(placement
			(enabled no)
			(sheetname "")
		)
		(fill
			(thermal_gap 0.5)
			(thermal_bridge_width 0.5)
			(island_removal_mode 0)
		)
		(polygon
			(pts
				(xy 909.769834 -68.766944) (xy 910.463254 -68.073524) (xy 927.92931 -68.073524) (xy 930.11625 -70.260464)
				(xy 930.11625 -85.51037) (xy 912.490174 -85.51037) (xy 911.455378 -84.47532) (xy 911.455378 -70.853808)
				(xy 909.769834 -69.168264)
			)
		)
	)
	(zone
		(layer "In2.Cu")
		(hatch none 0.5)
		(connect_pads
			(clearance 0)
		)
		(min_thickness 0.25)
		(keepout
			(tracks allowed)
			(vias allowed)
			(pads allowed)
			(copperpour allowed)
			(footprints allowed)
		)
		(placement
			(enabled no)
			(sheetname "")
		)
		(fill
			(thermal_gap 0.5)
			(thermal_bridge_width 0.5)
			(island_removal_mode 0)
		)
		(polygon
			(pts
				(xy 330.796646 -244.870986) (xy 320.750438 -244.87124) (xy 320.544444 -245.077234) (xy 320.544444 -245.890034)
				(xy 321.255644 -245.890034) (xy 324.227698 -248.861834) (xy 325.523098 -248.861834) (xy 325.599298 -248.938034)
				(xy 325.599298 -248.96064) (xy 326.183498 -249.54484) (xy 326.808084 -249.54484) (xy 327.561702 -250.298458)
				(xy 332.174596 -250.298204) (xy 332.173072 -250.29668) (xy 332.173072 -248.89587) (xy 332.110588 -248.833386)
				(xy 331.681836 -248.833386) (xy 331.517244 -248.668794) (xy 331.517244 -247.48617) (xy 331.38491 -247.353836)
				(xy 331.052678 -247.353836) (xy 330.94168 -247.242838) (xy 330.94168 -245.01602)
			)
		)
	)
	(zone
		(layer "In2.Cu")
		(hatch none 0.5)
		(connect_pads
			(clearance 0)
		)
		(min_thickness 0.25)
		(keepout
			(tracks allowed)
			(vias allowed)
			(pads allowed)
			(copperpour allowed)
			(footprints allowed)
		)
		(placement
			(enabled no)
			(sheetname "")
		)
		(fill
			(thermal_gap 0.5)
			(thermal_bridge_width 0.5)
			(island_removal_mode 0)
		)
		(polygon
			(pts
				(xy 86.627208 -290.610798) (xy 103.135684 -290.610544) (xy 103.113078 -290.63315) (xy 106.336084 -290.63315)
				(xy 106.33456 -213.220554) (xy 87.810086 -213.220808) (xy 86.868 -214.162894) (xy 84.934806 -216.096088)
				(xy 84.93506 -218.372182) (xy 85.566758 -219.00388) (xy 86.298024 -219.735146) (xy 86.298024 -219.951808)
				(xy 84.56168 -221.688152) (xy 84.56168 -222.47987) (xy 84.116926 -222.47987) (xy 84.0105 -222.586296)
				(xy 84.0105 -224.467928) (xy 83.90128 -224.577148) (xy 83.90128 -224.704148) (xy 84.15528 -224.958148)
				(xy 84.15528 -225.110548) (xy 83.97748 -225.288348) (xy 83.97748 -227.798376) (xy 85.17128 -228.992176)
				(xy 85.17128 -229.592886) (xy 83.673696 -231.09047) (xy 83.673696 -231.218994) (xy 83.87588 -231.421178)
				(xy 83.87588 -231.511348) (xy 82.780124 -232.607104) (xy 82.780124 -232.702608) (xy 82.989928 -232.912412)
				(xy 83.09102 -232.912412) (xy 83.09102 -234.886246) (xy 82.70748 -235.269786) (xy 82.70748 -240.018062)
				(xy 83.01228 -240.322862) (xy 83.01228 -247.253506) (xy 83.11261 -247.353836) (xy 83.444842 -247.353836)
				(xy 83.64728 -247.556274) (xy 83.64728 -248.738898) (xy 83.741768 -248.833386) (xy 84.17052 -248.833386)
				(xy 84.231226 -248.894092) (xy 84.231226 -250.063508) (xy 84.231226 -250.352814) (xy 84.363306 -250.484894)
				(xy 86.07933 -250.484894) (xy 86.31682 -250.247404) (xy 90.880438 -250.247404) (xy 90.880438 -249.69343)
				(xy 91.408758 -249.16511) (xy 93.369638 -249.16511) (xy 93.633798 -249.42927) (xy 93.936058 -249.42927)
				(xy 93.979238 -249.38609) (xy 94.324678 -249.38609) (xy 94.456758 -249.51817) (xy 94.456758 -249.83059)
				(xy 94.330012 -249.83059) (xy 94.239842 -249.921014) (xy 94.239842 -250.120404) (xy 94.239842 -250.256294)
				(xy 94.296738 -250.31319) (xy 95.20555 -250.31319) (xy 95.20555 -251.336556) (xy 93.195902 -253.346204)
				(xy 83.79968 -253.346204) (xy 83.79968 -256.97053) (xy 83.441286 -256.97053) (xy 83.441286 -258.46659)
				(xy 81.378806 -260.52907) (xy 81.378806 -261.783576) (xy 81.262474 -261.899908) (xy 80.95488 -261.899908)
				(xy 80.95488 -263.2329) (xy 81.15808 -263.2329) (xy 81.15808 -264.860278) (xy 80.80248 -265.215878)
				(xy 80.80248 -265.369548) (xy 84.708492 -269.27556) (xy 84.708492 -269.597886) (xy 84.00288 -270.303498)
				(xy 84.00288 -270.347948) (xy 85.62848 -271.973548) (xy 85.62848 -272.091658) (xy 83.92541 -273.794728)
				(xy 83.92541 -274.465288) (xy 84.027518 -274.567396) (xy 84.027518 -277.103078) (xy 83.68792 -277.442676)
				(xy 83.68792 -277.551388) (xy 84.76488 -278.628348) (xy 84.76488 -278.721312) (xy 84.40928 -279.076912)
				(xy 84.40928 -279.161748) (xy 85.55228 -280.304748) (xy 85.55228 -280.403808) (xy 85.28558 -280.670508)
				(xy 85.28558 -281.612848) (xy 84.89188 -282.006548) (xy 84.89188 -282.539948) (xy 85.080856 -282.728924)
				(xy 85.080856 -284.08503) (xy 85.478366 -284.48254) (xy 85.478366 -289.46221)
			)
		)
	)
	(zone
		(layer "In2.Cu")
		(hatch none 0.5)
		(connect_pads
			(clearance 0)
		)
		(min_thickness 0.25)
		(keepout
			(tracks allowed)
			(vias allowed)
			(pads allowed)
			(copperpour allowed)
			(footprints allowed)
		)
		(placement
			(enabled no)
			(sheetname "")
		)
		(fill
			(thermal_gap 0.5)
			(thermal_bridge_width 0.5)
			(island_removal_mode 0)
		)
		(polygon
			(pts
				(xy 420.97833 -206.384652) (xy 420.97833 -206.913226) (xy 420.44239 -206.913226) (xy 420.44239 -206.384652)
			)
		)
	)
	(zone
		(layer "In2.Cu")
		(hatch none 0.5)
		(connect_pads
			(clearance 0)
		)
		(min_thickness 0.25)
		(keepout
			(tracks allowed)
			(vias allowed)
			(pads allowed)
			(copperpour allowed)
			(footprints allowed)
		)
		(placement
			(enabled no)
			(sheetname "")
		)
		(fill
			(thermal_gap 0.5)
			(thermal_bridge_width 0.5)
			(island_removal_mode 0)
		)
		(polygon
			(pts
				(xy 423.04716 -156.337508) (xy 423.04716 -155.194508) (xy 424.3705 -155.194508) (xy 424.3705 -156.337508)
			)
		)
	)
	(zone
		(layer "In2.Cu")
		(hatch none 0.5)
		(connect_pads
			(clearance 0)
		)
		(min_thickness 0.25)
		(keepout
			(tracks allowed)
			(vias allowed)
			(pads allowed)
			(copperpour allowed)
			(footprints allowed)
		)
		(placement
			(enabled no)
			(sheetname "")
		)
		(fill
			(thermal_gap 0.5)
			(thermal_bridge_width 0.5)
			(island_removal_mode 0)
		)
		(polygon
			(pts
				(xy 50.75809 -223.93021) (xy 50.75809 -223.386904) (xy 51.312826 -223.386904) (xy 51.312826 -223.93021)
			)
		)
	)
	(zone
		(layer "In2.Cu")
		(hatch none 0.5)
		(connect_pads
			(clearance 0)
		)
		(min_thickness 0.25)
		(keepout
			(tracks allowed)
			(vias allowed)
			(pads allowed)
			(copperpour allowed)
			(footprints allowed)
		)
		(placement
			(enabled no)
			(sheetname "")
		)
		(fill
			(thermal_gap 0.5)
			(thermal_bridge_width 0.5)
			(island_removal_mode 0)
		)
		(polygon
			(pts
				(xy 50.75809 -246.88038) (xy 50.75809 -246.337074) (xy 51.312826 -246.337074) (xy 51.526694 -246.337074)
				(xy 51.526694 -246.88038) (xy 51.312826 -246.88038)
			)
		)
	)
	(zone
		(layer "In2.Cu")
		(hatch none 0.5)
		(connect_pads
			(clearance 0)
		)
		(min_thickness 0.25)
		(keepout
			(tracks allowed)
			(vias allowed)
			(pads allowed)
			(copperpour allowed)
			(footprints allowed)
		)
		(placement
			(enabled no)
			(sheetname "")
		)
		(fill
			(thermal_gap 0.5)
			(thermal_bridge_width 0.5)
			(island_removal_mode 0)
		)
		(polygon
			(pts
				(xy 298.723558 -315.730382) (xy 298.723558 -315.187076) (xy 299.278294 -315.187076) (xy 299.278294 -315.730382)
			)
		)
	)
	(zone
		(layer "In2.Cu")
		(hatch none 0.5)
		(connect_pads
			(clearance 0)
		)
		(min_thickness 0.25)
		(keepout
			(tracks allowed)
			(vias allowed)
			(pads allowed)
			(copperpour allowed)
			(footprints allowed)
		)
		(placement
			(enabled no)
			(sheetname "")
		)
		(fill
			(thermal_gap 0.5)
			(thermal_bridge_width 0.5)
			(island_removal_mode 0)
		)
		(polygon
			(pts
				(xy 180.556662 -242.084606) (xy 180.556662 -242.61318) (xy 180.020722 -242.61318) (xy 180.020722 -242.084606)
			)
		)
	)
	(zone
		(layer "In2.Cu")
		(hatch none 0.5)
		(connect_pads
			(clearance 0)
		)
		(min_thickness 0.25)
		(keepout
			(tracks allowed)
			(vias allowed)
			(pads allowed)
			(copperpour allowed)
			(footprints allowed)
		)
		(placement
			(enabled no)
			(sheetname "")
		)
		(fill
			(thermal_gap 0.5)
			(thermal_bridge_width 0.5)
			(island_removal_mode 0)
		)
		(polygon
			(pts
				(xy 409.990798 -231.884728) (xy 409.990798 -232.413302) (xy 409.454858 -232.413302) (xy 409.454858 -231.884728)
			)
		)
	)
	(zone
		(layer "In2.Cu")
		(hatch none 0.5)
		(connect_pads
			(clearance 0)
		)
		(min_thickness 0.25)
		(keepout
			(tracks allowed)
			(vias allowed)
			(pads allowed)
			(copperpour allowed)
			(footprints allowed)
		)
		(placement
			(enabled no)
			(sheetname "")
		)
		(fill
			(thermal_gap 0.5)
			(thermal_bridge_width 0.5)
			(island_removal_mode 0)
		)
		(polygon
			(pts
				(xy 173.038262 -242.084606) (xy 173.038262 -242.61318) (xy 172.502322 -242.61318) (xy 172.502322 -242.084606)
			)
		)
	)
	(zone
		(layer "In2.Cu")
		(hatch none 0.5)
		(connect_pads
			(clearance 0)
		)
		(min_thickness 0.25)
		(keepout
			(tracks allowed)
			(vias allowed)
			(pads allowed)
			(copperpour allowed)
			(footprints allowed)
		)
		(placement
			(enabled no)
			(sheetname "")
		)
		(fill
			(thermal_gap 0.5)
			(thermal_bridge_width 0.5)
			(island_removal_mode 0)
		)
		(polygon
			(pts
				(xy 425.078398 -266.734544) (xy 425.078398 -267.263118) (xy 424.542458 -267.263118) (xy 424.542458 -266.734544)
			)
		)
	)
	(zone
		(layer "In2.Cu")
		(hatch none 0.5)
		(connect_pads
			(clearance 0)
		)
		(min_thickness 0.25)
		(keepout
			(tracks allowed)
			(vias allowed)
			(pads allowed)
			(copperpour allowed)
			(footprints allowed)
		)
		(placement
			(enabled no)
			(sheetname "")
		)
		(fill
			(thermal_gap 0.5)
			(thermal_bridge_width 0.5)
			(island_removal_mode 0)
		)
		(polygon
			(pts
				(xy 173.038262 -288.834322) (xy 173.038262 -289.362896) (xy 172.502322 -289.362896) (xy 172.502322 -288.834322)
			)
		)
	)
	(zone
		(layer "In2.Cu")
		(hatch none 0.5)
		(connect_pads
			(clearance 0)
		)
		(min_thickness 0.25)
		(keepout
			(tracks allowed)
			(vias allowed)
			(pads allowed)
			(copperpour allowed)
			(footprints allowed)
		)
		(placement
			(enabled no)
			(sheetname "")
		)
		(fill
			(thermal_gap 0.5)
			(thermal_bridge_width 0.5)
			(island_removal_mode 0)
		)
		(polygon
			(pts
				(xy 173.038262 -286.284416) (xy 173.038262 -286.81299) (xy 172.502322 -286.81299) (xy 172.502322 -286.284416)
			)
		)
	)
	(zone
		(layer "In2.Cu")
		(hatch none 0.5)
		(connect_pads
			(clearance 0)
		)
		(min_thickness 0.25)
		(keepout
			(tracks allowed)
			(vias allowed)
			(pads allowed)
			(copperpour allowed)
			(footprints allowed)
		)
		(placement
			(enabled no)
			(sheetname "")
		)
		(fill
			(thermal_gap 0.5)
			(thermal_bridge_width 0.5)
			(island_removal_mode 0)
		)
		(polygon
			(pts
				(xy 420.97833 -248.034556) (xy 420.97833 -248.56313) (xy 420.44239 -248.56313) (xy 420.44239 -248.034556)
			)
		)
	)
	(zone
		(layer "In2.Cu")
		(hatch none 0.5)
		(connect_pads
			(clearance 0)
		)
		(min_thickness 0.25)
		(keepout
			(tracks allowed)
			(vias allowed)
			(pads allowed)
			(copperpour allowed)
			(footprints allowed)
		)
		(placement
			(enabled no)
			(sheetname "")
		)
		(fill
			(thermal_gap 0.5)
			(thermal_bridge_width 0.5)
			(island_removal_mode 0)
		)
		(polygon
			(pts
				(xy 173.038262 -305.834288) (xy 173.038262 -306.362862) (xy 172.502322 -306.362862) (xy 172.502322 -305.834288)
			)
		)
	)
	(zone
		(layer "In2.Cu")
		(hatch none 0.5)
		(connect_pads
			(clearance 0)
		)
		(min_thickness 0.25)
		(keepout
			(tracks allowed)
			(vias allowed)
			(pads allowed)
			(copperpour allowed)
			(footprints allowed)
		)
		(placement
			(enabled no)
			(sheetname "")
		)
		(fill
			(thermal_gap 0.5)
			(thermal_bridge_width 0.5)
			(island_removal_mode 0)
		)
		(polygon
			(pts
				(xy 425.078398 -245.484396) (xy 425.078398 -246.01297) (xy 424.542458 -246.01297) (xy 424.542458 -245.484396)
			)
		)
	)
	(zone
		(layer "In2.Cu")
		(hatch none 0.5)
		(connect_pads
			(clearance 0)
		)
		(min_thickness 0.25)
		(keepout
			(tracks allowed)
			(vias allowed)
			(pads allowed)
			(copperpour allowed)
			(footprints allowed)
		)
		(placement
			(enabled no)
			(sheetname "")
		)
		(fill
			(thermal_gap 0.5)
			(thermal_bridge_width 0.5)
			(island_removal_mode 0)
		)
		(polygon
			(pts
				(xy 389.073644 -251.304044) (xy 390.73963 -249.638058) (xy 390.797542 -249.638058) (xy 390.818116 -249.617484)
				(xy 390.891776 -249.543824) (xy 390.891776 -249.539252) (xy 390.8933 -249.537728) (xy 390.916668 -249.537728)
				(xy 394.607288 -249.537728) (xy 394.73632 -249.537728) (xy 394.794232 -249.479816) (xy 395.050264 -249.479816)
				(xy 395.219428 -249.310652) (xy 395.480794 -249.310652) (xy 396.153894 -248.637552) (xy 396.608554 -248.637552)
				(xy 397.903954 -247.342152) (xy 398.185894 -247.342152) (xy 398.505934 -247.022112) (xy 398.505934 -246.981472)
				(xy 398.089374 -246.564912) (xy 388.894574 -246.564912) (xy 388.514844 -246.564912) (xy 388.514844 -246.422418)
				(xy 387.934962 -245.842536) (xy 387.934962 -244.905276) (xy 387.739128 -244.709442) (xy 387.66623 -244.709442)
				(xy 387.65988 -244.715792) (xy 387.65988 -245.130574) (xy 387.191758 -245.598696) (xy 387.191758 -245.966996)
				(xy 387.138164 -246.02059) (xy 386.93979 -246.02059) (xy 386.467858 -246.492522) (xy 386.467858 -246.536972)
				(xy 386.480304 -246.549418) (xy 386.480304 -246.817642) (xy 386.026406 -247.27154) (xy 386.026406 -247.632728)
				(xy 384.98018 -248.678954) (xy 384.76174 -248.678954) (xy 382.341882 -248.678954) (xy 382.31826 -248.702576)
				(xy 382.31826 -249.484134) (xy 384.140964 -251.306838) (xy 387.528308 -251.306838) (xy 387.530848 -251.304298)
			)
		)
	)
	(zone
		(layer "In2.Cu")
		(hatch none 0.5)
		(connect_pads
			(clearance 0)
		)
		(min_thickness 0.25)
		(keepout
			(tracks allowed)
			(vias allowed)
			(pads allowed)
			(copperpour allowed)
			(footprints allowed)
		)
		(placement
			(enabled no)
			(sheetname "")
		)
		(fill
			(thermal_gap 0.5)
			(thermal_bridge_width 0.5)
			(island_removal_mode 0)
		)
		(polygon
			(pts
				(xy 50.78349 -265.580368) (xy 50.78349 -265.037062) (xy 51.338226 -265.037062) (xy 51.338226 -265.580368)
			)
		)
	)
	(zone
		(layer "In2.Cu")
		(hatch none 0.5)
		(connect_pads
			(clearance 0)
		)
		(min_thickness 0.25)
		(keepout
			(tracks allowed)
			(vias allowed)
			(pads allowed)
			(copperpour allowed)
			(footprints allowed)
		)
		(placement
			(enabled no)
			(sheetname "")
		)
		(fill
			(thermal_gap 0.5)
			(thermal_bridge_width 0.5)
			(island_removal_mode 0)
		)
		(polygon
			(pts
				(xy 177.13833 -244.634512) (xy 177.13833 -245.163086) (xy 176.60239 -245.163086) (xy 176.60239 -244.634512)
			)
		)
	)
	(zone
		(layer "In2.Cu")
		(hatch none 0.5)
		(connect_pads
			(clearance 0)
		)
		(min_thickness 0.25)
		(keepout
			(tracks allowed)
			(vias allowed)
			(pads allowed)
			(copperpour allowed)
			(footprints allowed)
		)
		(placement
			(enabled no)
			(sheetname "")
		)
		(fill
			(thermal_gap 0.5)
			(thermal_bridge_width 0.5)
			(island_removal_mode 0)
		)
		(polygon
			(pts
				(xy 157.950662 -304.13452) (xy 157.950662 -304.663094) (xy 157.414722 -304.663094) (xy 157.414722 -304.13452)
			)
		)
	)
	(zone
		(layer "In2.Cu")
		(hatch none 0.5)
		(connect_pads
			(clearance 0)
		)
		(min_thickness 0.25)
		(keepout
			(tracks allowed)
			(vias allowed)
			(pads allowed)
			(copperpour allowed)
			(footprints allowed)
		)
		(placement
			(enabled no)
			(sheetname "")
		)
		(fill
			(thermal_gap 0.5)
			(thermal_bridge_width 0.5)
			(island_removal_mode 0)
		)
		(polygon
			(pts
				(xy 298.698158 -223.93021) (xy 298.698158 -223.386904) (xy 299.252894 -223.386904) (xy 299.252894 -223.93021)
			)
		)
	)
	(zone
		(layer "In2.Cu")
		(hatch none 0.5)
		(connect_pads
			(clearance 0)
		)
		(min_thickness 0.25)
		(keepout
			(tracks allowed)
			(vias allowed)
			(pads allowed)
			(copperpour allowed)
			(footprints allowed)
		)
		(placement
			(enabled no)
			(sheetname "")
		)
		(fill
			(thermal_gap 0.5)
			(thermal_bridge_width 0.5)
			(island_removal_mode 0)
		)
		(polygon
			(pts
				(xy 372.9101 -341.544148) (xy 372.9101 -335.704688) (xy 381.67056 -335.704688) (xy 381.67056 -341.544148)
			)
		)
	)
	(zone
		(layer "In2.Cu")
		(hatch none 0.5)
		(connect_pads
			(clearance 0)
		)
		(min_thickness 0.25)
		(keepout
			(tracks allowed)
			(vias allowed)
			(pads allowed)
			(copperpour allowed)
			(footprints allowed)
		)
		(placement
			(enabled no)
			(sheetname "")
		)
		(fill
			(thermal_gap 0.5)
			(thermal_bridge_width 0.5)
			(island_removal_mode 0)
		)
		(polygon
			(pts
				(xy 173.038262 -308.384448) (xy 173.038262 -308.913022) (xy 172.502322 -308.913022) (xy 172.502322 -308.384448)
			)
		)
	)
	(zone
		(layer "In2.Cu")
		(hatch none 0.5)
		(connect_pads
			(clearance 0)
		)
		(min_thickness 0.25)
		(keepout
			(tracks allowed)
			(vias allowed)
			(pads allowed)
			(copperpour allowed)
			(footprints allowed)
		)
		(placement
			(enabled no)
			(sheetname "")
		)
		(fill
			(thermal_gap 0.5)
			(thermal_bridge_width 0.5)
			(island_removal_mode 0)
		)
		(polygon
			(pts
				(xy 173.038262 -289.68446) (xy 173.038262 -290.213034) (xy 172.502322 -290.213034) (xy 172.502322 -289.68446)
			)
		)
	)
	(zone
		(layer "In2.Cu")
		(hatch none 0.5)
		(connect_pads
			(clearance 0)
		)
		(min_thickness 0.25)
		(keepout
			(tracks allowed)
			(vias allowed)
			(pads allowed)
			(copperpour allowed)
			(footprints allowed)
		)
		(placement
			(enabled no)
			(sheetname "")
		)
		(fill
			(thermal_gap 0.5)
			(thermal_bridge_width 0.5)
			(island_removal_mode 0)
		)
		(polygon
			(pts
				(xy 173.038262 -276.084538) (xy 173.038262 -276.613112) (xy 172.502322 -276.613112) (xy 172.502322 -276.084538)
			)
		)
	)
	(zone
		(layer "In2.Cu")
		(hatch none 0.5)
		(connect_pads
			(clearance 0)
		)
		(min_thickness 0.25)
		(keepout
			(tracks allowed)
			(vias allowed)
			(pads allowed)
			(copperpour allowed)
			(footprints allowed)
		)
		(placement
			(enabled no)
			(sheetname "")
		)
		(fill
			(thermal_gap 0.5)
			(thermal_bridge_width 0.5)
			(island_removal_mode 0)
		)
		(polygon
			(pts
				(xy 177.13833 -259.93471) (xy 177.13833 -260.463284) (xy 176.60239 -260.463284) (xy 176.60239 -259.93471)
			)
		)
	)
	(zone
		(layer "In2.Cu")
		(hatch none 0.5)
		(connect_pads
			(clearance 0)
		)
		(min_thickness 0.25)
		(keepout
			(tracks allowed)
			(vias allowed)
			(pads allowed)
			(copperpour allowed)
			(footprints allowed)
		)
		(placement
			(enabled no)
			(sheetname "")
		)
		(fill
			(thermal_gap 0.5)
			(thermal_bridge_width 0.5)
			(island_removal_mode 0)
		)
		(polygon
			(pts
				(xy 157.925262 -300.734476) (xy 157.925262 -301.26305) (xy 157.389322 -301.26305) (xy 157.389322 -300.734476)
			)
		)
	)
	(zone
		(layer "In2.Cu")
		(hatch none 0.5)
		(connect_pads
			(clearance 0)
		)
		(min_thickness 0.25)
		(keepout
			(tracks allowed)
			(vias allowed)
			(pads allowed)
			(copperpour allowed)
			(footprints allowed)
		)
		(placement
			(enabled no)
			(sheetname "")
		)
		(fill
			(thermal_gap 0.5)
			(thermal_bridge_width 0.5)
			(island_removal_mode 0)
		)
		(polygon
			(pts
				(xy 157.925262 -227.6348) (xy 157.925262 -228.163374) (xy 157.389322 -228.163374) (xy 157.389322 -227.6348)
			)
		)
	)
	(zone
		(layer "In2.Cu")
		(hatch none 0.5)
		(connect_pads
			(clearance 0)
		)
		(min_thickness 0.25)
		(keepout
			(tracks allowed)
			(vias allowed)
			(pads allowed)
			(copperpour allowed)
			(footprints allowed)
		)
		(placement
			(enabled no)
			(sheetname "")
		)
		(fill
			(thermal_gap 0.5)
			(thermal_bridge_width 0.5)
			(island_removal_mode 0)
		)
		(polygon
			(pts
				(xy 50.78349 -289.380422) (xy 50.78349 -288.837116) (xy 51.338226 -288.837116) (xy 51.338226 -289.380422)
			)
		)
	)
	(zone
		(layer "In2.Cu")
		(hatch none 0.5)
		(connect_pads
			(clearance 0)
		)
		(min_thickness 0.25)
		(keepout
			(tracks allowed)
			(vias allowed)
			(pads allowed)
			(copperpour allowed)
			(footprints allowed)
		)
		(placement
			(enabled no)
			(sheetname "")
		)
		(fill
			(thermal_gap 0.5)
			(thermal_bridge_width 0.5)
			(island_removal_mode 0)
		)
		(polygon
			(pts
				(xy 298.723558 -289.380422) (xy 298.723558 -288.837116) (xy 299.278294 -288.837116) (xy 299.278294 -289.380422)
			)
		)
	)
	(zone
		(layer "In2.Cu")
		(hatch none 0.5)
		(connect_pads
			(clearance 0)
		)
		(min_thickness 0.25)
		(keepout
			(tracks allowed)
			(vias allowed)
			(pads allowed)
			(copperpour allowed)
			(footprints allowed)
		)
		(placement
			(enabled no)
			(sheetname "")
		)
		(fill
			(thermal_gap 0.5)
			(thermal_bridge_width 0.5)
			(island_removal_mode 0)
		)
		(polygon
			(pts
				(xy 313.785758 -306.380388) (xy 313.785758 -305.837082) (xy 314.340494 -305.837082) (xy 314.340494 -306.380388)
			)
		)
	)
	(zone
		(layer "In2.Cu")
		(hatch none 0.5)
		(connect_pads
			(clearance 0)
		)
		(min_thickness 0.25)
		(keepout
			(tracks allowed)
			(vias allowed)
			(pads allowed)
			(copperpour allowed)
			(footprints allowed)
		)
		(placement
			(enabled no)
			(sheetname "")
		)
		(fill
			(thermal_gap 0.5)
			(thermal_bridge_width 0.5)
			(island_removal_mode 0)
		)
		(polygon
			(pts
				(xy 50.75809 -234.980226) (xy 50.75809 -234.43692) (xy 51.312826 -234.43692) (xy 51.312826 -234.980226)
			)
		)
	)
	(zone
		(layer "In2.Cu")
		(hatch none 0.5)
		(connect_pads
			(clearance 0)
		)
		(min_thickness 0.25)
		(keepout
			(tracks allowed)
			(vias allowed)
			(pads allowed)
			(copperpour allowed)
			(footprints allowed)
		)
		(placement
			(enabled no)
			(sheetname "")
		)
		(fill
			(thermal_gap 0.5)
			(thermal_bridge_width 0.5)
			(island_removal_mode 0)
		)
		(polygon
			(pts
				(xy 405.89073 -229.334822) (xy 405.89073 -229.863396) (xy 405.35479 -229.863396) (xy 405.35479 -229.334822)
			)
		)
	)
	(zone
		(layer "In2.Cu")
		(hatch none 0.5)
		(connect_pads
			(clearance 0)
		)
		(min_thickness 0.25)
		(keepout
			(tracks allowed)
			(vias allowed)
			(pads allowed)
			(copperpour allowed)
			(footprints allowed)
		)
		(placement
			(enabled no)
			(sheetname "")
		)
		(fill
			(thermal_gap 0.5)
			(thermal_bridge_width 0.5)
			(island_removal_mode 0)
		)
		(polygon
			(pts
				(xy 343.45372 -50.249328) (xy 343.45372 -49.207928) (xy 344.8304 -49.207928) (xy 344.8304 -50.249328)
			)
		)
	)
	(zone
		(layer "In2.Cu")
		(hatch none 0.5)
		(connect_pads
			(clearance 0)
		)
		(min_thickness 0.25)
		(keepout
			(tracks allowed)
			(vias allowed)
			(pads allowed)
			(copperpour allowed)
			(footprints allowed)
		)
		(placement
			(enabled no)
			(sheetname "")
		)
		(fill
			(thermal_gap 0.5)
			(thermal_bridge_width 0.5)
			(island_removal_mode 0)
		)
		(polygon
			(pts
				(xy 298.723558 -312.330338) (xy 298.723558 -311.787032) (xy 299.278294 -311.787032) (xy 299.278294 -312.330338)
			)
		)
	)
	(zone
		(layer "In2.Cu")
		(hatch none 0.5)
		(connect_pads
			(clearance 0)
		)
		(min_thickness 0.25)
		(keepout
			(tracks allowed)
			(vias allowed)
			(pads allowed)
			(copperpour allowed)
			(footprints allowed)
		)
		(placement
			(enabled no)
			(sheetname "")
		)
		(fill
			(thermal_gap 0.5)
			(thermal_bridge_width 0.5)
			(island_removal_mode 0)
		)
		(polygon
			(pts
				(xy 420.97833 -236.134656) (xy 420.97833 -236.66323) (xy 420.44239 -236.66323) (xy 420.44239 -236.134656)
			)
		)
	)
	(zone
		(layer "In2.Cu")
		(hatch none 0.5)
		(connect_pads
			(clearance 0)
		)
		(min_thickness 0.25)
		(keepout
			(tracks allowed)
			(vias allowed)
			(pads allowed)
			(copperpour allowed)
			(footprints allowed)
		)
		(placement
			(enabled no)
			(sheetname "")
		)
		(fill
			(thermal_gap 0.5)
			(thermal_bridge_width 0.5)
			(island_removal_mode 0)
		)
		(polygon
			(pts
				(xy 50.78349 -262.180324) (xy 50.78349 -261.637018) (xy 51.338226 -261.637018) (xy 51.5874 -261.637018)
				(xy 51.5874 -262.180324) (xy 51.338226 -262.180324)
			)
		)
	)
	(zone
		(layer "In2.Cu")
		(hatch none 0.5)
		(connect_pads
			(clearance 0)
		)
		(min_thickness 0.25)
		(keepout
			(tracks allowed)
			(vias allowed)
			(pads allowed)
			(copperpour allowed)
			(footprints allowed)
		)
		(placement
			(enabled no)
			(sheetname "")
		)
		(fill
			(thermal_gap 0.5)
			(thermal_bridge_width 0.5)
			(island_removal_mode 0)
		)
		(polygon
			(pts
				(xy 173.038262 -210.634834) (xy 173.038262 -211.163408) (xy 172.502322 -211.163408) (xy 172.502322 -210.634834)
			)
		)
	)
	(zone
		(layer "In2.Cu")
		(hatch none 0.5)
		(connect_pads
			(clearance 0)
		)
		(min_thickness 0.25)
		(keepout
			(tracks allowed)
			(vias allowed)
			(pads allowed)
			(copperpour allowed)
			(footprints allowed)
		)
		(placement
			(enabled no)
			(sheetname "")
		)
		(fill
			(thermal_gap 0.5)
			(thermal_bridge_width 0.5)
			(island_removal_mode 0)
		)
		(polygon
			(pts
				(xy 173.038262 -244.634512) (xy 173.038262 -245.163086) (xy 172.502322 -245.163086) (xy 172.502322 -244.634512)
			)
		)
	)
	(zone
		(layer "In2.Cu")
		(hatch none 0.5)
		(connect_pads
			(clearance 0)
		)
		(min_thickness 0.25)
		(keepout
			(tracks allowed)
			(vias allowed)
			(pads allowed)
			(copperpour allowed)
			(footprints allowed)
		)
		(placement
			(enabled no)
			(sheetname "")
		)
		(fill
			(thermal_gap 0.5)
			(thermal_bridge_width 0.5)
			(island_removal_mode 0)
		)
		(polygon
			(pts
				(xy 409.965398 -223.384618) (xy 409.965398 -223.913192) (xy 409.965398 -224.542096) (xy 408.949144 -224.542096)
				(xy 408.949144 -223.913192) (xy 408.949144 -223.384618) (xy 409.429458 -223.384618)
			)
		)
	)
	(zone
		(layer "In2.Cu")
		(hatch none 0.5)
		(connect_pads
			(clearance 0)
		)
		(min_thickness 0.25)
		(keepout
			(tracks allowed)
			(vias allowed)
			(pads allowed)
			(copperpour allowed)
			(footprints allowed)
		)
		(placement
			(enabled no)
			(sheetname "")
		)
		(fill
			(thermal_gap 0.5)
			(thermal_bridge_width 0.5)
			(island_removal_mode 0)
		)
		(polygon
			(pts
				(xy 177.13833 -265.88466) (xy 177.13833 -266.413234) (xy 176.60239 -266.413234) (xy 176.60239 -265.88466)
			)
		)
	)
	(zone
		(layer "In2.Cu")
		(hatch none 0.5)
		(connect_pads
			(clearance 0)
		)
		(min_thickness 0.25)
		(keepout
			(tracks allowed)
			(vias allowed)
			(pads allowed)
			(copperpour allowed)
			(footprints allowed)
		)
		(placement
			(enabled no)
			(sheetname "")
		)
		(fill
			(thermal_gap 0.5)
			(thermal_bridge_width 0.5)
			(island_removal_mode 0)
		)
		(polygon
			(pts
				(xy 173.038262 -261.634478) (xy 173.038262 -262.163052) (xy 172.502322 -262.163052) (xy 172.502322 -261.634478)
			)
		)
	)
	(zone
		(layer "In2.Cu")
		(hatch none 0.5)
		(connect_pads
			(clearance 0)
		)
		(min_thickness 0.25)
		(keepout
			(tracks allowed)
			(vias allowed)
			(pads allowed)
			(copperpour allowed)
			(footprints allowed)
		)
		(placement
			(enabled no)
			(sheetname "")
		)
		(fill
			(thermal_gap 0.5)
			(thermal_bridge_width 0.5)
			(island_removal_mode 0)
		)
		(polygon
			(pts
				(xy 137.99058 -347.513148) (xy 137.99058 -344.427048) (xy 133.80212 -344.427048) (xy 133.80212 -347.513148)
			)
		)
	)
	(zone
		(layer "In2.Cu")
		(hatch none 0.5)
		(connect_pads
			(clearance 0)
		)
		(min_thickness 0.25)
		(keepout
			(tracks allowed)
			(vias allowed)
			(pads allowed)
			(copperpour allowed)
			(footprints allowed)
		)
		(placement
			(enabled no)
			(sheetname "")
		)
		(fill
			(thermal_gap 0.5)
			(thermal_bridge_width 0.5)
			(island_removal_mode 0)
		)
		(polygon
			(pts
				(xy 294.31234 -367.703608) (xy 294.31234 -364.566708) (xy 298.831 -364.566708) (xy 298.831 -367.703608)
			)
		)
	)
	(zone
		(layer "In2.Cu")
		(hatch none 0.5)
		(connect_pads
			(clearance 0)
		)
		(min_thickness 0.25)
		(keepout
			(tracks allowed)
			(vias allowed)
			(pads allowed)
			(copperpour allowed)
			(footprints allowed)
		)
		(placement
			(enabled no)
			(sheetname "")
		)
		(fill
			(thermal_gap 0.5)
			(thermal_bridge_width 0.5)
			(island_removal_mode 0)
		)
		(polygon
			(pts
				(xy 173.038262 -271.83461) (xy 173.038262 -272.363184) (xy 172.502322 -272.363184) (xy 172.502322 -271.83461)
			)
		)
	)
	(zone
		(layer "In2.Cu")
		(hatch none 0.5)
		(connect_pads
			(clearance 0)
		)
		(min_thickness 0.25)
		(keepout
			(tracks allowed)
			(vias allowed)
			(pads allowed)
			(copperpour allowed)
			(footprints allowed)
		)
		(placement
			(enabled no)
			(sheetname "")
		)
		(fill
			(thermal_gap 0.5)
			(thermal_bridge_width 0.5)
			(island_removal_mode 0)
		)
		(polygon
			(pts
				(xy 420.97833 -274.384516) (xy 420.97833 -274.91309) (xy 420.44239 -274.91309) (xy 420.44239 -274.384516)
			)
		)
	)
	(zone
		(layer "In2.Cu")
		(hatch none 0.5)
		(connect_pads
			(clearance 0)
		)
		(min_thickness 0.25)
		(keepout
			(tracks allowed)
			(vias allowed)
			(pads allowed)
			(copperpour allowed)
			(footprints allowed)
		)
		(placement
			(enabled no)
			(sheetname "")
		)
		(fill
			(thermal_gap 0.5)
			(thermal_bridge_width 0.5)
			(island_removal_mode 0)
		)
		(polygon
			(pts
				(xy 173.038262 -208.08442) (xy 173.038262 -208.612994) (xy 172.502322 -208.612994) (xy 172.502322 -208.08442)
			)
		)
	)
	(zone
		(layer "In2.Cu")
		(hatch none 0.5)
		(connect_pads
			(clearance 0)
		)
		(min_thickness 0.25)
		(keepout
			(tracks allowed)
			(vias allowed)
			(pads allowed)
			(copperpour allowed)
			(footprints allowed)
		)
		(placement
			(enabled no)
			(sheetname "")
		)
		(fill
			(thermal_gap 0.5)
			(thermal_bridge_width 0.5)
			(island_removal_mode 0)
		)
		(polygon
			(pts
				(xy 420.97833 -266.734544) (xy 420.97833 -267.263118) (xy 420.44239 -267.263118) (xy 420.44239 -266.734544)
			)
		)
	)
	(zone
		(layer "In2.Cu")
		(hatch none 0.5)
		(connect_pads
			(clearance 0)
		)
		(min_thickness 0.25)
		(keepout
			(tracks allowed)
			(vias allowed)
			(pads allowed)
			(copperpour allowed)
			(footprints allowed)
		)
		(placement
			(enabled no)
			(sheetname "")
		)
		(fill
			(thermal_gap 0.5)
			(thermal_bridge_width 0.5)
			(island_removal_mode 0)
		)
		(polygon
			(pts
				(xy 151.50846 -404.853648) (xy 151.50846 -402.971508) (xy 152.87752 -402.971508) (xy 152.87752 -404.853648)
			)
		)
	)
	(zone
		(layer "In2.Cu")
		(hatch none 0.5)
		(connect_pads
			(clearance 0)
		)
		(min_thickness 0.25)
		(keepout
			(tracks allowed)
			(vias allowed)
			(pads allowed)
			(copperpour allowed)
			(footprints allowed)
		)
		(placement
			(enabled no)
			(sheetname "")
		)
		(fill
			(thermal_gap 0.5)
			(thermal_bridge_width 0.5)
			(island_removal_mode 0)
		)
		(polygon
			(pts
				(xy 173.038262 -208.084674) (xy 173.038262 -208.613248) (xy 172.502322 -208.613248) (xy 172.502322 -208.084674)
			)
		)
	)
	(zone
		(layer "In2.Cu")
		(hatch none 0.5)
		(connect_pads
			(clearance 0)
		)
		(min_thickness 0.25)
		(keepout
			(tracks allowed)
			(vias allowed)
			(pads allowed)
			(copperpour allowed)
			(footprints allowed)
		)
		(placement
			(enabled no)
			(sheetname "")
		)
		(fill
			(thermal_gap 0.5)
			(thermal_bridge_width 0.5)
			(island_removal_mode 0)
		)
		(polygon
			(pts
				(xy 50.00244 -358.371648) (xy 50.00244 -357.449628) (xy 51.5747 -357.449628) (xy 51.5747 -358.371648)
			)
		)
	)
	(zone
		(layer "In2.Cu")
		(hatch none 0.5)
		(connect_pads
			(clearance 0)
		)
		(min_thickness 0.25)
		(keepout
			(tracks allowed)
			(vias allowed)
			(pads allowed)
			(copperpour allowed)
			(footprints allowed)
		)
		(placement
			(enabled no)
			(sheetname "")
		)
		(fill
			(thermal_gap 0.5)
			(thermal_bridge_width 0.5)
			(island_removal_mode 0)
		)
		(polygon
			(pts
				(xy 173.038262 -233.584496) (xy 173.038262 -234.11307) (xy 172.502322 -234.11307) (xy 172.502322 -233.584496)
			)
		)
	)
	(zone
		(layer "In2.Cu")
		(hatch none 0.5)
		(connect_pads
			(clearance 0)
		)
		(min_thickness 0.25)
		(keepout
			(tracks allowed)
			(vias allowed)
			(pads allowed)
			(copperpour allowed)
			(footprints allowed)
		)
		(placement
			(enabled no)
			(sheetname "")
		)
		(fill
			(thermal_gap 0.5)
			(thermal_bridge_width 0.5)
			(island_removal_mode 0)
		)
		(polygon
			(pts
				(xy 409.990798 -231.03459) (xy 409.990798 -231.563164) (xy 409.454858 -231.563164) (xy 409.454858 -231.03459)
				(xy 408.619198 -231.03459) (xy 408.619198 -230.220774) (xy 409.990798 -230.220774)
			)
		)
	)
	(zone
		(layer "In2.Cu")
		(hatch none 0.5)
		(connect_pads
			(clearance 0)
		)
		(min_thickness 0.25)
		(keepout
			(tracks allowed)
			(vias allowed)
			(pads allowed)
			(copperpour allowed)
			(footprints allowed)
		)
		(placement
			(enabled no)
			(sheetname "")
		)
		(fill
			(thermal_gap 0.5)
			(thermal_bridge_width 0.5)
			(island_removal_mode 0)
		)
		(polygon
			(pts
				(xy 420.97833 -314.334398) (xy 420.97833 -314.862972) (xy 420.44239 -314.862972) (xy 420.44239 -314.334398)
			)
		)
	)
	(zone
		(layer "In2.Cu")
		(hatch none 0.5)
		(connect_pads
			(clearance 0)
		)
		(min_thickness 0.25)
		(keepout
			(tracks allowed)
			(vias allowed)
			(pads allowed)
			(copperpour allowed)
			(footprints allowed)
		)
		(placement
			(enabled no)
			(sheetname "")
		)
		(fill
			(thermal_gap 0.5)
			(thermal_bridge_width 0.5)
			(island_removal_mode 0)
		)
		(polygon
			(pts
				(xy 420.97833 -234.434634) (xy 420.97833 -234.963208) (xy 420.44239 -234.963208) (xy 420.44239 -234.434634)
			)
		)
	)
	(zone
		(layer "In2.Cu")
		(hatch none 0.5)
		(connect_pads
			(clearance 0)
		)
		(min_thickness 0.25)
		(keepout
			(tracks allowed)
			(vias allowed)
			(pads allowed)
			(copperpour allowed)
			(footprints allowed)
		)
		(placement
			(enabled no)
			(sheetname "")
		)
		(fill
			(thermal_gap 0.5)
			(thermal_bridge_width 0.5)
			(island_removal_mode 0)
		)
		(polygon
			(pts
				(xy 405.89073 -231.034844) (xy 405.89073 -231.563418) (xy 405.35479 -231.563418) (xy 405.35479 -231.034844)
			)
		)
	)
	(zone
		(layer "In2.Cu")
		(hatch none 0.5)
		(connect_pads
			(clearance 0)
		)
		(min_thickness 0.25)
		(keepout
			(tracks allowed)
			(vias allowed)
			(pads allowed)
			(copperpour allowed)
			(footprints allowed)
		)
		(placement
			(enabled no)
			(sheetname "")
		)
		(fill
			(thermal_gap 0.5)
			(thermal_bridge_width 0.5)
			(island_removal_mode 0)
		)
		(polygon
			(pts
				(xy 50.78349 -308.08041) (xy 50.78349 -307.537104) (xy 51.338226 -307.537104) (xy 51.338226 -308.08041)
			)
		)
	)
	(zone
		(layer "In2.Cu")
		(hatch none 0.5)
		(connect_pads
			(clearance 0)
		)
		(min_thickness 0.25)
		(keepout
			(tracks allowed)
			(vias allowed)
			(pads allowed)
			(copperpour allowed)
			(footprints allowed)
		)
		(placement
			(enabled no)
			(sheetname "")
		)
		(fill
			(thermal_gap 0.5)
			(thermal_bridge_width 0.5)
			(island_removal_mode 0)
		)
		(polygon
			(pts
				(xy 173.038262 -293.934388) (xy 173.038262 -294.462962) (xy 172.502322 -294.462962) (xy 172.502322 -293.934388)
			)
		)
	)
	(zone
		(layer "In2.Cu")
		(hatch none 0.5)
		(connect_pads
			(clearance 0)
		)
		(min_thickness 0.25)
		(keepout
			(tracks allowed)
			(vias allowed)
			(pads allowed)
			(copperpour allowed)
			(footprints allowed)
		)
		(placement
			(enabled no)
			(sheetname "")
		)
		(fill
			(thermal_gap 0.5)
			(thermal_bridge_width 0.5)
			(island_removal_mode 0)
		)
		(polygon
			(pts
				(xy 173.038262 -216.58453) (xy 173.038262 -217.113104) (xy 172.502322 -217.113104) (xy 172.502322 -216.58453)
			)
		)
	)
	(zone
		(layer "In2.Cu")
		(hatch none 0.5)
		(connect_pads
			(clearance 0)
		)
		(min_thickness 0.25)
		(keepout
			(tracks allowed)
			(vias allowed)
			(pads allowed)
			(copperpour allowed)
			(footprints allowed)
		)
		(placement
			(enabled no)
			(sheetname "")
		)
		(fill
			(thermal_gap 0.5)
			(thermal_bridge_width 0.5)
			(island_removal_mode 0)
		)
		(polygon
			(pts
				(xy 420.97833 -236.134402) (xy 420.97833 -236.662976) (xy 420.44239 -236.662976) (xy 420.44239 -236.134402)
			)
		)
	)
	(zone
		(layer "In2.Cu")
		(hatch none 0.5)
		(connect_pads
			(clearance 0)
		)
		(min_thickness 0.25)
		(keepout
			(tracks allowed)
			(vias allowed)
			(pads allowed)
			(copperpour allowed)
			(footprints allowed)
		)
		(placement
			(enabled no)
			(sheetname "")
		)
		(fill
			(thermal_gap 0.5)
			(thermal_bridge_width 0.5)
			(island_removal_mode 0)
		)
		(polygon
			(pts
				(xy 50.75809 -245.180358) (xy 50.75809 -244.637052) (xy 51.312826 -244.637052) (xy 51.312826 -245.180358)
			)
		)
	)
	(zone
		(layer "In2.Cu")
		(hatch none 0.5)
		(connect_pads
			(clearance 0)
		)
		(min_thickness 0.25)
		(keepout
			(tracks allowed)
			(vias allowed)
			(pads allowed)
			(copperpour allowed)
			(footprints allowed)
		)
		(placement
			(enabled no)
			(sheetname "")
		)
		(fill
			(thermal_gap 0.5)
			(thermal_bridge_width 0.5)
			(island_removal_mode 0)
		)
		(polygon
			(pts
				(xy 420.97833 -270.984726) (xy 420.97833 -271.5133) (xy 420.44239 -271.5133) (xy 419.929056 -271.5133)
				(xy 419.929056 -270.984726) (xy 420.44239 -270.984726)
			)
		)
	)
	(zone
		(layer "In2.Cu")
		(hatch none 0.5)
		(connect_pads
			(clearance 0)
		)
		(min_thickness 0.25)
		(keepout
			(tracks allowed)
			(vias allowed)
			(pads allowed)
			(copperpour allowed)
			(footprints allowed)
		)
		(placement
			(enabled no)
			(sheetname "")
		)
		(fill
			(thermal_gap 0.5)
			(thermal_bridge_width 0.5)
			(island_removal_mode 0)
		)
		(polygon
			(pts
				(xy 298.723558 -291.080444) (xy 298.723558 -290.537138) (xy 299.278294 -290.537138) (xy 299.278294 -291.080444)
			)
		)
	)
	(zone
		(layer "In2.Cu")
		(hatch none 0.5)
		(connect_pads
			(clearance 0)
		)
		(min_thickness 0.25)
		(keepout
			(tracks allowed)
			(vias allowed)
			(pads allowed)
			(copperpour allowed)
			(footprints allowed)
		)
		(placement
			(enabled no)
			(sheetname "")
		)
		(fill
			(thermal_gap 0.5)
			(thermal_bridge_width 0.5)
			(island_removal_mode 0)
		)
		(polygon
			(pts
				(xy 420.97833 -210.634834) (xy 420.97833 -211.163408) (xy 420.44239 -211.163408) (xy 420.44239 -210.634834)
			)
		)
	)
	(zone
		(layer "In2.Cu")
		(hatch none 0.5)
		(connect_pads
			(clearance 0)
		)
		(min_thickness 0.25)
		(keepout
			(tracks allowed)
			(vias allowed)
			(pads allowed)
			(copperpour allowed)
			(footprints allowed)
		)
		(placement
			(enabled no)
			(sheetname "")
		)
		(fill
			(thermal_gap 0.5)
			(thermal_bridge_width 0.5)
			(island_removal_mode 0)
		)
		(polygon
			(pts
				(xy 352.11766 -352.036888) (xy 352.11766 -351.285048) (xy 353.5426 -351.285048) (xy 353.5426 -352.036888)
			)
		)
	)
	(zone
		(layer "In2.Cu")
		(hatch none 0.5)
		(connect_pads
			(clearance 0)
		)
		(min_thickness 0.25)
		(keepout
			(tracks allowed)
			(vias allowed)
			(pads allowed)
			(copperpour allowed)
			(footprints allowed)
		)
		(placement
			(enabled no)
			(sheetname "")
		)
		(fill
			(thermal_gap 0.5)
			(thermal_bridge_width 0.5)
			(island_removal_mode 0)
		)
		(polygon
			(pts
				(xy 173.038262 -243.784628) (xy 173.038262 -244.313202) (xy 172.502322 -244.313202) (xy 172.502322 -243.784628)
			)
		)
	)
	(zone
		(layer "In2.Cu")
		(hatch none 0.5)
		(connect_pads
			(clearance 0)
		)
		(min_thickness 0.25)
		(keepout
			(tracks allowed)
			(vias allowed)
			(pads allowed)
			(copperpour allowed)
			(footprints allowed)
		)
		(placement
			(enabled no)
			(sheetname "")
		)
		(fill
			(thermal_gap 0.5)
			(thermal_bridge_width 0.5)
			(island_removal_mode 0)
		)
		(polygon
			(pts
				(xy 420.97833 -295.63441) (xy 420.97833 -296.162984) (xy 420.44239 -296.162984) (xy 420.44239 -295.63441)
			)
		)
	)
	(zone
		(layer "In2.Cu")
		(hatch none 0.5)
		(connect_pads
			(clearance 0)
		)
		(min_thickness 0.25)
		(keepout
			(tracks allowed)
			(vias allowed)
			(pads allowed)
			(copperpour allowed)
			(footprints allowed)
		)
		(placement
			(enabled no)
			(sheetname "")
		)
		(fill
			(thermal_gap 0.5)
			(thermal_bridge_width 0.5)
			(island_removal_mode 0)
		)
		(polygon
			(pts
				(xy 405.86533 -227.634546) (xy 405.86533 -228.16312) (xy 405.32939 -228.16312) (xy 405.32939 -227.634546)
			)
		)
	)
	(zone
		(layer "In2.Cu")
		(hatch none 0.5)
		(connect_pads
			(clearance 0)
		)
		(min_thickness 0.25)
		(keepout
			(tracks allowed)
			(vias allowed)
			(pads allowed)
			(copperpour allowed)
			(footprints allowed)
		)
		(placement
			(enabled no)
			(sheetname "")
		)
		(fill
			(thermal_gap 0.5)
			(thermal_bridge_width 0.5)
			(island_removal_mode 0)
		)
		(polygon
			(pts
				(xy 101.22408 -338.971128) (xy 101.22408 -334.289908) (xy 114.45748 -334.289908) (xy 114.45748 -338.971128)
			)
		)
	)
	(zone
		(layer "In2.Cu")
		(hatch none 0.5)
		(connect_pads
			(clearance 0)
		)
		(min_thickness 0.25)
		(keepout
			(tracks allowed)
			(vias allowed)
			(pads allowed)
			(copperpour allowed)
			(footprints allowed)
		)
		(placement
			(enabled no)
			(sheetname "")
		)
		(fill
			(thermal_gap 0.5)
			(thermal_bridge_width 0.5)
			(island_removal_mode 0)
		)
		(polygon
			(pts
				(xy 173.038262 -235.284518) (xy 173.038262 -235.813092) (xy 172.502322 -235.813092) (xy 172.502322 -235.284518)
			)
		)
	)
	(zone
		(layer "In2.Cu")
		(hatch none 0.5)
		(connect_pads
			(clearance 0)
		)
		(min_thickness 0.25)
		(keepout
			(tracks allowed)
			(vias allowed)
			(pads allowed)
			(copperpour allowed)
			(footprints allowed)
		)
		(placement
			(enabled no)
			(sheetname "")
		)
		(fill
			(thermal_gap 0.5)
			(thermal_bridge_width 0.5)
			(island_removal_mode 0)
		)
		(polygon
			(pts
				(xy 298.723558 -314.03036) (xy 298.723558 -313.487054) (xy 299.278294 -313.487054) (xy 299.482002 -313.487054)
				(xy 299.722032 -313.487054) (xy 299.901102 -313.487054) (xy 299.93844 -313.524392) (xy 299.93844 -314.302394)
				(xy 299.548804 -314.302394) (xy 299.473874 -314.227464) (xy 299.278294 -314.031884) (xy 299.278294 -314.03036)
			)
		)
	)
	(zone
		(layer "In2.Cu")
		(hatch none 0.5)
		(connect_pads
			(clearance 0)
		)
		(min_thickness 0.25)
		(keepout
			(tracks allowed)
			(vias allowed)
			(pads allowed)
			(copperpour allowed)
			(footprints allowed)
		)
		(placement
			(enabled no)
			(sheetname "")
		)
		(fill
			(thermal_gap 0.5)
			(thermal_bridge_width 0.5)
			(island_removal_mode 0)
		)
		(polygon
			(pts
				(xy 294.59809 -246.030242) (xy 294.59809 -245.486936) (xy 295.152826 -245.486936) (xy 295.152826 -246.030242)
			)
		)
	)
	(zone
		(layer "In2.Cu")
		(hatch none 0.5)
		(connect_pads
			(clearance 0)
		)
		(min_thickness 0.25)
		(keepout
			(tracks allowed)
			(vias allowed)
			(pads allowed)
			(copperpour allowed)
			(footprints allowed)
		)
		(placement
			(enabled no)
			(sheetname "")
		)
		(fill
			(thermal_gap 0.5)
			(thermal_bridge_width 0.5)
			(island_removal_mode 0)
		)
		(polygon
			(pts
				(xy 50.78349 -291.080444) (xy 50.78349 -290.537138) (xy 51.338226 -290.537138) (xy 51.338226 -291.080444)
			)
		)
	)
	(zone
		(layer "In2.Cu")
		(hatch none 0.5)
		(connect_pads
			(clearance 0)
		)
		(min_thickness 0.25)
		(keepout
			(tracks allowed)
			(vias allowed)
			(pads allowed)
			(copperpour allowed)
			(footprints allowed)
		)
		(placement
			(enabled no)
			(sheetname "")
		)
		(fill
			(thermal_gap 0.5)
			(thermal_bridge_width 0.5)
			(island_removal_mode 0)
		)
		(polygon
			(pts
				(xy 405.86533 -224.234756) (xy 405.86533 -224.76333) (xy 405.32939 -224.76333) (xy 405.32939 -224.234756)
			)
		)
	)
	(zone
		(layer "In2.Cu")
		(hatch none 0.5)
		(connect_pads
			(clearance 0)
		)
		(min_thickness 0.25)
		(keepout
			(tracks allowed)
			(vias allowed)
			(pads allowed)
			(copperpour allowed)
			(footprints allowed)
		)
		(placement
			(enabled no)
			(sheetname "")
		)
		(fill
			(thermal_gap 0.5)
			(thermal_bridge_width 0.5)
			(island_removal_mode 0)
		)
		(polygon
			(pts
				(xy 157.950662 -270.134588) (xy 157.950662 -270.663162) (xy 157.414722 -270.663162) (xy 157.414722 -270.134588)
			)
		)
	)
	(zone
		(layer "In2.Cu")
		(hatch none 0.5)
		(connect_pads
			(clearance 0)
		)
		(min_thickness 0.25)
		(keepout
			(tracks allowed)
			(vias allowed)
			(pads allowed)
			(copperpour allowed)
			(footprints allowed)
		)
		(placement
			(enabled no)
			(sheetname "")
		)
		(fill
			(thermal_gap 0.5)
			(thermal_bridge_width 0.5)
			(island_removal_mode 0)
		)
		(polygon
			(pts
				(xy 157.950662 -231.034844) (xy 157.950662 -231.563418) (xy 157.414722 -231.563418) (xy 157.414722 -231.034844)
			)
		)
	)
	(zone
		(layer "In2.Cu")
		(hatch none 0.5)
		(connect_pads
			(clearance 0)
		)
		(min_thickness 0.25)
		(keepout
			(tracks allowed)
			(vias allowed)
			(pads allowed)
			(copperpour allowed)
			(footprints allowed)
		)
		(placement
			(enabled no)
			(sheetname "")
		)
		(fill
			(thermal_gap 0.5)
			(thermal_bridge_width 0.5)
			(island_removal_mode 0)
		)
		(polygon
			(pts
				(xy 420.97833 -265.88466) (xy 420.97833 -266.413234) (xy 420.44239 -266.413234) (xy 420.44239 -265.88466)
			)
		)
	)
	(zone
		(layer "In2.Cu")
		(hatch none 0.5)
		(connect_pads
			(clearance 0)
		)
		(min_thickness 0.25)
		(keepout
			(tracks allowed)
			(vias allowed)
			(pads allowed)
			(copperpour allowed)
			(footprints allowed)
		)
		(placement
			(enabled no)
			(sheetname "")
		)
		(fill
			(thermal_gap 0.5)
			(thermal_bridge_width 0.5)
			(island_removal_mode 0)
		)
		(polygon
			(pts
				(xy 50.78349 -260.480302) (xy 50.78349 -259.936996) (xy 51.338226 -259.936996) (xy 51.338226 -260.480302)
			)
		)
	)
	(zone
		(layer "In2.Cu")
		(hatch none 0.5)
		(connect_pads
			(clearance 0)
		)
		(min_thickness 0.25)
		(keepout
			(tracks allowed)
			(vias allowed)
			(pads allowed)
			(copperpour allowed)
			(footprints allowed)
		)
		(placement
			(enabled no)
			(sheetname "")
		)
		(fill
			(thermal_gap 0.5)
			(thermal_bridge_width 0.5)
			(island_removal_mode 0)
		)
		(polygon
			(pts
				(xy 50.959004 -153.822654) (xy 50.959004 -152.847802) (xy 51.261264 -152.545542) (xy 54.213252 -152.545542)
				(xy 54.638956 -152.971246) (xy 54.638956 -153.657808) (xy 54.240684 -154.05608) (xy 51.19243 -154.05608)
			)
		)
	)
	(zone
		(layer "In2.Cu")
		(hatch none 0.5)
		(connect_pads
			(clearance 0)
		)
		(min_thickness 0.25)
		(keepout
			(tracks allowed)
			(vias allowed)
			(pads allowed)
			(copperpour allowed)
			(footprints allowed)
		)
		(placement
			(enabled no)
			(sheetname "")
		)
		(fill
			(thermal_gap 0.5)
			(thermal_bridge_width 0.5)
			(island_removal_mode 0)
		)
		(polygon
			(pts
				(xy 298.698158 -239.230408) (xy 298.698158 -238.687102) (xy 299.252894 -238.687102) (xy 299.59427 -238.687102)
				(xy 299.59427 -239.230408) (xy 299.252894 -239.230408)
			)
		)
	)
	(zone
		(layer "In2.Cu")
		(hatch none 0.5)
		(connect_pads
			(clearance 0)
		)
		(min_thickness 0.25)
		(keepout
			(tracks allowed)
			(vias allowed)
			(pads allowed)
			(copperpour allowed)
			(footprints allowed)
		)
		(placement
			(enabled no)
			(sheetname "")
		)
		(fill
			(thermal_gap 0.5)
			(thermal_bridge_width 0.5)
			(island_removal_mode 0)
		)
		(polygon
			(pts
				(xy 50.75809 -216.280238) (xy 50.75809 -215.736932) (xy 51.312826 -215.736932) (xy 51.312826 -216.280238)
			)
		)
	)
	(zone
		(layer "In2.Cu")
		(hatch none 0.5)
		(connect_pads
			(clearance 0)
		)
		(min_thickness 0.25)
		(keepout
			(tracks allowed)
			(vias allowed)
			(pads allowed)
			(copperpour allowed)
			(footprints allowed)
		)
		(placement
			(enabled no)
			(sheetname "")
		)
		(fill
			(thermal_gap 0.5)
			(thermal_bridge_width 0.5)
			(island_removal_mode 0)
		)
		(polygon
			(pts
				(xy 420.97833 -214.884508) (xy 420.97833 -215.413082) (xy 420.44239 -215.413082) (xy 420.03218 -215.413082)
				(xy 420.03218 -214.884508) (xy 420.44239 -214.884508)
			)
		)
	)
	(zone
		(layer "In2.Cu")
		(hatch none 0.5)
		(connect_pads
			(clearance 0)
		)
		(min_thickness 0.25)
		(keepout
			(tracks allowed)
			(vias allowed)
			(pads allowed)
			(copperpour allowed)
			(footprints allowed)
		)
		(placement
			(enabled no)
			(sheetname "")
		)
		(fill
			(thermal_gap 0.5)
			(thermal_bridge_width 0.5)
			(island_removal_mode 0)
		)
		(polygon
			(pts
				(xy 173.038262 -262.484616) (xy 173.038262 -263.01319) (xy 172.502322 -263.01319) (xy 172.502322 -262.484616)
			)
		)
	)
	(zone
		(layer "In2.Cu")
		(hatch none 0.5)
		(connect_pads
			(clearance 0)
		)
		(min_thickness 0.25)
		(keepout
			(tracks allowed)
			(vias allowed)
			(pads allowed)
			(copperpour allowed)
			(footprints allowed)
		)
		(placement
			(enabled no)
			(sheetname "")
		)
		(fill
			(thermal_gap 0.5)
			(thermal_bridge_width 0.5)
			(island_removal_mode 0)
		)
		(polygon
			(pts
				(xy 173.038262 -240.384584) (xy 173.038262 -240.913158) (xy 172.502322 -240.913158) (xy 172.502322 -240.384584)
			)
		)
	)
	(zone
		(layer "In2.Cu")
		(hatch none 0.5)
		(connect_pads
			(clearance 0)
		)
		(min_thickness 0.25)
		(keepout
			(tracks allowed)
			(vias allowed)
			(pads allowed)
			(copperpour allowed)
			(footprints allowed)
		)
		(placement
			(enabled no)
			(sheetname "")
		)
		(fill
			(thermal_gap 0.5)
			(thermal_bridge_width 0.5)
			(island_removal_mode 0)
		)
		(polygon
			(pts
				(xy 420.97833 -219.984574) (xy 420.97833 -220.513148) (xy 420.44239 -220.513148) (xy 420.44239 -219.984574)
			)
		)
	)
	(zone
		(layer "In2.Cu")
		(hatch none 0.5)
		(connect_pads
			(clearance 0)
		)
		(min_thickness 0.25)
		(keepout
			(tracks allowed)
			(vias allowed)
			(pads allowed)
			(copperpour allowed)
			(footprints allowed)
		)
		(placement
			(enabled no)
			(sheetname "")
		)
		(fill
			(thermal_gap 0.5)
			(thermal_bridge_width 0.5)
			(island_removal_mode 0)
		)
		(polygon
			(pts
				(xy 173.038262 -209.784696) (xy 173.038262 -210.31327) (xy 172.502322 -210.31327) (xy 172.502322 -209.784696)
			)
		)
	)
	(zone
		(layer "In2.Cu")
		(hatch none 0.5)
		(connect_pads
			(clearance 0)
		)
		(min_thickness 0.25)
		(keepout
			(tracks allowed)
			(vias allowed)
			(pads allowed)
			(copperpour allowed)
			(footprints allowed)
		)
		(placement
			(enabled no)
			(sheetname "")
		)
		(fill
			(thermal_gap 0.5)
			(thermal_bridge_width 0.5)
			(island_removal_mode 0)
		)
		(polygon
			(pts
				(xy 420.97833 -218.284806) (xy 420.97833 -218.81338) (xy 420.44239 -218.81338) (xy 420.44239 -218.284806)
			)
		)
	)
	(zone
		(layer "In2.Cu")
		(hatch none 0.5)
		(connect_pads
			(clearance 0)
		)
		(min_thickness 0.25)
		(keepout
			(tracks allowed)
			(vias allowed)
			(pads allowed)
			(copperpour allowed)
			(footprints allowed)
		)
		(placement
			(enabled no)
			(sheetname "")
		)
		(fill
			(thermal_gap 0.5)
			(thermal_bridge_width 0.5)
			(island_removal_mode 0)
		)
		(polygon
			(pts
				(xy 157.925262 -304.984404) (xy 157.925262 -305.512978) (xy 157.389322 -305.512978) (xy 157.389322 -304.984404)
			)
		)
	)
	(zone
		(layer "In2.Cu")
		(hatch none 0.5)
		(connect_pads
			(clearance 0)
		)
		(min_thickness 0.25)
		(keepout
			(tracks allowed)
			(vias allowed)
			(pads allowed)
			(copperpour allowed)
			(footprints allowed)
		)
		(placement
			(enabled no)
			(sheetname "")
		)
		(fill
			(thermal_gap 0.5)
			(thermal_bridge_width 0.5)
			(island_removal_mode 0)
		)
		(polygon
			(pts
				(xy 173.038262 -265.88466) (xy 173.038262 -266.413234) (xy 172.502322 -266.413234) (xy 172.502322 -265.88466)
			)
		)
	)
	(zone
		(layer "In2.Cu")
		(hatch none 0.5)
		(connect_pads
			(clearance 0)
		)
		(min_thickness 0.25)
		(keepout
			(tracks allowed)
			(vias allowed)
			(pads allowed)
			(copperpour allowed)
			(footprints allowed)
		)
		(placement
			(enabled no)
			(sheetname "")
		)
		(fill
			(thermal_gap 0.5)
			(thermal_bridge_width 0.5)
			(island_removal_mode 0)
		)
		(polygon
			(pts
				(xy 298.698158 -233.280458) (xy 298.698158 -232.737152) (xy 299.252894 -232.737152) (xy 299.252894 -233.280458)
			)
		)
	)
	(zone
		(layer "In2.Cu")
		(hatch none 0.5)
		(connect_pads
			(clearance 0)
		)
		(min_thickness 0.25)
		(keepout
			(tracks allowed)
			(vias allowed)
			(pads allowed)
			(copperpour allowed)
			(footprints allowed)
		)
		(placement
			(enabled no)
			(sheetname "")
		)
		(fill
			(thermal_gap 0.5)
			(thermal_bridge_width 0.5)
			(island_removal_mode 0)
		)
		(polygon
			(pts
				(xy 157.925262 -226.784662) (xy 157.925262 -227.313236) (xy 157.389322 -227.313236) (xy 157.389322 -226.784662)
			)
		)
	)
	(zone
		(layer "In2.Cu")
		(hatch none 0.5)
		(connect_pads
			(clearance 0)
		)
		(min_thickness 0.25)
		(keepout
			(tracks allowed)
			(vias allowed)
			(pads allowed)
			(copperpour allowed)
			(footprints allowed)
		)
		(placement
			(enabled no)
			(sheetname "")
		)
		(fill
			(thermal_gap 0.5)
			(thermal_bridge_width 0.5)
			(island_removal_mode 0)
		)
		(polygon
			(pts
				(xy 298.698158 -211.180426) (xy 298.698158 -210.63712) (xy 299.252894 -210.63712) (xy 299.252894 -211.180426)
			)
		)
	)
	(zone
		(layer "In2.Cu")
		(hatch none 0.5)
		(connect_pads
			(clearance 0)
		)
		(min_thickness 0.25)
		(keepout
			(tracks allowed)
			(vias allowed)
			(pads allowed)
			(copperpour allowed)
			(footprints allowed)
		)
		(placement
			(enabled no)
			(sheetname "")
		)
		(fill
			(thermal_gap 0.5)
			(thermal_bridge_width 0.5)
			(island_removal_mode 0)
		)
		(polygon
			(pts
				(xy 313.785758 -302.980344) (xy 313.785758 -302.437038) (xy 314.340494 -302.437038) (xy 314.340494 -302.980344)
			)
		)
	)
	(zone
		(layer "In2.Cu")
		(hatch none 0.5)
		(connect_pads
			(clearance 0)
		)
		(min_thickness 0.25)
		(keepout
			(tracks allowed)
			(vias allowed)
			(pads allowed)
			(copperpour allowed)
			(footprints allowed)
		)
		(placement
			(enabled no)
			(sheetname "")
		)
		(fill
			(thermal_gap 0.5)
			(thermal_bridge_width 0.5)
			(island_removal_mode 0)
		)
		(polygon
			(pts
				(xy 420.97833 -220.834458) (xy 420.97833 -221.363032) (xy 420.44239 -221.363032) (xy 420.44239 -220.834458)
			)
		)
	)
	(zone
		(layer "In2.Cu")
		(hatch none 0.5)
		(connect_pads
			(clearance 0)
		)
		(min_thickness 0.25)
		(keepout
			(tracks allowed)
			(vias allowed)
			(pads allowed)
			(copperpour allowed)
			(footprints allowed)
		)
		(placement
			(enabled no)
			(sheetname "")
		)
		(fill
			(thermal_gap 0.5)
			(thermal_bridge_width 0.5)
			(island_removal_mode 0)
		)
		(polygon
			(pts
				(xy 76.6191 -350.733868) (xy 76.6191 -349.275908) (xy 77.37094 -349.275908) (xy 77.37094 -350.733868)
			)
		)
	)
	(zone
		(layer "In2.Cu")
		(hatch none 0.5)
		(connect_pads
			(clearance 0)
		)
		(min_thickness 0.25)
		(keepout
			(tracks allowed)
			(vias allowed)
			(pads allowed)
			(copperpour allowed)
			(footprints allowed)
		)
		(placement
			(enabled no)
			(sheetname "")
		)
		(fill
			(thermal_gap 0.5)
			(thermal_bridge_width 0.5)
			(island_removal_mode 0)
		)
		(polygon
			(pts
				(xy 116.64696 -339.382608) (xy 116.64696 -334.861408) (xy 127.99822 -334.861408) (xy 127.99822 -339.382608)
			)
		)
	)
	(zone
		(layer "In2.Cu")
		(hatch none 0.5)
		(connect_pads
			(clearance 0)
		)
		(min_thickness 0.25)
		(keepout
			(tracks allowed)
			(vias allowed)
			(pads allowed)
			(copperpour allowed)
			(footprints allowed)
		)
		(placement
			(enabled no)
			(sheetname "")
		)
		(fill
			(thermal_gap 0.5)
			(thermal_bridge_width 0.5)
			(island_removal_mode 0)
		)
		(polygon
			(pts
				(xy 405.86533 -224.234502) (xy 405.86533 -224.763076) (xy 405.32939 -224.763076) (xy 405.140668 -224.763076)
				(xy 405.092916 -224.715324) (xy 405.092916 -224.308416) (xy 405.16683 -224.234502) (xy 405.32939 -224.234502)
			)
		)
	)
	(zone
		(layer "In2.Cu")
		(hatch none 0.5)
		(connect_pads
			(clearance 0)
		)
		(min_thickness 0.25)
		(keepout
			(tracks allowed)
			(vias allowed)
			(pads allowed)
			(copperpour allowed)
			(footprints allowed)
		)
		(placement
			(enabled no)
			(sheetname "")
		)
		(fill
			(thermal_gap 0.5)
			(thermal_bridge_width 0.5)
			(island_removal_mode 0)
		)
		(polygon
			(pts
				(xy 420.97833 -306.684426) (xy 420.97833 -307.213) (xy 420.44239 -307.213) (xy 420.44239 -306.684426)
			)
		)
	)
	(zone
		(layer "In2.Cu")
		(hatch none 0.5)
		(connect_pads
			(clearance 0)
		)
		(min_thickness 0.25)
		(keepout
			(tracks allowed)
			(vias allowed)
			(pads allowed)
			(copperpour allowed)
			(footprints allowed)
		)
		(placement
			(enabled no)
			(sheetname "")
		)
		(fill
			(thermal_gap 0.5)
			(thermal_bridge_width 0.5)
			(island_removal_mode 0)
		)
		(polygon
			(pts
				(xy 65.84569 -300.430438) (xy 65.84569 -299.887132) (xy 66.400426 -299.887132) (xy 66.400426 -300.430438)
			)
		)
	)
	(zone
		(layer "In2.Cu")
		(hatch none 0.5)
		(connect_pads
			(clearance 0)
		)
		(min_thickness 0.25)
		(keepout
			(tracks allowed)
			(vias allowed)
			(pads allowed)
			(copperpour allowed)
			(footprints allowed)
		)
		(placement
			(enabled no)
			(sheetname "")
		)
		(fill
			(thermal_gap 0.5)
			(thermal_bridge_width 0.5)
			(island_removal_mode 0)
		)
		(polygon
			(pts
				(xy 313.785758 -229.880414) (xy 313.785758 -229.337108) (xy 314.340494 -229.337108) (xy 314.636912 -229.337108)
				(xy 314.636912 -229.880414) (xy 314.340494 -229.880414)
			)
		)
	)
	(zone
		(layer "In2.Cu")
		(hatch none 0.5)
		(connect_pads
			(clearance 0)
		)
		(min_thickness 0.25)
		(keepout
			(tracks allowed)
			(vias allowed)
			(pads allowed)
			(copperpour allowed)
			(footprints allowed)
		)
		(placement
			(enabled no)
			(sheetname "")
		)
		(fill
			(thermal_gap 0.5)
			(thermal_bridge_width 0.5)
			(island_removal_mode 0)
		)
		(polygon
			(pts
				(xy 65.84569 -306.380388) (xy 65.84569 -305.837082) (xy 66.400426 -305.837082) (xy 66.400426 -306.380388)
			)
		)
	)
	(zone
		(layer "In2.Cu")
		(hatch none 0.5)
		(connect_pads
			(clearance 0)
		)
		(min_thickness 0.25)
		(keepout
			(tracks allowed)
			(vias allowed)
			(pads allowed)
			(copperpour allowed)
			(footprints allowed)
		)
		(placement
			(enabled no)
			(sheetname "")
		)
		(fill
			(thermal_gap 0.5)
			(thermal_bridge_width 0.5)
			(island_removal_mode 0)
		)
		(polygon
			(pts
				(xy 106.336084 -290.610544) (xy 107.84332 -290.610544) (xy 111.257588 -290.610544) (xy 112.453674 -290.61029)
				(xy 114.01298 -292.169596) (xy 120.026684 -292.169596) (xy 121.807986 -293.950898) (xy 132.560822 -293.950644)
				(xy 133.451346 -293.06012) (xy 134.742428 -293.06012) (xy 135.837168 -294.15486) (xy 136.074404 -294.15486)
				(xy 136.401302 -293.827962) (xy 136.597136 -293.827962) (xy 136.793224 -294.02405) (xy 137.348722 -294.02405)
				(xy 137.610342 -293.76243) (xy 137.610342 -293.623746) (xy 137.520426 -293.53383) (xy 137.520426 -293.215314)
				(xy 137.871962 -292.863778) (xy 138.075924 -292.863778) (xy 138.22299 -293.010844) (xy 138.517122 -293.010844)
				(xy 139.963398 -291.564568) (xy 139.963398 -291.229796) (xy 139.5222 -290.788598) (xy 139.521946 -287.896046)
				(xy 140.099796 -287.318196) (xy 140.099796 -284.823154) (xy 139.842748 -284.56636) (xy 139.842748 -284.139132)
				(xy 139.842748 -282.95219) (xy 139.839446 -282.948888) (xy 139.839446 -282.838652) (xy 139.128246 -282.127452)
				(xy 139.128246 -281.653488) (xy 139.128246 -281.104848) (xy 139.342622 -280.890472) (xy 139.342622 -280.827734)
				(xy 139.128246 -280.613358) (xy 139.128246 -280.549096) (xy 139.289028 -280.388314) (xy 139.289028 -280.234644)
				(xy 139.22121 -280.166826) (xy 139.22121 -279.289002) (xy 139.24153 -279.268682) (xy 139.513564 -279.268682)
				(xy 139.96289 -279.718008) (xy 140.03782 -279.718008) (xy 140.47597 -279.279858) (xy 140.47597 -279.230328)
				(xy 139.87272 -278.627078) (xy 139.87272 -278.572468) (xy 141.413992 -277.031196) (xy 141.413992 -276.920706)
				(xy 140.95476 -276.461474) (xy 140.95476 -256.709672) (xy 140.886942 -256.641854) (xy 140.157708 -256.641854)
				(xy 140.064744 -256.54889) (xy 140.064744 -255.847088) (xy 140.064744 -255.783842) (xy 140.107162 -255.741424)
				(xy 140.514324 -255.741424) (xy 140.5763 -255.679448) (xy 140.5763 -253.982728) (xy 140.510006 -253.916434)
				(xy 139.83081 -253.916434) (xy 139.57173 -253.657354) (xy 134.464044 -253.657354) (xy 134.4549 -253.64821)
				(xy 134.4549 -252.98527) (xy 134.293864 -252.824234) (xy 133.773672 -252.824234) (xy 133.573774 -253.024132)
				(xy 133.573774 -253.027688) (xy 133.064504 -253.027688) (xy 131.152646 -253.586488) (xy 131.025138 -253.586488)
				(xy 130.237738 -252.799088) (xy 130.237738 -252.598936) (xy 130.398266 -252.438408) (xy 130.417062 -252.419612)
				(xy 134.157466 -248.678954) (xy 136.821672 -248.678954) (xy 137.040112 -248.678954) (xy 138.086338 -247.632728)
				(xy 138.086338 -247.27154) (xy 138.540236 -246.817642) (xy 138.540236 -246.59844) (xy 138.540236 -246.549418)
				(xy 138.52779 -246.536972) (xy 138.52779 -246.492522) (xy 138.999722 -246.02059) (xy 139.198096 -246.02059)
				(xy 139.25169 -245.966996) (xy 139.25169 -245.598696) (xy 139.719812 -245.130574) (xy 139.719812 -243.657882)
				(xy 139.483846 -243.421916) (xy 139.483846 -242.138962) (xy 139.555474 -242.067334) (xy 140.436854 -242.067334)
				(xy 140.589 -241.915188) (xy 140.589 -238.041688) (xy 140.457428 -237.910116) (xy 139.957302 -237.910116)
				(xy 139.775438 -237.728252) (xy 139.775438 -236.572298) (xy 140.245084 -236.572298) (xy 140.31087 -236.572298)
				(xy 140.393674 -236.489494) (xy 140.393674 -235.671868) (xy 140.393674 -235.474256) (xy 140.48486 -235.38307)
				(xy 140.722858 -235.38307) (xy 140.7541 -235.351828) (xy 140.7541 -234.701588) (xy 140.69568 -234.643168)
				(xy 140.161264 -234.643168) (xy 140.132562 -234.614466) (xy 139.460732 -234.614466) (xy 139.21232 -234.862878)
				(xy 138.50747 -234.862878) (xy 138.47064 -234.826048) (xy 138.47064 -234.121452) (xy 138.506454 -234.085638)
				(xy 138.629644 -234.085638) (xy 138.631422 -234.087416) (xy 138.813794 -234.087416) (xy 139.270994 -233.630216)
				(xy 140.698982 -233.630216) (xy 140.747496 -233.581702) (xy 140.747496 -231.628442) (xy 141.65961 -231.628188)
				(xy 141.819884 -231.467914) (xy 141.819884 -229.06355) (xy 141.730476 -228.974142) (xy 141.178534 -228.974142)
				(xy 140.10894 -227.904548) (xy 140.10894 -227.823776) (xy 140.44549 -227.487226) (xy 140.44549 -227.305362)
				(xy 139.784074 -226.643946) (xy 139.784074 -226.450906) (xy 140.23467 -226.00031) (xy 141.815058 -226.00031)
				(xy 141.87932 -225.936048) (xy 141.87932 -221.841568) (xy 143.128238 -220.59265) (xy 143.128238 -220.464126)
				(xy 139.689078 -217.024966) (xy 138.779504 -215.97112) (xy 138.779504 -215.326722) (xy 136.672828 -213.220046)
				(xy 111.256064 -213.220554) (xy 107.841796 -213.220554) (xy 106.33456 -213.220554)
			)
		)
	)
	(zone
		(layer "In2.Cu")
		(hatch none 0.5)
		(connect_pads
			(clearance 0)
		)
		(min_thickness 0.25)
		(keepout
			(tracks allowed)
			(vias allowed)
			(pads allowed)
			(copperpour allowed)
			(footprints allowed)
		)
		(placement
			(enabled no)
			(sheetname "")
		)
		(fill
			(thermal_gap 0.5)
			(thermal_bridge_width 0.5)
			(island_removal_mode 0)
		)
		(polygon
			(pts
				(xy 340.72576 -338.392008) (xy 340.72576 -335.509108) (xy 353.22256 -335.509108) (xy 353.22256 -338.392008)
			)
		)
	)
	(zone
		(layer "In2.Cu")
		(hatch none 0.5)
		(connect_pads
			(clearance 0)
		)
		(min_thickness 0.25)
		(keepout
			(tracks allowed)
			(vias allowed)
			(pads allowed)
			(copperpour allowed)
			(footprints allowed)
		)
		(placement
			(enabled no)
			(sheetname "")
		)
		(fill
			(thermal_gap 0.5)
			(thermal_bridge_width 0.5)
			(island_removal_mode 0)
		)
		(polygon
			(pts
				(xy 173.038262 -291.384482) (xy 173.038262 -291.913056) (xy 172.502322 -291.913056) (xy 172.502322 -291.384482)
			)
		)
	)
	(zone
		(layer "In2.Cu")
		(hatch none 0.5)
		(connect_pads
			(clearance 0)
		)
		(min_thickness 0.25)
		(keepout
			(tracks allowed)
			(vias allowed)
			(pads allowed)
			(copperpour allowed)
			(footprints allowed)
		)
		(placement
			(enabled no)
			(sheetname "")
		)
		(fill
			(thermal_gap 0.5)
			(thermal_bridge_width 0.5)
			(island_removal_mode 0)
		)
		(polygon
			(pts
				(xy 173.038262 -270.134842) (xy 173.038262 -270.663416) (xy 172.502322 -270.663416) (xy 172.502322 -270.134842)
			)
		)
	)
	(zone
		(layer "In2.Cu")
		(hatch none 0.5)
		(connect_pads
			(clearance 0)
		)
		(min_thickness 0.25)
		(keepout
			(tracks allowed)
			(vias allowed)
			(pads allowed)
			(copperpour allowed)
			(footprints allowed)
		)
		(placement
			(enabled no)
			(sheetname "")
		)
		(fill
			(thermal_gap 0.5)
			(thermal_bridge_width 0.5)
			(island_removal_mode 0)
		)
		(polygon
			(pts
				(xy 294.59809 -243.480336) (xy 294.59809 -242.93703) (xy 295.152826 -242.93703) (xy 295.152826 -243.480336)
			)
		)
	)
	(zone
		(layer "In2.Cu")
		(hatch none 0.5)
		(connect_pads
			(clearance 0)
		)
		(min_thickness 0.25)
		(keepout
			(tracks allowed)
			(vias allowed)
			(pads allowed)
			(copperpour allowed)
			(footprints allowed)
		)
		(placement
			(enabled no)
			(sheetname "")
		)
		(fill
			(thermal_gap 0.5)
			(thermal_bridge_width 0.5)
			(island_removal_mode 0)
		)
		(polygon
			(pts
				(xy 50.78349 -278.33066) (xy 50.78349 -277.787354) (xy 51.338226 -277.787354) (xy 51.338226 -278.33066)
			)
		)
	)
	(zone
		(layer "In2.Cu")
		(hatch none 0.5)
		(connect_pads
			(clearance 0)
		)
		(min_thickness 0.25)
		(keepout
			(tracks allowed)
			(vias allowed)
			(pads allowed)
			(copperpour allowed)
			(footprints allowed)
		)
		(placement
			(enabled no)
			(sheetname "")
		)
		(fill
			(thermal_gap 0.5)
			(thermal_bridge_width 0.5)
			(island_removal_mode 0)
		)
		(polygon
			(pts
				(xy 157.925262 -302.434498) (xy 157.925262 -302.963072) (xy 157.389322 -302.963072) (xy 157.389322 -302.434498)
			)
		)
	)
	(zone
		(layer "In2.Cu")
		(hatch none 0.5)
		(connect_pads
			(clearance 0)
		)
		(min_thickness 0.25)
		(keepout
			(tracks allowed)
			(vias allowed)
			(pads allowed)
			(copperpour allowed)
			(footprints allowed)
		)
		(placement
			(enabled no)
			(sheetname "")
		)
		(fill
			(thermal_gap 0.5)
			(thermal_bridge_width 0.5)
			(island_removal_mode 0)
		)
		(polygon
			(pts
				(xy 405.89073 -226.784662) (xy 405.89073 -227.313236) (xy 405.35479 -227.313236) (xy 405.35479 -226.784662)
			)
		)
	)
	(zone
		(layer "In2.Cu")
		(hatch none 0.5)
		(connect_pads
			(clearance 0)
		)
		(min_thickness 0.25)
		(keepout
			(tracks allowed)
			(vias allowed)
			(pads allowed)
			(copperpour allowed)
			(footprints allowed)
		)
		(placement
			(enabled no)
			(sheetname "")
		)
		(fill
			(thermal_gap 0.5)
			(thermal_bridge_width 0.5)
			(island_removal_mode 0)
		)
		(polygon
			(pts
				(xy 321.99072 -348.592648) (xy 321.99072 -347.330268) (xy 322.71462 -347.330268) (xy 322.71462 -348.592648)
			)
		)
	)
	(zone
		(layer "In2.Cu")
		(hatch none 0.5)
		(connect_pads
			(clearance 0)
		)
		(min_thickness 0.25)
		(keepout
			(tracks allowed)
			(vias allowed)
			(pads allowed)
			(copperpour allowed)
			(footprints allowed)
		)
		(placement
			(enabled no)
			(sheetname "")
		)
		(fill
			(thermal_gap 0.5)
			(thermal_bridge_width 0.5)
			(island_removal_mode 0)
		)
		(polygon
			(pts
				(xy 420.97833 -212.334602) (xy 420.97833 -212.863176) (xy 420.44239 -212.863176) (xy 420.44239 -212.334602)
			)
		)
	)
	(zone
		(layer "In2.Cu")
		(hatch none 0.5)
		(connect_pads
			(clearance 0)
		)
		(min_thickness 0.25)
		(keepout
			(tracks allowed)
			(vias allowed)
			(pads allowed)
			(copperpour allowed)
			(footprints allowed)
		)
		(placement
			(enabled no)
			(sheetname "")
		)
		(fill
			(thermal_gap 0.5)
			(thermal_bridge_width 0.5)
			(island_removal_mode 0)
		)
		(polygon
			(pts
				(xy 298.698158 -216.280238) (xy 298.698158 -215.736932) (xy 299.252894 -215.736932) (xy 299.252894 -216.280238)
			)
		)
	)
	(zone
		(layer "In2.Cu")
		(hatch none 0.5)
		(connect_pads
			(clearance 0)
		)
		(min_thickness 0.25)
		(keepout
			(tracks allowed)
			(vias allowed)
			(pads allowed)
			(copperpour allowed)
			(footprints allowed)
		)
		(placement
			(enabled no)
			(sheetname "")
		)
		(fill
			(thermal_gap 0.5)
			(thermal_bridge_width 0.5)
			(island_removal_mode 0)
		)
		(polygon
			(pts
				(xy 298.723558 -274.930616) (xy 298.723558 -274.38731) (xy 299.278294 -274.38731) (xy 299.278294 -274.930616)
			)
		)
	)
	(zone
		(layer "In2.Cu")
		(hatch none 0.5)
		(connect_pads
			(clearance 0)
		)
		(min_thickness 0.25)
		(keepout
			(tracks allowed)
			(vias allowed)
			(pads allowed)
			(copperpour allowed)
			(footprints allowed)
		)
		(placement
			(enabled no)
			(sheetname "")
		)
		(fill
			(thermal_gap 0.5)
			(thermal_bridge_width 0.5)
			(island_removal_mode 0)
		)
		(polygon
			(pts
				(xy 420.97833 -212.334856) (xy 420.97833 -212.86343) (xy 420.44239 -212.86343) (xy 420.44239 -212.334856)
			)
		)
	)
	(zone
		(layer "In2.Cu")
		(hatch none 0.5)
		(connect_pads
			(clearance 0)
		)
		(min_thickness 0.25)
		(keepout
			(tracks allowed)
			(vias allowed)
			(pads allowed)
			(copperpour allowed)
			(footprints allowed)
		)
		(placement
			(enabled no)
			(sheetname "")
		)
		(fill
			(thermal_gap 0.5)
			(thermal_bridge_width 0.5)
			(island_removal_mode 0)
		)
		(polygon
			(pts
				(xy 46.658022 -246.030242) (xy 46.658022 -245.486936) (xy 47.212758 -245.486936) (xy 47.212758 -246.030242)
			)
		)
	)
	(zone
		(layer "In2.Cu")
		(hatch none 0.5)
		(connect_pads
			(clearance 0)
		)
		(min_thickness 0.25)
		(keepout
			(tracks allowed)
			(vias allowed)
			(pads allowed)
			(copperpour allowed)
			(footprints allowed)
		)
		(placement
			(enabled no)
			(sheetname "")
		)
		(fill
			(thermal_gap 0.5)
			(thermal_bridge_width 0.5)
			(island_removal_mode 0)
		)
		(polygon
			(pts
				(xy 173.038262 -232.734612) (xy 173.038262 -233.263186) (xy 172.502322 -233.263186) (xy 172.502322 -232.734612)
			)
		)
	)
	(zone
		(layer "In2.Cu")
		(hatch none 0.5)
		(connect_pads
			(clearance 0)
		)
		(min_thickness 0.25)
		(keepout
			(tracks allowed)
			(vias allowed)
			(pads allowed)
			(copperpour allowed)
			(footprints allowed)
		)
		(placement
			(enabled no)
			(sheetname "")
		)
		(fill
			(thermal_gap 0.5)
			(thermal_bridge_width 0.5)
			(island_removal_mode 0)
		)
		(polygon
			(pts
				(xy 425.078398 -259.93471) (xy 425.078398 -260.463284) (xy 424.542458 -260.463284) (xy 424.542458 -259.93471)
			)
		)
	)
	(zone
		(layer "In2.Cu")
		(hatch none 0.5)
		(connect_pads
			(clearance 0)
		)
		(min_thickness 0.25)
		(keepout
			(tracks allowed)
			(vias allowed)
			(pads allowed)
			(copperpour allowed)
			(footprints allowed)
		)
		(placement
			(enabled no)
			(sheetname "")
		)
		(fill
			(thermal_gap 0.5)
			(thermal_bridge_width 0.5)
			(island_removal_mode 0)
		)
		(polygon
			(pts
				(xy 405.89073 -307.534564) (xy 405.89073 -308.063138) (xy 405.35479 -308.063138) (xy 405.35479 -307.534564)
			)
		)
	)
	(zone
		(layer "In2.Cu")
		(hatch none 0.5)
		(connect_pads
			(clearance 0)
		)
		(min_thickness 0.25)
		(keepout
			(tracks allowed)
			(vias allowed)
			(pads allowed)
			(copperpour allowed)
			(footprints allowed)
		)
		(placement
			(enabled no)
			(sheetname "")
		)
		(fill
			(thermal_gap 0.5)
			(thermal_bridge_width 0.5)
			(island_removal_mode 0)
		)
		(polygon
			(pts
				(xy 50.78349 -312.330338) (xy 50.78349 -311.787032) (xy 51.338226 -311.787032) (xy 51.338226 -312.330338)
			)
		)
	)
	(zone
		(layer "In2.Cu")
		(hatch none 0.5)
		(connect_pads
			(clearance 0)
		)
		(min_thickness 0.25)
		(keepout
			(tracks allowed)
			(vias allowed)
			(pads allowed)
			(copperpour allowed)
			(footprints allowed)
		)
		(placement
			(enabled no)
			(sheetname "")
		)
		(fill
			(thermal_gap 0.5)
			(thermal_bridge_width 0.5)
			(island_removal_mode 0)
		)
		(polygon
			(pts
				(xy 298.698158 -251.980446) (xy 298.698158 -251.43714) (xy 299.252894 -251.43714) (xy 299.252894 -251.980446)
			)
		)
	)
	(zone
		(layer "In2.Cu")
		(hatch none 0.5)
		(connect_pads
			(clearance 0)
		)
		(min_thickness 0.25)
		(keepout
			(tracks allowed)
			(vias allowed)
			(pads allowed)
			(copperpour allowed)
			(footprints allowed)
		)
		(placement
			(enabled no)
			(sheetname "")
		)
		(fill
			(thermal_gap 0.5)
			(thermal_bridge_width 0.5)
			(island_removal_mode 0)
		)
		(polygon
			(pts
				(xy 420.97833 -247.184418) (xy 420.97833 -247.712992) (xy 420.44239 -247.712992) (xy 420.44239 -247.184418)
			)
		)
	)
	(zone
		(layer "In2.Cu")
		(hatch none 0.5)
		(connect_pads
			(clearance 0)
		)
		(min_thickness 0.25)
		(keepout
			(tracks allowed)
			(vias allowed)
			(pads allowed)
			(copperpour allowed)
			(footprints allowed)
		)
		(placement
			(enabled no)
			(sheetname "")
		)
		(fill
			(thermal_gap 0.5)
			(thermal_bridge_width 0.5)
			(island_removal_mode 0)
		)
		(polygon
			(pts
				(xy 420.97833 -311.784492) (xy 420.97833 -312.313066) (xy 420.44239 -312.313066) (xy 420.44239 -311.784492)
			)
		)
	)
	(zone
		(layer "In2.Cu")
		(hatch none 0.5)
		(connect_pads
			(clearance 0)
		)
		(min_thickness 0.25)
		(keepout
			(tracks allowed)
			(vias allowed)
			(pads allowed)
			(copperpour allowed)
			(footprints allowed)
		)
		(placement
			(enabled no)
			(sheetname "")
		)
		(fill
			(thermal_gap 0.5)
			(thermal_bridge_width 0.5)
			(island_removal_mode 0)
		)
		(polygon
			(pts
				(xy 173.038262 -217.434668) (xy 173.038262 -217.963242) (xy 172.502322 -217.963242) (xy 172.502322 -217.434668)
			)
		)
	)
	(zone
		(layer "In2.Cu")
		(hatch none 0.5)
		(connect_pads
			(clearance 0)
		)
		(min_thickness 0.25)
		(keepout
			(tracks allowed)
			(vias allowed)
			(pads allowed)
			(copperpour allowed)
			(footprints allowed)
		)
		(placement
			(enabled no)
			(sheetname "")
		)
		(fill
			(thermal_gap 0.5)
			(thermal_bridge_width 0.5)
			(island_removal_mode 0)
		)
		(polygon
			(pts
				(xy 173.038262 -232.734866) (xy 173.038262 -233.26344) (xy 172.502322 -233.26344) (xy 172.502322 -232.734866)
			)
		)
	)
	(zone
		(layer "In2.Cu")
		(hatch none 0.5)
		(connect_pads
			(clearance 0)
		)
		(min_thickness 0.25)
		(keepout
			(tracks allowed)
			(vias allowed)
			(pads allowed)
			(copperpour allowed)
			(footprints allowed)
		)
		(placement
			(enabled no)
			(sheetname "")
		)
		(fill
			(thermal_gap 0.5)
			(thermal_bridge_width 0.5)
			(island_removal_mode 0)
		)
		(polygon
			(pts
				(xy 157.950662 -305.834542) (xy 157.950662 -306.363116) (xy 157.414722 -306.363116) (xy 157.414722 -305.834542)
			)
		)
	)
	(zone
		(layer "In2.Cu")
		(hatch none 0.5)
		(connect_pads
			(clearance 0)
		)
		(min_thickness 0.25)
		(keepout
			(tracks allowed)
			(vias allowed)
			(pads allowed)
			(copperpour allowed)
			(footprints allowed)
		)
		(placement
			(enabled no)
			(sheetname "")
		)
		(fill
			(thermal_gap 0.5)
			(thermal_bridge_width 0.5)
			(island_removal_mode 0)
		)
		(polygon
			(pts
				(xy 139.839446 -283.546296) (xy 139.839446 -282.948888) (xy 139.839446 -282.803092) (xy 139.128246 -282.091892)
				(xy 139.128246 -281.653488) (xy 139.128246 -281.104848) (xy 139.342622 -280.890472) (xy 139.342622 -280.827734)
				(xy 139.128246 -280.613358) (xy 139.128246 -280.549096) (xy 139.289028 -280.388314) (xy 139.289028 -280.234644)
				(xy 139.22121 -280.166826) (xy 139.22121 -279.289002) (xy 139.24153 -279.268682) (xy 139.513564 -279.268682)
				(xy 139.96289 -279.718008) (xy 140.03782 -279.718008) (xy 140.47597 -279.279858) (xy 140.47597 -279.230328)
				(xy 139.87272 -278.627078) (xy 139.87272 -278.572468) (xy 141.3383 -277.106888) (xy 141.490446 -277.106888)
				(xy 141.521942 -277.138384) (xy 142.16253 -277.778718) (xy 142.68323 -277.778718) (xy 143.052546 -278.148034)
				(xy 143.052546 -278.633174) (xy 143.054578 -278.63546) (xy 143.580358 -280.112978) (xy 144.101566 -281.038554)
				(xy 145.757646 -282.694634) (xy 146.209766 -283.146754) (xy 146.209766 -283.857192) (xy 145.706846 -284.360112)
				(xy 140.149326 -284.360112) (xy 139.839446 -284.050232)
			)
		)
	)
	(zone
		(layer "In2.Cu")
		(hatch none 0.5)
		(connect_pads
			(clearance 0)
		)
		(min_thickness 0.25)
		(keepout
			(tracks allowed)
			(vias allowed)
			(pads allowed)
			(copperpour allowed)
			(footprints allowed)
		)
		(placement
			(enabled no)
			(sheetname "")
		)
		(fill
			(thermal_gap 0.5)
			(thermal_bridge_width 0.5)
			(island_removal_mode 0)
		)
		(polygon
			(pts
				(xy 420.97833 -205.534514) (xy 420.97833 -206.063088) (xy 420.44239 -206.063088) (xy 420.44239 -205.534514)
			)
		)
	)
	(zone
		(layer "In2.Cu")
		(hatch none 0.5)
		(connect_pads
			(clearance 0)
		)
		(min_thickness 0.25)
		(keepout
			(tracks allowed)
			(vias allowed)
			(pads allowed)
			(copperpour allowed)
			(footprints allowed)
		)
		(placement
			(enabled no)
			(sheetname "")
		)
		(fill
			(thermal_gap 0.5)
			(thermal_bridge_width 0.5)
			(island_removal_mode 0)
		)
		(polygon
			(pts
				(xy 146.518884 -254.06477) (xy 144.946116 -254.06477) (xy 144.944338 -254.062992) (xy 144.483074 -254.524256)
				(xy 142.677896 -254.524256) (xy 142.076424 -253.922784) (xy 140.78331 -253.923038) (xy 140.5763 -254.130048)
				(xy 140.5763 -255.679448) (xy 140.514324 -255.741424) (xy 140.107162 -255.741424) (xy 140.064744 -255.783842)
				(xy 140.064744 -255.847088) (xy 140.064744 -256.54889) (xy 140.157708 -256.641854) (xy 140.886942 -256.641854)
				(xy 140.95476 -256.709672) (xy 140.95476 -260.366764) (xy 145.644108 -260.366764) (xy 147.11299 -261.835392)
				(xy 147.252944 -261.835392) (xy 148.341588 -260.746494) (xy 148.341588 -254.309626) (xy 147.864068 -253.832106)
				(xy 146.945096 -253.832106) (xy 146.751548 -253.832106)
			)
		)
	)
	(zone
		(layer "In2.Cu")
		(hatch none 0.5)
		(connect_pads
			(clearance 0)
		)
		(min_thickness 0.25)
		(keepout
			(tracks allowed)
			(vias allowed)
			(pads allowed)
			(copperpour allowed)
			(footprints allowed)
		)
		(placement
			(enabled no)
			(sheetname "")
		)
		(fill
			(thermal_gap 0.5)
			(thermal_bridge_width 0.5)
			(island_removal_mode 0)
		)
		(polygon
			(pts
				(xy 405.89073 -228.484684) (xy 405.89073 -229.013258) (xy 405.35479 -229.013258) (xy 405.35479 -228.484684)
			)
		)
	)
	(zone
		(layer "In2.Cu")
		(hatch none 0.5)
		(connect_pads
			(clearance 0)
		)
		(min_thickness 0.25)
		(keepout
			(tracks allowed)
			(vias allowed)
			(pads allowed)
			(copperpour allowed)
			(footprints allowed)
		)
		(placement
			(enabled no)
			(sheetname "")
		)
		(fill
			(thermal_gap 0.5)
			(thermal_bridge_width 0.5)
			(island_removal_mode 0)
		)
		(polygon
			(pts
				(xy 428.49673 -242.084606) (xy 428.49673 -242.61318) (xy 427.96079 -242.61318) (xy 427.96079 -242.084606)
			)
		)
	)
	(zone
		(layer "In2.Cu")
		(hatch none 0.5)
		(connect_pads
			(clearance 0)
		)
		(min_thickness 0.25)
		(keepout
			(tracks allowed)
			(vias allowed)
			(pads allowed)
			(copperpour allowed)
			(footprints allowed)
		)
		(placement
			(enabled no)
			(sheetname "")
		)
		(fill
			(thermal_gap 0.5)
			(thermal_bridge_width 0.5)
			(island_removal_mode 0)
		)
		(polygon
			(pts
				(xy 420.97833 -220.834712) (xy 420.97833 -221.363286) (xy 420.44239 -221.363286) (xy 420.44239 -220.834712)
			)
		)
	)
	(zone
		(layer "In2.Cu")
		(hatch none 0.5)
		(connect_pads
			(clearance 0)
		)
		(min_thickness 0.25)
		(keepout
			(tracks allowed)
			(vias allowed)
			(pads allowed)
			(copperpour allowed)
			(footprints allowed)
		)
		(placement
			(enabled no)
			(sheetname "")
		)
		(fill
			(thermal_gap 0.5)
			(thermal_bridge_width 0.5)
			(island_removal_mode 0)
		)
		(polygon
			(pts
				(xy 173.038262 -249.734578) (xy 173.038262 -250.263152) (xy 172.502322 -250.263152) (xy 172.502322 -249.734578)
			)
		)
	)
	(zone
		(layer "In2.Cu")
		(hatch none 0.5)
		(connect_pads
			(clearance 0)
		)
		(min_thickness 0.25)
		(keepout
			(tracks allowed)
			(vias allowed)
			(pads allowed)
			(copperpour allowed)
			(footprints allowed)
		)
		(placement
			(enabled no)
			(sheetname "")
		)
		(fill
			(thermal_gap 0.5)
			(thermal_bridge_width 0.5)
			(island_removal_mode 0)
		)
		(polygon
			(pts
				(xy 405.89073 -299.034454) (xy 405.89073 -299.563028) (xy 405.35479 -299.563028) (xy 405.35479 -299.034454)
			)
		)
	)
	(zone
		(layer "In2.Cu")
		(hatch none 0.5)
		(connect_pads
			(clearance 0)
		)
		(min_thickness 0.25)
		(keepout
			(tracks allowed)
			(vias allowed)
			(pads allowed)
			(copperpour allowed)
			(footprints allowed)
		)
		(placement
			(enabled no)
			(sheetname "")
		)
		(fill
			(thermal_gap 0.5)
			(thermal_bridge_width 0.5)
			(island_removal_mode 0)
		)
		(polygon
			(pts
				(xy 177.13833 -260.784594) (xy 177.13833 -261.313168) (xy 176.60239 -261.313168) (xy 176.60239 -260.784594)
			)
		)
	)
	(zone
		(layer "In2.Cu")
		(hatch none 0.5)
		(connect_pads
			(clearance 0)
		)
		(min_thickness 0.25)
		(keepout
			(tracks allowed)
			(vias allowed)
			(pads allowed)
			(copperpour allowed)
			(footprints allowed)
		)
		(placement
			(enabled no)
			(sheetname "")
		)
		(fill
			(thermal_gap 0.5)
			(thermal_bridge_width 0.5)
			(island_removal_mode 0)
		)
		(polygon
			(pts
				(xy 173.038262 -246.334534) (xy 173.038262 -246.863108) (xy 172.502322 -246.863108) (xy 172.502322 -246.334534)
			)
		)
	)
	(zone
		(layer "In2.Cu")
		(hatch none 0.5)
		(connect_pads
			(clearance 0)
		)
		(min_thickness 0.25)
		(keepout
			(tracks allowed)
			(vias allowed)
			(pads allowed)
			(copperpour allowed)
			(footprints allowed)
		)
		(placement
			(enabled no)
			(sheetname "")
		)
		(fill
			(thermal_gap 0.5)
			(thermal_bridge_width 0.5)
			(island_removal_mode 0)
		)
		(polygon
			(pts
				(xy 388.89686 -265.417046) (xy 391.442448 -265.417046) (xy 394.54582 -268.520418) (xy 395.079728 -268.520418)
				(xy 395.24686 -268.353286) (xy 395.24686 -267.819378) (xy 395.24686 -264.927588) (xy 395.322044 -264.927588)
				(xy 395.398244 -264.851388) (xy 395.398244 -262.514588) (xy 393.250166 -260.366764) (xy 388.89686 -260.366764)
			)
		)
	)
	(zone
		(layer "In2.Cu")
		(hatch none 0.5)
		(connect_pads
			(clearance 0)
		)
		(min_thickness 0.25)
		(keepout
			(tracks allowed)
			(vias allowed)
			(pads allowed)
			(copperpour allowed)
			(footprints allowed)
		)
		(placement
			(enabled no)
			(sheetname "")
		)
		(fill
			(thermal_gap 0.5)
			(thermal_bridge_width 0.5)
			(island_removal_mode 0)
		)
		(polygon
			(pts
				(xy 420.97833 -221.684596) (xy 420.97833 -222.21317) (xy 420.44239 -222.21317) (xy 420.44239 -221.684596)
			)
		)
	)
	(zone
		(layer "In2.Cu")
		(hatch none 0.5)
		(connect_pads
			(clearance 0)
		)
		(min_thickness 0.25)
		(keepout
			(tracks allowed)
			(vias allowed)
			(pads allowed)
			(copperpour allowed)
			(footprints allowed)
		)
		(placement
			(enabled no)
			(sheetname "")
		)
		(fill
			(thermal_gap 0.5)
			(thermal_bridge_width 0.5)
			(island_removal_mode 0)
		)
		(polygon
			(pts
				(xy 420.97833 -218.284552) (xy 420.97833 -218.813126) (xy 420.44239 -218.813126) (xy 420.44239 -218.284552)
			)
		)
	)
	(zone
		(layer "In2.Cu")
		(hatch none 0.5)
		(connect_pads
			(clearance 0)
		)
		(min_thickness 0.25)
		(keepout
			(tracks allowed)
			(vias allowed)
			(pads allowed)
			(copperpour allowed)
			(footprints allowed)
		)
		(placement
			(enabled no)
			(sheetname "")
		)
		(fill
			(thermal_gap 0.5)
			(thermal_bridge_width 0.5)
			(island_removal_mode 0)
		)
		(polygon
			(pts
				(xy 173.038262 -275.2344) (xy 173.038262 -275.762974) (xy 172.502322 -275.762974) (xy 172.502322 -275.2344)
			)
		)
	)
	(zone
		(layer "In2.Cu")
		(hatch none 0.5)
		(connect_pads
			(clearance 0)
		)
		(min_thickness 0.25)
		(keepout
			(tracks allowed)
			(vias allowed)
			(pads allowed)
			(copperpour allowed)
			(footprints allowed)
		)
		(placement
			(enabled no)
			(sheetname "")
		)
		(fill
			(thermal_gap 0.5)
			(thermal_bridge_width 0.5)
			(island_removal_mode 0)
		)
		(polygon
			(pts
				(xy 298.698158 -240.93043) (xy 298.698158 -240.387124) (xy 299.252894 -240.387124) (xy 299.252894 -240.93043)
			)
		)
	)
	(zone
		(layer "In2.Cu")
		(hatch none 0.5)
		(connect_pads
			(clearance 0)
		)
		(min_thickness 0.25)
		(keepout
			(tracks allowed)
			(vias allowed)
			(pads allowed)
			(copperpour allowed)
			(footprints allowed)
		)
		(placement
			(enabled no)
			(sheetname "")
		)
		(fill
			(thermal_gap 0.5)
			(thermal_bridge_width 0.5)
			(island_removal_mode 0)
		)
		(polygon
			(pts
				(xy 157.950662 -231.03459) (xy 157.950662 -231.563164) (xy 157.414722 -231.563164) (xy 157.414722 -231.03459)
			)
		)
	)
	(zone
		(layer "In2.Cu")
		(hatch none 0.5)
		(connect_pads
			(clearance 0)
		)
		(min_thickness 0.25)
		(keepout
			(tracks allowed)
			(vias allowed)
			(pads allowed)
			(copperpour allowed)
			(footprints allowed)
		)
		(placement
			(enabled no)
			(sheetname "")
		)
		(fill
			(thermal_gap 0.5)
			(thermal_bridge_width 0.5)
			(island_removal_mode 0)
		)
		(polygon
			(pts
				(xy 170.75404 -358.224328) (xy 170.75404 -357.020368) (xy 172.51426 -357.020368) (xy 172.51426 -358.224328)
			)
		)
	)
	(zone
		(layer "In2.Cu")
		(hatch none 0.5)
		(connect_pads
			(clearance 0)
		)
		(min_thickness 0.25)
		(keepout
			(tracks allowed)
			(vias allowed)
			(pads allowed)
			(copperpour allowed)
			(footprints allowed)
		)
		(placement
			(enabled no)
			(sheetname "")
		)
		(fill
			(thermal_gap 0.5)
			(thermal_bridge_width 0.5)
			(island_removal_mode 0)
		)
		(polygon
			(pts
				(xy 141.133576 -251.304044) (xy 142.799562 -249.638058) (xy 142.857474 -249.638058) (xy 142.878048 -249.617484)
				(xy 142.951708 -249.543824) (xy 142.951708 -249.539252) (xy 142.953232 -249.537728) (xy 142.9766 -249.537728)
				(xy 146.66722 -249.537728) (xy 146.796252 -249.537728) (xy 146.854164 -249.479816) (xy 147.110196 -249.479816)
				(xy 147.27936 -249.310652) (xy 147.540726 -249.310652) (xy 148.213826 -248.637552) (xy 148.668486 -248.637552)
				(xy 149.963886 -247.342152) (xy 150.245826 -247.342152) (xy 150.565866 -247.022112) (xy 150.565866 -246.981472)
				(xy 150.149306 -246.564912) (xy 140.954506 -246.564912) (xy 140.574776 -246.564912) (xy 140.574776 -246.422418)
				(xy 139.994894 -245.842536) (xy 139.994894 -244.905276) (xy 139.79906 -244.709442) (xy 139.726162 -244.709442)
				(xy 139.719812 -244.715792) (xy 139.719812 -245.130574) (xy 139.25169 -245.598696) (xy 139.25169 -245.966996)
				(xy 139.198096 -246.02059) (xy 138.999722 -246.02059) (xy 138.52779 -246.492522) (xy 138.52779 -246.536972)
				(xy 138.540236 -246.549418) (xy 138.540236 -246.817642) (xy 138.086338 -247.27154) (xy 138.086338 -247.632728)
				(xy 137.040112 -248.678954) (xy 136.821672 -248.678954) (xy 134.401814 -248.678954) (xy 134.378192 -248.702576)
				(xy 134.378192 -249.484134) (xy 136.200896 -251.306838) (xy 139.58824 -251.306838) (xy 139.59078 -251.304298)
			)
		)
	)
	(zone
		(layer "In2.Cu")
		(hatch none 0.5)
		(connect_pads
			(clearance 0)
		)
		(min_thickness 0.25)
		(keepout
			(tracks allowed)
			(vias allowed)
			(pads allowed)
			(copperpour allowed)
			(footprints allowed)
		)
		(placement
			(enabled no)
			(sheetname "")
		)
		(fill
			(thermal_gap 0.5)
			(thermal_bridge_width 0.5)
			(island_removal_mode 0)
		)
		(polygon
			(pts
				(xy 420.97833 -293.084504) (xy 420.97833 -293.613078) (xy 420.44239 -293.613078) (xy 419.914324 -293.613078)
				(xy 419.914324 -293.084504) (xy 420.44239 -293.084504)
			)
		)
	)
	(zone
		(layer "In2.Cu")
		(hatch none 0.5)
		(connect_pads
			(clearance 0)
		)
		(min_thickness 0.25)
		(keepout
			(tracks allowed)
			(vias allowed)
			(pads allowed)
			(copperpour allowed)
			(footprints allowed)
		)
		(placement
			(enabled no)
			(sheetname "")
		)
		(fill
			(thermal_gap 0.5)
			(thermal_bridge_width 0.5)
			(island_removal_mode 0)
		)
		(polygon
			(pts
				(xy 420.97833 -296.484548) (xy 420.97833 -297.013122) (xy 420.44239 -297.013122) (xy 420.44239 -296.484548)
			)
		)
	)
	(zone
		(layer "In2.Cu")
		(hatch none 0.5)
		(connect_pads
			(clearance 0)
		)
		(min_thickness 0.25)
		(keepout
			(tracks allowed)
			(vias allowed)
			(pads allowed)
			(copperpour allowed)
			(footprints allowed)
		)
		(placement
			(enabled no)
			(sheetname "")
		)
		(fill
			(thermal_gap 0.5)
			(thermal_bridge_width 0.5)
			(island_removal_mode 0)
		)
		(polygon
			(pts
				(xy 428.49673 -242.93449) (xy 428.49673 -243.463064) (xy 427.96079 -243.463064) (xy 427.96079 -242.93449)
			)
		)
	)
	(zone
		(layer "In2.Cu")
		(hatch none 0.5)
		(connect_pads
			(clearance 0)
		)
		(min_thickness 0.25)
		(keepout
			(tracks allowed)
			(vias allowed)
			(pads allowed)
			(copperpour allowed)
			(footprints allowed)
		)
		(placement
			(enabled no)
			(sheetname "")
		)
		(fill
			(thermal_gap 0.5)
			(thermal_bridge_width 0.5)
			(island_removal_mode 0)
		)
		(polygon
			(pts
				(xy 298.698158 -246.88038) (xy 298.698158 -246.337074) (xy 299.252894 -246.337074) (xy 299.466762 -246.337074)
				(xy 299.466762 -246.88038) (xy 299.252894 -246.88038)
			)
		)
	)
	(zone
		(layer "In2.Cu")
		(hatch none 0.5)
		(connect_pads
			(clearance 0)
		)
		(min_thickness 0.25)
		(keepout
			(tracks allowed)
			(vias allowed)
			(pads allowed)
			(copperpour allowed)
			(footprints allowed)
		)
		(placement
			(enabled no)
			(sheetname "")
		)
		(fill
			(thermal_gap 0.5)
			(thermal_bridge_width 0.5)
			(island_removal_mode 0)
		)
		(polygon
			(pts
				(xy 83.01228 -244.464586) (xy 73.635362 -244.46484) (xy 73.305162 -244.13464) (xy 73.305162 -243.75364)
				(xy 76.513944 -240.544858) (xy 76.800202 -240.2586) (xy 82.833464 -240.2586) (xy 82.909156 -240.334292)
				(xy 83.01228 -240.492534)
			)
		)
	)
	(zone
		(layer "In2.Cu")
		(hatch none 0.5)
		(connect_pads
			(clearance 0)
		)
		(min_thickness 0.25)
		(keepout
			(tracks allowed)
			(vias allowed)
			(pads allowed)
			(copperpour allowed)
			(footprints allowed)
		)
		(placement
			(enabled no)
			(sheetname "")
		)
		(fill
			(thermal_gap 0.5)
			(thermal_bridge_width 0.5)
			(island_removal_mode 0)
		)
		(polygon
			(pts
				(xy 298.698158 -220.53042) (xy 298.698158 -219.987114) (xy 299.252894 -219.987114) (xy 299.252894 -220.53042)
			)
		)
	)
	(zone
		(layer "In2.Cu")
		(hatch none 0.5)
		(connect_pads
			(clearance 0)
		)
		(min_thickness 0.25)
		(keepout
			(tracks allowed)
			(vias allowed)
			(pads allowed)
			(copperpour allowed)
			(footprints allowed)
		)
		(placement
			(enabled no)
			(sheetname "")
		)
		(fill
			(thermal_gap 0.5)
			(thermal_bridge_width 0.5)
			(island_removal_mode 0)
		)
		(polygon
			(pts
				(xy 420.97833 -233.584496) (xy 420.97833 -234.11307) (xy 420.44239 -234.11307) (xy 420.44239 -233.584496)
			)
		)
	)
	(zone
		(layer "In2.Cu")
		(hatch none 0.5)
		(connect_pads
			(clearance 0)
		)
		(min_thickness 0.25)
		(keepout
			(tracks allowed)
			(vias allowed)
			(pads allowed)
			(copperpour allowed)
			(footprints allowed)
		)
		(placement
			(enabled no)
			(sheetname "")
		)
		(fill
			(thermal_gap 0.5)
			(thermal_bridge_width 0.5)
			(island_removal_mode 0)
		)
		(polygon
			(pts
				(xy 420.97833 -246.334534) (xy 420.97833 -246.863108) (xy 420.44239 -246.863108) (xy 420.44239 -246.334534)
			)
		)
	)
	(zone
		(layer "In2.Cu")
		(hatch none 0.5)
		(connect_pads
			(clearance 0)
		)
		(min_thickness 0.25)
		(keepout
			(tracks allowed)
			(vias allowed)
			(pads allowed)
			(copperpour allowed)
			(footprints allowed)
		)
		(placement
			(enabled no)
			(sheetname "")
		)
		(fill
			(thermal_gap 0.5)
			(thermal_bridge_width 0.5)
			(island_removal_mode 0)
		)
		(polygon
			(pts
				(xy 50.78349 -263.880346) (xy 50.78349 -263.33704) (xy 51.338226 -263.33704) (xy 51.338226 -263.880346)
			)
		)
	)
	(zone
		(layer "In2.Cu")
		(hatch none 0.5)
		(connect_pads
			(clearance 0)
		)
		(min_thickness 0.25)
		(keepout
			(tracks allowed)
			(vias allowed)
			(pads allowed)
			(copperpour allowed)
			(footprints allowed)
		)
		(placement
			(enabled no)
			(sheetname "")
		)
		(fill
			(thermal_gap 0.5)
			(thermal_bridge_width 0.5)
			(island_removal_mode 0)
		)
		(polygon
			(pts
				(xy 173.038262 -205.534514) (xy 173.038262 -206.063088) (xy 172.502322 -206.063088) (xy 172.502322 -205.534514)
			)
		)
	)
	(zone
		(layer "In2.Cu")
		(hatch none 0.5)
		(connect_pads
			(clearance 0)
		)
		(min_thickness 0.25)
		(keepout
			(tracks allowed)
			(vias allowed)
			(pads allowed)
			(copperpour allowed)
			(footprints allowed)
		)
		(placement
			(enabled no)
			(sheetname "")
		)
		(fill
			(thermal_gap 0.5)
			(thermal_bridge_width 0.5)
			(island_removal_mode 0)
		)
		(polygon
			(pts
				(xy 298.723558 -278.33066) (xy 298.723558 -277.787354) (xy 299.278294 -277.787354) (xy 299.278294 -278.33066)
			)
		)
	)
	(zone
		(layer "In2.Cu")
		(hatch none 0.5)
		(connect_pads
			(clearance 0)
		)
		(min_thickness 0.25)
		(keepout
			(tracks allowed)
			(vias allowed)
			(pads allowed)
			(copperpour allowed)
			(footprints allowed)
		)
		(placement
			(enabled no)
			(sheetname "")
		)
		(fill
			(thermal_gap 0.5)
			(thermal_bridge_width 0.5)
			(island_removal_mode 0)
		)
		(polygon
			(pts
				(xy 173.038262 -220.834712) (xy 173.038262 -221.363286) (xy 172.502322 -221.363286) (xy 172.502322 -220.834712)
			)
		)
	)
	(zone
		(layer "In2.Cu")
		(hatch none 0.5)
		(connect_pads
			(clearance 0)
		)
		(min_thickness 0.25)
		(keepout
			(tracks allowed)
			(vias allowed)
			(pads allowed)
			(copperpour allowed)
			(footprints allowed)
		)
		(placement
			(enabled no)
			(sheetname "")
		)
		(fill
			(thermal_gap 0.5)
			(thermal_bridge_width 0.5)
			(island_removal_mode 0)
		)
		(polygon
			(pts
				(xy 111.17072 -365.082328) (xy 111.17072 -363.825028) (xy 112.9411 -363.825028) (xy 112.9411 -365.082328)
			)
		)
	)
	(zone
		(layer "In2.Cu")
		(hatch none 0.5)
		(connect_pads
			(clearance 0)
		)
		(min_thickness 0.25)
		(keepout
			(tracks allowed)
			(vias allowed)
			(pads allowed)
			(copperpour allowed)
			(footprints allowed)
		)
		(placement
			(enabled no)
			(sheetname "")
		)
		(fill
			(thermal_gap 0.5)
			(thermal_bridge_width 0.5)
			(island_removal_mode 0)
		)
		(polygon
			(pts
				(xy 50.75809 -212.880448) (xy 50.75809 -212.337142) (xy 51.312826 -212.337142) (xy 51.680618 -212.337142)
				(xy 51.680618 -212.880448) (xy 51.312826 -212.880448)
			)
		)
	)
	(zone
		(layer "In2.Cu")
		(hatch none 0.5)
		(connect_pads
			(clearance 0)
		)
		(min_thickness 0.25)
		(keepout
			(tracks allowed)
			(vias allowed)
			(pads allowed)
			(copperpour allowed)
			(footprints allowed)
		)
		(placement
			(enabled no)
			(sheetname "")
		)
		(fill
			(thermal_gap 0.5)
			(thermal_bridge_width 0.5)
			(island_removal_mode 0)
		)
		(polygon
			(pts
				(xy 50.78349 -293.630604) (xy 50.78349 -293.087298) (xy 51.338226 -293.087298) (xy 51.338226 -293.630604)
			)
		)
	)
	(zone
		(layer "In2.Cu")
		(hatch none 0.5)
		(connect_pads
			(clearance 0)
		)
		(min_thickness 0.25)
		(keepout
			(tracks allowed)
			(vias allowed)
			(pads allowed)
			(copperpour allowed)
			(footprints allowed)
		)
		(placement
			(enabled no)
			(sheetname "")
		)
		(fill
			(thermal_gap 0.5)
			(thermal_bridge_width 0.5)
			(island_removal_mode 0)
		)
		(polygon
			(pts
				(xy 173.038262 -248.034556) (xy 173.038262 -248.56313) (xy 172.502322 -248.56313) (xy 172.502322 -248.034556)
			)
		)
	)
	(zone
		(layer "In2.Cu")
		(hatch none 0.5)
		(connect_pads
			(clearance 0)
		)
		(min_thickness 0.25)
		(keepout
			(tracks allowed)
			(vias allowed)
			(pads allowed)
			(copperpour allowed)
			(footprints allowed)
		)
		(placement
			(enabled no)
			(sheetname "")
		)
		(fill
			(thermal_gap 0.5)
			(thermal_bridge_width 0.5)
			(island_removal_mode 0)
		)
		(polygon
			(pts
				(xy 298.698158 -222.230442) (xy 298.698158 -221.687136) (xy 299.252894 -221.687136) (xy 299.252894 -222.230442)
			)
		)
	)
	(zone
		(layer "In2.Cu")
		(hatch none 0.5)
		(connect_pads
			(clearance 0)
		)
		(min_thickness 0.25)
		(keepout
			(tracks allowed)
			(vias allowed)
			(pads allowed)
			(copperpour allowed)
			(footprints allowed)
		)
		(placement
			(enabled no)
			(sheetname "")
		)
		(fill
			(thermal_gap 0.5)
			(thermal_bridge_width 0.5)
			(island_removal_mode 0)
		)
		(polygon
			(pts
				(xy 50.75809 -240.93043) (xy 50.75809 -240.387124) (xy 51.312826 -240.387124) (xy 51.312826 -240.93043)
			)
		)
	)
	(zone
		(layer "In2.Cu")
		(hatch none 0.5)
		(connect_pads
			(clearance 0)
		)
		(min_thickness 0.25)
		(keepout
			(tracks allowed)
			(vias allowed)
			(pads allowed)
			(copperpour allowed)
			(footprints allowed)
		)
		(placement
			(enabled no)
			(sheetname "")
		)
		(fill
			(thermal_gap 0.5)
			(thermal_bridge_width 0.5)
			(island_removal_mode 0)
		)
		(polygon
			(pts
				(xy 173.038262 -272.68424) (xy 173.038262 -273.212814) (xy 172.502322 -273.212814) (xy 172.502322 -272.68424)
			)
		)
	)
	(zone
		(layer "In2.Cu")
		(hatch none 0.5)
		(connect_pads
			(clearance 0)
		)
		(min_thickness 0.25)
		(keepout
			(tracks allowed)
			(vias allowed)
			(pads allowed)
			(copperpour allowed)
			(footprints allowed)
		)
		(placement
			(enabled no)
			(sheetname "")
		)
		(fill
			(thermal_gap 0.5)
			(thermal_bridge_width 0.5)
			(island_removal_mode 0)
		)
		(polygon
			(pts
				(xy 173.038262 -250.584462) (xy 173.038262 -251.113036) (xy 172.502322 -251.113036) (xy 172.502322 -250.584462)
			)
		)
	)
	(zone
		(layer "In2.Cu")
		(hatch none 0.5)
		(connect_pads
			(clearance 0)
		)
		(min_thickness 0.25)
		(keepout
			(tracks allowed)
			(vias allowed)
			(pads allowed)
			(copperpour allowed)
			(footprints allowed)
		)
		(placement
			(enabled no)
			(sheetname "")
		)
		(fill
			(thermal_gap 0.5)
			(thermal_bridge_width 0.5)
			(island_removal_mode 0)
		)
		(polygon
			(pts
				(xy 82.192622 -250.665234) (xy 87.463122 -250.66498) (xy 87.463122 -253.346204) (xy 83.79968 -253.346204)
				(xy 83.79968 -256.97053) (xy 83.441286 -256.97053) (xy 83.441286 -257.974084) (xy 83.255358 -258.160012)
				(xy 81.259172 -260.156198) (xy 80.921352 -260.156198) (xy 75.91044 -260.156198) (xy 70.403212 -254.64897)
				(xy 70.403212 -254.210058) (xy 70.52183 -254.09144) (xy 70.892416 -254.09144) (xy 78.766416 -254.09144)
			)
		)
	)
	(zone
		(layer "In2.Cu")
		(hatch none 0.5)
		(connect_pads
			(clearance 0)
		)
		(min_thickness 0.25)
		(keepout
			(tracks allowed)
			(vias allowed)
			(pads allowed)
			(copperpour allowed)
			(footprints allowed)
		)
		(placement
			(enabled no)
			(sheetname "")
		)
		(fill
			(thermal_gap 0.5)
			(thermal_bridge_width 0.5)
			(island_removal_mode 0)
		)
		(polygon
			(pts
				(xy 298.698158 -206.930244) (xy 298.698158 -206.386938) (xy 299.252894 -206.386938) (xy 299.252894 -206.930244)
			)
		)
	)
	(zone
		(layer "In2.Cu")
		(hatch none 0.5)
		(connect_pads
			(clearance 0)
		)
		(min_thickness 0.25)
		(keepout
			(tracks allowed)
			(vias allowed)
			(pads allowed)
			(copperpour allowed)
			(footprints allowed)
		)
		(placement
			(enabled no)
			(sheetname "")
		)
		(fill
			(thermal_gap 0.5)
			(thermal_bridge_width 0.5)
			(island_removal_mode 0)
		)
		(polygon
			(pts
				(xy 157.950662 -269.284704) (xy 157.950662 -269.813278) (xy 157.414722 -269.813278) (xy 157.414722 -269.284704)
			)
		)
	)
	(zone
		(layer "In2.Cu")
		(hatch none 0.5)
		(connect_pads
			(clearance 0)
		)
		(min_thickness 0.25)
		(keepout
			(tracks allowed)
			(vias allowed)
			(pads allowed)
			(copperpour allowed)
			(footprints allowed)
		)
		(placement
			(enabled no)
			(sheetname "")
		)
		(fill
			(thermal_gap 0.5)
			(thermal_bridge_width 0.5)
			(island_removal_mode 0)
		)
		(polygon
			(pts
				(xy 420.97833 -244.634512) (xy 420.97833 -245.163086) (xy 420.44239 -245.163086) (xy 420.44239 -244.634512)
			)
		)
	)
	(zone
		(layer "In2.Cu")
		(hatch none 0.5)
		(connect_pads
			(clearance 0)
		)
		(min_thickness 0.25)
		(keepout
			(tracks allowed)
			(vias allowed)
			(pads allowed)
			(copperpour allowed)
			(footprints allowed)
		)
		(placement
			(enabled no)
			(sheetname "")
		)
		(fill
			(thermal_gap 0.5)
			(thermal_bridge_width 0.5)
			(island_removal_mode 0)
		)
		(polygon
			(pts
				(xy 405.89073 -225.084386) (xy 405.89073 -225.61296) (xy 405.35479 -225.61296) (xy 405.35479 -225.084386)
			)
		)
	)
	(zone
		(layer "In2.Cu")
		(hatch none 0.5)
		(connect_pads
			(clearance 0)
		)
		(min_thickness 0.25)
		(keepout
			(tracks allowed)
			(vias allowed)
			(pads allowed)
			(copperpour allowed)
			(footprints allowed)
		)
		(placement
			(enabled no)
			(sheetname "")
		)
		(fill
			(thermal_gap 0.5)
			(thermal_bridge_width 0.5)
			(island_removal_mode 0)
		)
		(polygon
			(pts
				(xy 162.02533 -223.384618) (xy 162.02533 -223.913192) (xy 162.02533 -224.542096) (xy 161.009076 -224.542096)
				(xy 161.009076 -223.913192) (xy 161.009076 -223.384618) (xy 161.48939 -223.384618)
			)
		)
	)
	(zone
		(layer "In2.Cu")
		(hatch none 0.5)
		(connect_pads
			(clearance 0)
		)
		(min_thickness 0.25)
		(keepout
			(tracks allowed)
			(vias allowed)
			(pads allowed)
			(copperpour allowed)
			(footprints allowed)
		)
		(placement
			(enabled no)
			(sheetname "")
		)
		(fill
			(thermal_gap 0.5)
			(thermal_bridge_width 0.5)
			(island_removal_mode 0)
		)
		(polygon
			(pts
				(xy 50.75809 -217.98026) (xy 50.75809 -217.436954) (xy 51.312826 -217.436954) (xy 51.312826 -217.98026)
			)
		)
	)
	(zone
		(layer "In2.Cu")
		(hatch none 0.5)
		(connect_pads
			(clearance 0)
		)
		(min_thickness 0.25)
		(keepout
			(tracks allowed)
			(vias allowed)
			(pads allowed)
			(copperpour allowed)
			(footprints allowed)
		)
		(placement
			(enabled no)
			(sheetname "")
		)
		(fill
			(thermal_gap 0.5)
			(thermal_bridge_width 0.5)
			(island_removal_mode 0)
		)
		(polygon
			(pts
				(xy 420.97833 -276.934422) (xy 420.97833 -277.462996) (xy 420.44239 -277.462996) (xy 420.44239 -276.934422)
			)
		)
	)
	(zone
		(layer "In2.Cu")
		(hatch none 0.5)
		(connect_pads
			(clearance 0)
		)
		(min_thickness 0.25)
		(keepout
			(tracks allowed)
			(vias allowed)
			(pads allowed)
			(copperpour allowed)
			(footprints allowed)
		)
		(placement
			(enabled no)
			(sheetname "")
		)
		(fill
			(thermal_gap 0.5)
			(thermal_bridge_width 0.5)
			(island_removal_mode 0)
		)
		(polygon
			(pts
				(xy 298.723558 -260.480302) (xy 298.723558 -259.936996) (xy 299.278294 -259.936996) (xy 299.278294 -260.480302)
			)
		)
	)
	(zone
		(layer "In2.Cu")
		(hatch none 0.5)
		(connect_pads
			(clearance 0)
		)
		(min_thickness 0.25)
		(keepout
			(tracks allowed)
			(vias allowed)
			(pads allowed)
			(copperpour allowed)
			(footprints allowed)
		)
		(placement
			(enabled no)
			(sheetname "")
		)
		(fill
			(thermal_gap 0.5)
			(thermal_bridge_width 0.5)
			(island_removal_mode 0)
		)
		(polygon
			(pts
				(xy 133.1214 -25.39492) (xy 133.1214 -23.30196) (xy 134.56158 -23.30196) (xy 134.56158 -25.39492)
			)
		)
	)
	(zone
		(layer "In2.Cu")
		(hatch none 0.5)
		(connect_pads
			(clearance 0)
		)
		(min_thickness 0.25)
		(keepout
			(tracks allowed)
			(vias allowed)
			(pads allowed)
			(copperpour allowed)
			(footprints allowed)
		)
		(placement
			(enabled no)
			(sheetname "")
		)
		(fill
			(thermal_gap 0.5)
			(thermal_bridge_width 0.5)
			(island_removal_mode 0)
		)
		(polygon
			(pts
				(xy 414.91916 -366.878108) (xy 414.91916 -365.557308) (xy 416.39236 -365.557308) (xy 416.39236 -366.878108)
			)
		)
	)
	(zone
		(layer "In2.Cu")
		(hatch none 0.5)
		(connect_pads
			(clearance 0)
		)
		(min_thickness 0.25)
		(keepout
			(tracks allowed)
			(vias allowed)
			(pads allowed)
			(copperpour allowed)
			(footprints allowed)
		)
		(placement
			(enabled no)
			(sheetname "")
		)
		(fill
			(thermal_gap 0.5)
			(thermal_bridge_width 0.5)
			(island_removal_mode 0)
		)
		(polygon
			(pts
				(xy 420.97833 -273.534378) (xy 420.97833 -274.062952) (xy 420.44239 -274.062952) (xy 420.44239 -273.534378)
			)
		)
	)
	(zone
		(layer "In2.Cu")
		(hatch none 0.5)
		(connect_pads
			(clearance 0)
		)
		(min_thickness 0.25)
		(keepout
			(tracks allowed)
			(vias allowed)
			(pads allowed)
			(copperpour allowed)
			(footprints allowed)
		)
		(placement
			(enabled no)
			(sheetname "")
		)
		(fill
			(thermal_gap 0.5)
			(thermal_bridge_width 0.5)
			(island_removal_mode 0)
		)
		(polygon
			(pts
				(xy 173.038262 -268.434566) (xy 173.038262 -268.96314) (xy 172.502322 -268.96314) (xy 172.502322 -268.6304)
				(xy 172.698156 -268.434566)
			)
		)
	)
	(zone
		(layer "In2.Cu")
		(hatch none 0.5)
		(connect_pads
			(clearance 0)
		)
		(min_thickness 0.25)
		(keepout
			(tracks allowed)
			(vias allowed)
			(pads allowed)
			(copperpour allowed)
			(footprints allowed)
		)
		(placement
			(enabled no)
			(sheetname "")
		)
		(fill
			(thermal_gap 0.5)
			(thermal_bridge_width 0.5)
			(island_removal_mode 0)
		)
		(polygon
			(pts
				(xy 157.950662 -299.034454) (xy 157.950662 -299.563028) (xy 157.414722 -299.563028) (xy 157.414722 -299.034454)
			)
		)
	)
	(zone
		(layer "In2.Cu")
		(hatch none 0.5)
		(connect_pads
			(clearance 0)
		)
		(min_thickness 0.25)
		(keepout
			(tracks allowed)
			(vias allowed)
			(pads allowed)
			(copperpour allowed)
			(footprints allowed)
		)
		(placement
			(enabled no)
			(sheetname "")
		)
		(fill
			(thermal_gap 0.5)
			(thermal_bridge_width 0.5)
			(island_removal_mode 0)
		)
		(polygon
			(pts
				(xy 175.273462 -266.734544) (xy 175.273462 -267.263118) (xy 174.737522 -267.263118) (xy 174.737522 -266.734544)
			)
		)
	)
	(zone
		(layer "In2.Cu")
		(hatch none 0.5)
		(connect_pads
			(clearance 0)
		)
		(min_thickness 0.25)
		(keepout
			(tracks allowed)
			(vias allowed)
			(pads allowed)
			(copperpour allowed)
			(footprints allowed)
		)
		(placement
			(enabled no)
			(sheetname "")
		)
		(fill
			(thermal_gap 0.5)
			(thermal_bridge_width 0.5)
			(island_removal_mode 0)
		)
		(polygon
			(pts
				(xy 173.038262 -215.734646) (xy 173.038262 -216.26322) (xy 172.502322 -216.26322) (xy 172.502322 -215.734646)
			)
		)
	)
	(zone
		(layer "In2.Cu")
		(hatch none 0.5)
		(connect_pads
			(clearance 0)
		)
		(min_thickness 0.25)
		(keepout
			(tracks allowed)
			(vias allowed)
			(pads allowed)
			(copperpour allowed)
			(footprints allowed)
		)
		(placement
			(enabled no)
			(sheetname "")
		)
		(fill
			(thermal_gap 0.5)
			(thermal_bridge_width 0.5)
			(island_removal_mode 0)
		)
		(polygon
			(pts
				(xy 298.723558 -263.880346) (xy 298.723558 -263.33704) (xy 299.278294 -263.33704) (xy 299.278294 -263.880346)
			)
		)
	)
	(zone
		(layer "In2.Cu")
		(hatch none 0.5)
		(connect_pads
			(clearance 0)
		)
		(min_thickness 0.25)
		(keepout
			(tracks allowed)
			(vias allowed)
			(pads allowed)
			(copperpour allowed)
			(footprints allowed)
		)
		(placement
			(enabled no)
			(sheetname "")
		)
		(fill
			(thermal_gap 0.5)
			(thermal_bridge_width 0.5)
			(island_removal_mode 0)
		)
		(polygon
			(pts
				(xy 409.965398 -222.53448) (xy 409.965398 -223.063054) (xy 409.429458 -223.063054) (xy 409.429458 -222.53448)
			)
		)
	)
	(zone
		(layer "In2.Cu")
		(hatch none 0.5)
		(connect_pads
			(clearance 0)
		)
		(min_thickness 0.25)
		(keepout
			(tracks allowed)
			(vias allowed)
			(pads allowed)
			(copperpour allowed)
			(footprints allowed)
		)
		(placement
			(enabled no)
			(sheetname "")
		)
		(fill
			(thermal_gap 0.5)
			(thermal_bridge_width 0.5)
			(island_removal_mode 0)
		)
		(polygon
			(pts
				(xy 50.78349 -270.680434) (xy 50.78349 -270.137128) (xy 51.338226 -270.137128) (xy 51.338226 -270.680434)
			)
		)
	)
	(zone
		(layer "In2.Cu")
		(hatch none 0.5)
		(connect_pads
			(clearance 0)
		)
		(min_thickness 0.25)
		(keepout
			(tracks allowed)
			(vias allowed)
			(pads allowed)
			(copperpour allowed)
			(footprints allowed)
		)
		(placement
			(enabled no)
			(sheetname "")
		)
		(fill
			(thermal_gap 0.5)
			(thermal_bridge_width 0.5)
			(island_removal_mode 0)
		)
		(polygon
			(pts
				(xy 420.97833 -248.88444) (xy 420.97833 -249.413014) (xy 420.44239 -249.413014) (xy 420.44239 -248.88444)
			)
		)
	)
	(zone
		(layer "In2.Cu")
		(hatch none 0.5)
		(connect_pads
			(clearance 0)
		)
		(min_thickness 0.25)
		(keepout
			(tracks allowed)
			(vias allowed)
			(pads allowed)
			(copperpour allowed)
			(footprints allowed)
		)
		(placement
			(enabled no)
			(sheetname "")
		)
		(fill
			(thermal_gap 0.5)
			(thermal_bridge_width 0.5)
			(island_removal_mode 0)
		)
		(polygon
			(pts
				(xy 420.97833 -277.78456) (xy 420.97833 -278.313134) (xy 420.44239 -278.313134) (xy 420.44239 -277.78456)
			)
		)
	)
	(zone
		(layer "In2.Cu")
		(hatch none 0.5)
		(connect_pads
			(clearance 0)
		)
		(min_thickness 0.25)
		(keepout
			(tracks allowed)
			(vias allowed)
			(pads allowed)
			(copperpour allowed)
			(footprints allowed)
		)
		(placement
			(enabled no)
			(sheetname "")
		)
		(fill
			(thermal_gap 0.5)
			(thermal_bridge_width 0.5)
			(island_removal_mode 0)
		)
		(polygon
			(pts
				(xy 65.84569 -225.630232) (xy 65.84569 -225.086926) (xy 66.400426 -225.086926) (xy 66.734436 -225.086926)
				(xy 66.734436 -225.630232) (xy 66.400426 -225.630232)
			)
		)
	)
	(zone
		(layer "In2.Cu")
		(hatch none 0.5)
		(connect_pads
			(clearance 0)
		)
		(min_thickness 0.25)
		(keepout
			(tracks allowed)
			(vias allowed)
			(pads allowed)
			(copperpour allowed)
			(footprints allowed)
		)
		(placement
			(enabled no)
			(sheetname "")
		)
		(fill
			(thermal_gap 0.5)
			(thermal_bridge_width 0.5)
			(island_removal_mode 0)
		)
		(polygon
			(pts
				(xy 104.14 -352.130868) (xy 104.14 -351.379028) (xy 105.56494 -351.379028) (xy 105.56494 -352.130868)
			)
		)
	)
	(zone
		(layer "In2.Cu")
		(hatch none 0.5)
		(connect_pads
			(clearance 0)
		)
		(min_thickness 0.25)
		(keepout
			(tracks allowed)
			(vias allowed)
			(pads allowed)
			(copperpour allowed)
			(footprints allowed)
		)
		(placement
			(enabled no)
			(sheetname "")
		)
		(fill
			(thermal_gap 0.5)
			(thermal_bridge_width 0.5)
			(island_removal_mode 0)
		)
		(polygon
			(pts
				(xy 50.78349 -274.080224) (xy 50.78349 -273.536918) (xy 51.338226 -273.536918) (xy 51.338226 -274.080224)
			)
		)
	)
	(zone
		(layer "In2.Cu")
		(hatch none 0.5)
		(connect_pads
			(clearance 0)
		)
		(min_thickness 0.25)
		(keepout
			(tracks allowed)
			(vias allowed)
			(pads allowed)
			(copperpour allowed)
			(footprints allowed)
		)
		(placement
			(enabled no)
			(sheetname "")
		)
		(fill
			(thermal_gap 0.5)
			(thermal_bridge_width 0.5)
			(island_removal_mode 0)
		)
		(polygon
			(pts
				(xy 173.038262 -314.334398) (xy 173.038262 -314.862972) (xy 172.502322 -314.862972) (xy 172.502322 -314.334398)
			)
		)
	)
	(zone
		(layer "In2.Cu")
		(hatch none 0.5)
		(connect_pads
			(clearance 0)
		)
		(min_thickness 0.25)
		(keepout
			(tracks allowed)
			(vias allowed)
			(pads allowed)
			(copperpour allowed)
			(footprints allowed)
		)
		(placement
			(enabled no)
			(sheetname "")
		)
		(fill
			(thermal_gap 0.5)
			(thermal_bridge_width 0.5)
			(island_removal_mode 0)
		)
		(polygon
			(pts
				(xy 173.038262 -214.884508) (xy 173.038262 -215.413082) (xy 172.502322 -215.413082) (xy 172.092112 -215.413082)
				(xy 172.092112 -214.884508) (xy 172.502322 -214.884508)
			)
		)
	)
	(zone
		(layer "In2.Cu")
		(hatch none 0.5)
		(connect_pads
			(clearance 0)
		)
		(min_thickness 0.25)
		(keepout
			(tracks allowed)
			(vias allowed)
			(pads allowed)
			(copperpour allowed)
			(footprints allowed)
		)
		(placement
			(enabled no)
			(sheetname "")
		)
		(fill
			(thermal_gap 0.5)
			(thermal_bridge_width 0.5)
			(island_removal_mode 0)
		)
		(polygon
			(pts
				(xy 173.038262 -264.184638) (xy 173.038262 -264.713212) (xy 172.502322 -264.713212) (xy 172.502322 -264.184638)
			)
		)
	)
	(zone
		(layer "In2.Cu")
		(hatch none 0.5)
		(connect_pads
			(clearance 0)
		)
		(min_thickness 0.25)
		(keepout
			(tracks allowed)
			(vias allowed)
			(pads allowed)
			(copperpour allowed)
			(footprints allowed)
		)
		(placement
			(enabled no)
			(sheetname "")
		)
		(fill
			(thermal_gap 0.5)
			(thermal_bridge_width 0.5)
			(island_removal_mode 0)
		)
		(polygon
			(pts
				(xy 173.038262 -245.484396) (xy 173.038262 -246.01297) (xy 172.502322 -246.01297) (xy 172.502322 -245.484396)
			)
		)
	)
	(zone
		(layer "In2.Cu")
		(hatch none 0.5)
		(connect_pads
			(clearance 0)
		)
		(min_thickness 0.25)
		(keepout
			(tracks allowed)
			(vias allowed)
			(pads allowed)
			(copperpour allowed)
			(footprints allowed)
		)
		(placement
			(enabled no)
			(sheetname "")
		)
		(fill
			(thermal_gap 0.5)
			(thermal_bridge_width 0.5)
			(island_removal_mode 0)
		)
		(polygon
			(pts
				(xy 420.97833 -236.98454) (xy 420.97833 -237.513114) (xy 420.44239 -237.513114) (xy 420.44239 -236.98454)
			)
		)
	)
	(zone
		(layer "In2.Cu")
		(hatch none 0.5)
		(connect_pads
			(clearance 0)
		)
		(min_thickness 0.25)
		(keepout
			(tracks allowed)
			(vias allowed)
			(pads allowed)
			(copperpour allowed)
			(footprints allowed)
		)
		(placement
			(enabled no)
			(sheetname "")
		)
		(fill
			(thermal_gap 0.5)
			(thermal_bridge_width 0.5)
			(island_removal_mode 0)
		)
		(polygon
			(pts
				(xy 50.75809 -250.280424) (xy 50.75809 -249.737118) (xy 51.312826 -249.737118) (xy 51.312826 -250.280424)
			)
		)
	)
	(zone
		(layer "In2.Cu")
		(hatch none 0.5)
		(connect_pads
			(clearance 0)
		)
		(min_thickness 0.25)
		(keepout
			(tracks allowed)
			(vias allowed)
			(pads allowed)
			(copperpour allowed)
			(footprints allowed)
		)
		(placement
			(enabled no)
			(sheetname "")
		)
		(fill
			(thermal_gap 0.5)
			(thermal_bridge_width 0.5)
			(island_removal_mode 0)
		)
		(polygon
			(pts
				(xy 46.658022 -268.130274) (xy 46.658022 -267.586968) (xy 47.212758 -267.586968) (xy 47.212758 -268.130274)
			)
		)
	)
	(zone
		(layer "In2.Cu")
		(hatch none 0.5)
		(connect_pads
			(clearance 0)
		)
		(min_thickness 0.25)
		(keepout
			(tracks allowed)
			(vias allowed)
			(pads allowed)
			(copperpour allowed)
			(footprints allowed)
		)
		(placement
			(enabled no)
			(sheetname "")
		)
		(fill
			(thermal_gap 0.5)
			(thermal_bridge_width 0.5)
			(island_removal_mode 0)
		)
		(polygon
			(pts
				(xy 328.41946 -57.391808) (xy 328.41946 -39.246048) (xy 345.43238 -39.246048) (xy 345.43238 -57.391808)
			)
		)
	)
	(zone
		(layer "In2.Cu")
		(hatch none 0.5)
		(connect_pads
			(clearance 0)
		)
		(min_thickness 0.25)
		(keepout
			(tracks allowed)
			(vias allowed)
			(pads allowed)
			(copperpour allowed)
			(footprints allowed)
		)
		(placement
			(enabled no)
			(sheetname "")
		)
		(fill
			(thermal_gap 0.5)
			(thermal_bridge_width 0.5)
			(island_removal_mode 0)
		)
		(polygon
			(pts
				(xy 298.698158 -217.98026) (xy 298.698158 -217.436954) (xy 299.252894 -217.436954) (xy 299.252894 -217.98026)
			)
		)
	)
	(zone
		(layer "In2.Cu")
		(hatch none 0.5)
		(connect_pads
			(clearance 0)
		)
		(min_thickness 0.25)
		(keepout
			(tracks allowed)
			(vias allowed)
			(pads allowed)
			(copperpour allowed)
			(footprints allowed)
		)
		(placement
			(enabled no)
			(sheetname "")
		)
		(fill
			(thermal_gap 0.5)
			(thermal_bridge_width 0.5)
			(island_removal_mode 0)
		)
		(polygon
			(pts
				(xy 177.13833 -266.734544) (xy 177.13833 -267.263118) (xy 176.60239 -267.263118) (xy 176.60239 -266.734544)
			)
		)
	)
	(zone
		(layer "In2.Cu")
		(hatch none 0.5)
		(connect_pads
			(clearance 0)
		)
		(min_thickness 0.25)
		(keepout
			(tracks allowed)
			(vias allowed)
			(pads allowed)
			(copperpour allowed)
			(footprints allowed)
		)
		(placement
			(enabled no)
			(sheetname "")
		)
		(fill
			(thermal_gap 0.5)
			(thermal_bridge_width 0.5)
			(island_removal_mode 0)
		)
		(polygon
			(pts
				(xy 420.97833 -260.784594) (xy 420.97833 -261.313168) (xy 420.44239 -261.313168) (xy 420.44239 -260.784594)
			)
		)
	)
	(zone
		(layer "In2.Cu")
		(hatch none 0.5)
		(connect_pads
			(clearance 0)
		)
		(min_thickness 0.25)
		(keepout
			(tracks allowed)
			(vias allowed)
			(pads allowed)
			(copperpour allowed)
			(footprints allowed)
		)
		(placement
			(enabled no)
			(sheetname "")
		)
		(fill
			(thermal_gap 0.5)
			(thermal_bridge_width 0.5)
			(island_removal_mode 0)
		)
		(polygon
			(pts
				(xy 298.723558 -295.330372) (xy 298.723558 -294.787066) (xy 299.278294 -294.787066) (xy 299.278294 -295.330372)
			)
		)
	)
	(zone
		(layer "In2.Cu")
		(hatch none 0.5)
		(connect_pads
			(clearance 0)
		)
		(min_thickness 0.25)
		(keepout
			(tracks allowed)
			(vias allowed)
			(pads allowed)
			(copperpour allowed)
			(footprints allowed)
		)
		(placement
			(enabled no)
			(sheetname "")
		)
		(fill
			(thermal_gap 0.5)
			(thermal_bridge_width 0.5)
			(island_removal_mode 0)
		)
		(polygon
			(pts
				(xy 420.97833 -209.784696) (xy 420.97833 -210.31327) (xy 420.44239 -210.31327) (xy 420.44239 -209.784696)
			)
		)
	)
	(zone
		(layer "In2.Cu")
		(hatch none 0.5)
		(connect_pads
			(clearance 0)
		)
		(min_thickness 0.25)
		(keepout
			(tracks allowed)
			(vias allowed)
			(pads allowed)
			(copperpour allowed)
			(footprints allowed)
		)
		(placement
			(enabled no)
			(sheetname "")
		)
		(fill
			(thermal_gap 0.5)
			(thermal_bridge_width 0.5)
			(island_removal_mode 0)
		)
		(polygon
			(pts
				(xy 157.925262 -306.684426) (xy 157.925262 -307.213) (xy 157.389322 -307.213) (xy 156.997654 -307.213)
				(xy 156.997654 -306.397914) (xy 157.925262 -306.397914)
			)
		)
	)
	(zone
		(layer "In2.Cu")
		(hatch none 0.5)
		(connect_pads
			(clearance 0)
		)
		(min_thickness 0.25)
		(keepout
			(tracks allowed)
			(vias allowed)
			(pads allowed)
			(copperpour allowed)
			(footprints allowed)
		)
		(placement
			(enabled no)
			(sheetname "")
		)
		(fill
			(thermal_gap 0.5)
			(thermal_bridge_width 0.5)
			(island_removal_mode 0)
		)
		(polygon
			(pts
				(xy 391.836148 -266.039346) (xy 394.477748 -268.680946) (xy 395.050772 -268.680946) (xy 395.192758 -268.822932)
				(xy 395.960854 -268.822932) (xy 395.960854 -269.943072) (xy 395.838934 -269.943072) (xy 395.838934 -271.954752)
				(xy 395.381734 -271.954752) (xy 395.381734 -272.803112) (xy 395.102334 -272.803112) (xy 395.044676 -272.86077)
				(xy 395.044676 -273.53641) (xy 396.5575 -275.049234) (xy 395.489684 -276.117304) (xy 393.35964 -273.987514)
				(xy 393.35964 -273.593814) (xy 392.52906 -272.763234) (xy 390.03986 -270.274034) (xy 389.22706 -270.274034)
				(xy 389.20166 -270.299434) (xy 388.89686 -270.299434) (xy 388.89686 -265.563604) (xy 391.360406 -265.563604)
			)
		)
	)
	(zone
		(layer "In2.Cu")
		(hatch none 0.5)
		(connect_pads
			(clearance 0)
		)
		(min_thickness 0.25)
		(keepout
			(tracks allowed)
			(vias allowed)
			(pads allowed)
			(copperpour allowed)
			(footprints allowed)
		)
		(placement
			(enabled no)
			(sheetname "")
		)
		(fill
			(thermal_gap 0.5)
			(thermal_bridge_width 0.5)
			(island_removal_mode 0)
		)
		(polygon
			(pts
				(xy 313.785758 -231.580436) (xy 313.785758 -231.03713) (xy 314.340494 -231.03713) (xy 314.340494 -231.580436)
			)
		)
	)
	(zone
		(layer "In2.Cu")
		(hatch none 0.5)
		(connect_pads
			(clearance 0)
		)
		(min_thickness 0.25)
		(keepout
			(tracks allowed)
			(vias allowed)
			(pads allowed)
			(copperpour allowed)
			(footprints allowed)
		)
		(placement
			(enabled no)
			(sheetname "")
		)
		(fill
			(thermal_gap 0.5)
			(thermal_bridge_width 0.5)
			(island_removal_mode 0)
		)
		(polygon
			(pts
				(xy 173.038262 -236.98454) (xy 173.038262 -237.513114) (xy 172.502322 -237.513114) (xy 172.502322 -236.98454)
			)
		)
	)
	(zone
		(layer "In2.Cu")
		(hatch none 0.5)
		(connect_pads
			(clearance 0)
		)
		(min_thickness 0.25)
		(keepout
			(tracks allowed)
			(vias allowed)
			(pads allowed)
			(copperpour allowed)
			(footprints allowed)
		)
		(placement
			(enabled no)
			(sheetname "")
		)
		(fill
			(thermal_gap 0.5)
			(thermal_bridge_width 0.5)
			(island_removal_mode 0)
		)
		(polygon
			(pts
				(xy 420.97833 -217.434668) (xy 420.97833 -217.963242) (xy 420.44239 -217.963242) (xy 420.44239 -217.434668)
			)
		)
	)
	(zone
		(layer "In2.Cu")
		(hatch none 0.5)
		(connect_pads
			(clearance 0)
		)
		(min_thickness 0.25)
		(keepout
			(tracks allowed)
			(vias allowed)
			(pads allowed)
			(copperpour allowed)
			(footprints allowed)
		)
		(placement
			(enabled no)
			(sheetname "")
		)
		(fill
			(thermal_gap 0.5)
			(thermal_bridge_width 0.5)
			(island_removal_mode 0)
		)
		(polygon
			(pts
				(xy 162.02533 -222.53448) (xy 162.02533 -223.063054) (xy 161.48939 -223.063054) (xy 161.48939 -222.53448)
			)
		)
	)
	(zone
		(layer "In2.Cu")
		(hatch none 0.5)
		(connect_pads
			(clearance 0)
		)
		(min_thickness 0.25)
		(keepout
			(tracks allowed)
			(vias allowed)
			(pads allowed)
			(copperpour allowed)
			(footprints allowed)
		)
		(placement
			(enabled no)
			(sheetname "")
		)
		(fill
			(thermal_gap 0.5)
			(thermal_bridge_width 0.5)
			(island_removal_mode 0)
		)
		(polygon
			(pts
				(xy 173.038262 -266.734544) (xy 173.038262 -267.263118) (xy 172.502322 -267.263118) (xy 172.502322 -266.734544)
			)
		)
	)
	(zone
		(layer "In2.Cu")
		(hatch none 0.5)
		(connect_pads
			(clearance 0)
		)
		(min_thickness 0.25)
		(keepout
			(tracks allowed)
			(vias allowed)
			(pads allowed)
			(copperpour allowed)
			(footprints allowed)
		)
		(placement
			(enabled no)
			(sheetname "")
		)
		(fill
			(thermal_gap 0.5)
			(thermal_bridge_width 0.5)
			(island_removal_mode 0)
		)
		(polygon
			(pts
				(xy 154.20086 -404.853648) (xy 154.20086 -402.971508) (xy 155.56992 -402.971508) (xy 155.56992 -404.853648)
			)
		)
	)
	(zone
		(layer "In2.Cu")
		(hatch none 0.5)
		(connect_pads
			(clearance 0)
		)
		(min_thickness 0.25)
		(keepout
			(tracks allowed)
			(vias allowed)
			(pads allowed)
			(copperpour allowed)
			(footprints allowed)
		)
		(placement
			(enabled no)
			(sheetname "")
		)
		(fill
			(thermal_gap 0.5)
			(thermal_bridge_width 0.5)
			(island_removal_mode 0)
		)
		(polygon
			(pts
				(xy 50.75809 -205.230222) (xy 50.75809 -204.686916) (xy 51.312826 -204.686916) (xy 51.312826 -205.230222)
			)
		)
	)
	(zone
		(layer "In2.Cu")
		(hatch none 0.5)
		(connect_pads
			(clearance 0)
		)
		(min_thickness 0.25)
		(keepout
			(tracks allowed)
			(vias allowed)
			(pads allowed)
			(copperpour allowed)
			(footprints allowed)
		)
		(placement
			(enabled no)
			(sheetname "")
		)
		(fill
			(thermal_gap 0.5)
			(thermal_bridge_width 0.5)
			(island_removal_mode 0)
		)
		(polygon
			(pts
				(xy 173.038262 -310.08447) (xy 173.038262 -310.613044) (xy 172.502322 -310.613044) (xy 172.502322 -310.08447)
			)
		)
	)
	(zone
		(layer "In2.Cu")
		(hatch none 0.5)
		(connect_pads
			(clearance 0)
		)
		(min_thickness 0.25)
		(keepout
			(tracks allowed)
			(vias allowed)
			(pads allowed)
			(copperpour allowed)
			(footprints allowed)
		)
		(placement
			(enabled no)
			(sheetname "")
		)
		(fill
			(thermal_gap 0.5)
			(thermal_bridge_width 0.5)
			(island_removal_mode 0)
		)
		(polygon
			(pts
				(xy 159.58566 -404.853648) (xy 159.58566 -402.971508) (xy 160.95472 -402.971508) (xy 160.95472 -404.853648)
			)
		)
	)
	(zone
		(layer "In2.Cu")
		(hatch none 0.5)
		(connect_pads
			(clearance 0)
		)
		(min_thickness 0.25)
		(keepout
			(tracks allowed)
			(vias allowed)
			(pads allowed)
			(copperpour allowed)
			(footprints allowed)
		)
		(placement
			(enabled no)
			(sheetname "")
		)
		(fill
			(thermal_gap 0.5)
			(thermal_bridge_width 0.5)
			(island_removal_mode 0)
		)
		(polygon
			(pts
				(xy 420.97833 -271.83461) (xy 420.97833 -272.363184) (xy 420.44239 -272.363184) (xy 420.44239 -271.83461)
			)
		)
	)
	(zone
		(layer "In2.Cu")
		(hatch none 0.5)
		(connect_pads
			(clearance 0)
		)
		(min_thickness 0.25)
		(keepout
			(tracks allowed)
			(vias allowed)
			(pads allowed)
			(copperpour allowed)
			(footprints allowed)
		)
		(placement
			(enabled no)
			(sheetname "")
		)
		(fill
			(thermal_gap 0.5)
			(thermal_bridge_width 0.5)
			(island_removal_mode 0)
		)
		(polygon
			(pts
				(xy 173.038262 -208.934558) (xy 173.038262 -209.463132) (xy 172.502322 -209.463132) (xy 172.502322 -208.934558)
			)
		)
	)
	(zone
		(layer "In2.Cu")
		(hatch none 0.5)
		(connect_pads
			(clearance 0)
		)
		(min_thickness 0.25)
		(keepout
			(tracks allowed)
			(vias allowed)
			(pads allowed)
			(copperpour allowed)
			(footprints allowed)
		)
		(placement
			(enabled no)
			(sheetname "")
		)
		(fill
			(thermal_gap 0.5)
			(thermal_bridge_width 0.5)
			(island_removal_mode 0)
		)
		(polygon
			(pts
				(xy 50.78349 -276.630638) (xy 50.78349 -276.087332) (xy 51.338226 -276.087332) (xy 51.338226 -276.630638)
			)
		)
	)
	(zone
		(layer "In2.Cu")
		(hatch none 0.5)
		(connect_pads
			(clearance 0)
		)
		(min_thickness 0.25)
		(keepout
			(tracks allowed)
			(vias allowed)
			(pads allowed)
			(copperpour allowed)
			(footprints allowed)
		)
		(placement
			(enabled no)
			(sheetname "")
		)
		(fill
			(thermal_gap 0.5)
			(thermal_bridge_width 0.5)
			(island_removal_mode 0)
		)
		(polygon
			(pts
				(xy 420.97833 -316.03442) (xy 420.97833 -316.562994) (xy 420.44239 -316.562994) (xy 420.44239 -316.03442)
			)
		)
	)
	(zone
		(layer "In2.Cu")
		(hatch none 0.5)
		(connect_pads
			(clearance 0)
		)
		(min_thickness 0.25)
		(keepout
			(tracks allowed)
			(vias allowed)
			(pads allowed)
			(copperpour allowed)
			(footprints allowed)
		)
		(placement
			(enabled no)
			(sheetname "")
		)
		(fill
			(thermal_gap 0.5)
			(thermal_bridge_width 0.5)
			(island_removal_mode 0)
		)
		(polygon
			(pts
				(xy 326.8218 -347.957648) (xy 326.8218 -346.255848) (xy 329.1586 -346.255848) (xy 329.1586 -347.957648)
			)
		)
	)
	(zone
		(layer "In2.Cu")
		(hatch none 0.5)
		(connect_pads
			(clearance 0)
		)
		(min_thickness 0.25)
		(keepout
			(tracks allowed)
			(vias allowed)
			(pads allowed)
			(copperpour allowed)
			(footprints allowed)
		)
		(placement
			(enabled no)
			(sheetname "")
		)
		(fill
			(thermal_gap 0.5)
			(thermal_bridge_width 0.5)
			(island_removal_mode 0)
		)
		(polygon
			(pts
				(xy 420.97833 -238.684562) (xy 420.97833 -239.213136) (xy 420.44239 -239.213136) (xy 420.44239 -238.684562)
			)
		)
	)
	(zone
		(layer "In2.Cu")
		(hatch none 0.5)
		(connect_pads
			(clearance 0)
		)
		(min_thickness 0.25)
		(keepout
			(tracks allowed)
			(vias allowed)
			(pads allowed)
			(copperpour allowed)
			(footprints allowed)
		)
		(placement
			(enabled no)
			(sheetname "")
		)
		(fill
			(thermal_gap 0.5)
			(thermal_bridge_width 0.5)
			(island_removal_mode 0)
		)
		(polygon
			(pts
				(xy 298.723558 -308.08041) (xy 298.723558 -307.537104) (xy 299.278294 -307.537104) (xy 299.278294 -308.08041)
			)
		)
	)
	(zone
		(layer "In2.Cu")
		(hatch none 0.5)
		(connect_pads
			(clearance 0)
		)
		(min_thickness 0.25)
		(keepout
			(tracks allowed)
			(vias allowed)
			(pads allowed)
			(copperpour allowed)
			(footprints allowed)
		)
		(placement
			(enabled no)
			(sheetname "")
		)
		(fill
			(thermal_gap 0.5)
			(thermal_bridge_width 0.5)
			(island_removal_mode 0)
		)
		(polygon
			(pts
				(xy 126.01194 -342.415368) (xy 126.01194 -339.329268) (xy 133.72084 -339.329268) (xy 133.72084 -342.415368)
			)
		)
	)
	(zone
		(layer "In2.Cu")
		(hatch none 0.5)
		(connect_pads
			(clearance 0)
		)
		(min_thickness 0.25)
		(keepout
			(tracks allowed)
			(vias allowed)
			(pads allowed)
			(copperpour allowed)
			(footprints allowed)
		)
		(placement
			(enabled no)
			(sheetname "")
		)
		(fill
			(thermal_gap 0.5)
			(thermal_bridge_width 0.5)
			(island_removal_mode 0)
		)
		(polygon
			(pts
				(xy 420.97833 -309.234586) (xy 420.97833 -309.76316) (xy 420.44239 -309.76316) (xy 420.44239 -309.234586)
			)
		)
	)
	(zone
		(layer "In2.Cu")
		(hatch none 0.5)
		(connect_pads
			(clearance 0)
		)
		(min_thickness 0.25)
		(keepout
			(tracks allowed)
			(vias allowed)
			(pads allowed)
			(copperpour allowed)
			(footprints allowed)
		)
		(placement
			(enabled no)
			(sheetname "")
		)
		(fill
			(thermal_gap 0.5)
			(thermal_bridge_width 0.5)
			(island_removal_mode 0)
		)
		(polygon
			(pts
				(xy 420.97833 -289.68446) (xy 420.97833 -290.213034) (xy 420.44239 -290.213034) (xy 420.44239 -289.68446)
			)
		)
	)
	(zone
		(layer "In2.Cu")
		(hatch none 0.5)
		(connect_pads
			(clearance 0)
		)
		(min_thickness 0.25)
		(keepout
			(tracks allowed)
			(vias allowed)
			(pads allowed)
			(copperpour allowed)
			(footprints allowed)
		)
		(placement
			(enabled no)
			(sheetname "")
		)
		(fill
			(thermal_gap 0.5)
			(thermal_bridge_width 0.5)
			(island_removal_mode 0)
		)
		(polygon
			(pts
				(xy 420.97833 -245.484396) (xy 420.97833 -246.01297) (xy 420.44239 -246.01297) (xy 420.44239 -245.484396)
			)
		)
	)
	(zone
		(layer "In2.Cu")
		(hatch none 0.5)
		(connect_pads
			(clearance 0)
		)
		(min_thickness 0.25)
		(keepout
			(tracks allowed)
			(vias allowed)
			(pads allowed)
			(copperpour allowed)
			(footprints allowed)
		)
		(placement
			(enabled no)
			(sheetname "")
		)
		(fill
			(thermal_gap 0.5)
			(thermal_bridge_width 0.5)
			(island_removal_mode 0)
		)
		(polygon
			(pts
				(xy 173.038262 -210.63458) (xy 173.038262 -211.163154) (xy 172.502322 -211.163154) (xy 172.502322 -210.63458)
			)
		)
	)
	(zone
		(layer "In2.Cu")
		(hatch none 0.5)
		(connect_pads
			(clearance 0)
		)
		(min_thickness 0.25)
		(keepout
			(tracks allowed)
			(vias allowed)
			(pads allowed)
			(copperpour allowed)
			(footprints allowed)
		)
		(placement
			(enabled no)
			(sheetname "")
		)
		(fill
			(thermal_gap 0.5)
			(thermal_bridge_width 0.5)
			(island_removal_mode 0)
		)
		(polygon
			(pts
				(xy 50.75809 -211.180426) (xy 50.75809 -210.63712) (xy 51.312826 -210.63712) (xy 51.312826 -211.180426)
			)
		)
	)
	(zone
		(layer "In2.Cu")
		(hatch none 0.5)
		(connect_pads
			(clearance 0)
		)
		(min_thickness 0.25)
		(keepout
			(tracks allowed)
			(vias allowed)
			(pads allowed)
			(copperpour allowed)
			(footprints allowed)
		)
		(placement
			(enabled no)
			(sheetname "")
		)
		(fill
			(thermal_gap 0.5)
			(thermal_bridge_width 0.5)
			(island_removal_mode 0)
		)
		(polygon
			(pts
				(xy 173.038262 -211.484718) (xy 173.038262 -212.013292) (xy 172.502322 -212.013292) (xy 172.502322 -211.484718)
			)
		)
	)
	(zone
		(layer "In2.Cu")
		(hatch none 0.5)
		(connect_pads
			(clearance 0)
		)
		(min_thickness 0.25)
		(keepout
			(tracks allowed)
			(vias allowed)
			(pads allowed)
			(copperpour allowed)
			(footprints allowed)
		)
		(placement
			(enabled no)
			(sheetname "")
		)
		(fill
			(thermal_gap 0.5)
			(thermal_bridge_width 0.5)
			(island_removal_mode 0)
		)
		(polygon
			(pts
				(xy 354.276152 -290.610544) (xy 355.783388 -290.610544) (xy 359.197656 -290.610544) (xy 360.393742 -290.61029)
				(xy 361.953048 -292.169596) (xy 367.966752 -292.169596) (xy 367.966752 -290.844732) (xy 368.671602 -290.139882)
				(xy 385.292346 -290.139882) (xy 387.462014 -287.970214) (xy 387.462014 -287.896046) (xy 388.039864 -287.318196)
				(xy 388.039864 -284.823154) (xy 387.782816 -284.56636) (xy 387.782816 -284.139132) (xy 387.782816 -282.95219)
				(xy 387.779514 -282.948888) (xy 387.779514 -282.838652) (xy 387.068314 -282.127452) (xy 387.068314 -281.653488)
				(xy 387.068314 -281.104848) (xy 387.28269 -280.890472) (xy 387.28269 -280.827734) (xy 387.068314 -280.613358)
				(xy 387.068314 -280.549096) (xy 387.229096 -280.388314) (xy 387.229096 -280.234644) (xy 387.161278 -280.166826)
				(xy 387.161278 -279.289002) (xy 387.181598 -279.268682) (xy 387.453632 -279.268682) (xy 387.942328 -279.757378)
				(xy 388.001256 -279.757378) (xy 388.416038 -279.342596) (xy 388.416038 -279.230328) (xy 387.8072 -278.62149)
				(xy 387.8072 -278.569928) (xy 389.35406 -277.023068) (xy 389.35406 -276.920706) (xy 388.89686 -276.463506)
				(xy 388.89686 -256.711704) (xy 388.82701 -256.641854) (xy 388.097776 -256.641854) (xy 388.004812 -256.54889)
				(xy 388.004812 -255.847088) (xy 388.004812 -255.783842) (xy 388.04723 -255.741424) (xy 388.458964 -255.741424)
				(xy 388.53364 -255.666748) (xy 388.53364 -254) (xy 388.450074 -253.916434) (xy 387.770878 -253.916434)
				(xy 387.511798 -253.657354) (xy 382.404112 -253.657354) (xy 382.37922 -253.632462) (xy 382.37922 -252.969522)
				(xy 382.233932 -252.824234) (xy 381.71374 -252.824234) (xy 381.513842 -253.024132) (xy 381.513842 -253.027688)
				(xy 381.004572 -253.027688) (xy 379.092714 -253.586488) (xy 378.965206 -253.586488) (xy 378.177806 -252.799088)
				(xy 378.177806 -252.598936) (xy 378.338334 -252.438408) (xy 378.35713 -252.419612) (xy 382.097534 -248.678954)
				(xy 384.76174 -248.678954) (xy 384.98018 -248.678954) (xy 386.026406 -247.632728) (xy 386.026406 -247.27154)
				(xy 386.480304 -246.817642) (xy 386.480304 -246.59844) (xy 386.480304 -246.549418) (xy 386.467858 -246.536972)
				(xy 386.467858 -246.492522) (xy 386.93979 -246.02059) (xy 387.138164 -246.02059) (xy 387.191758 -245.966996)
				(xy 387.191758 -245.598696) (xy 387.65988 -245.130574) (xy 387.65988 -243.657882) (xy 387.423914 -243.421916)
				(xy 387.423914 -242.138962) (xy 387.495542 -242.067334) (xy 388.450074 -242.067334) (xy 388.5311 -241.986308)
				(xy 388.5311 -238.034068) (xy 388.407148 -237.910116) (xy 387.89737 -237.910116) (xy 387.715506 -237.728252)
				(xy 387.715506 -236.572298) (xy 388.185152 -236.572298) (xy 388.250938 -236.572298) (xy 388.333742 -236.489494)
				(xy 388.333742 -235.671868) (xy 388.333742 -235.474256) (xy 388.424928 -235.38307) (xy 388.687818 -235.38307)
				(xy 388.69112 -235.379768) (xy 388.69112 -234.660948) (xy 388.67334 -234.643168) (xy 388.616952 -234.643168)
				(xy 388.101332 -234.643168) (xy 388.07263 -234.614466) (xy 387.4008 -234.614466) (xy 387.152388 -234.862878)
				(xy 386.47497 -234.862878) (xy 386.40512 -234.793028) (xy 386.40512 -234.12704) (xy 386.446522 -234.085638)
				(xy 386.569712 -234.085638) (xy 386.57149 -234.087416) (xy 386.753862 -234.087416) (xy 387.211062 -233.630216)
				(xy 388.63905 -233.630216) (xy 388.687564 -233.581702) (xy 388.687564 -231.628442) (xy 389.599678 -231.628188)
				(xy 389.759952 -231.467914) (xy 389.759952 -229.06355) (xy 389.670544 -228.974142) (xy 389.115554 -228.974142)
				(xy 388.110222 -227.96881) (xy 388.110222 -227.762562) (xy 388.385558 -227.487226) (xy 388.385558 -227.305362)
				(xy 387.724142 -226.643946) (xy 387.724142 -226.450906) (xy 388.174738 -226.00031) (xy 389.640318 -226.00031)
				(xy 389.84428 -225.796348) (xy 389.84428 -221.798388) (xy 391.068306 -220.574362) (xy 391.068306 -220.462094)
				(xy 387.52907 -216.922858) (xy 386.719572 -215.97112) (xy 386.719572 -215.326722) (xy 384.612896 -213.220046)
				(xy 359.196132 -213.220554) (xy 355.781864 -213.220554) (xy 354.274628 -213.220554)
			)
		)
	)
	(zone
		(layer "In2.Cu")
		(hatch none 0.5)
		(connect_pads
			(clearance 0)
		)
		(min_thickness 0.25)
		(keepout
			(tracks allowed)
			(vias allowed)
			(pads allowed)
			(copperpour allowed)
			(footprints allowed)
		)
		(placement
			(enabled no)
			(sheetname "")
		)
		(fill
			(thermal_gap 0.5)
			(thermal_bridge_width 0.5)
			(island_removal_mode 0)
		)
		(polygon
			(pts
				(xy 65.84569 -231.580436) (xy 65.84569 -231.03713) (xy 66.400426 -231.03713) (xy 66.400426 -231.580436)
			)
		)
	)
	(zone
		(layer "In2.Cu")
		(hatch none 0.5)
		(connect_pads
			(clearance 0)
		)
		(min_thickness 0.25)
		(keepout
			(tracks allowed)
			(vias allowed)
			(pads allowed)
			(copperpour allowed)
			(footprints allowed)
		)
		(placement
			(enabled no)
			(sheetname "")
		)
		(fill
			(thermal_gap 0.5)
			(thermal_bridge_width 0.5)
			(island_removal_mode 0)
		)
		(polygon
			(pts
				(xy 50.75809 -209.480404) (xy 50.75809 -208.937098) (xy 51.312826 -208.937098) (xy 51.312826 -209.480404)
			)
		)
	)
	(zone
		(layer "In2.Cu")
		(hatch none 0.5)
		(connect_pads
			(clearance 0)
		)
		(min_thickness 0.25)
		(keepout
			(tracks allowed)
			(vias allowed)
			(pads allowed)
			(copperpour allowed)
			(footprints allowed)
		)
		(placement
			(enabled no)
			(sheetname "")
		)
		(fill
			(thermal_gap 0.5)
			(thermal_bridge_width 0.5)
			(island_removal_mode 0)
		)
		(polygon
			(pts
				(xy 298.723558 -280.030428) (xy 298.723558 -279.487122) (xy 299.278294 -279.487122) (xy 299.278294 -280.030428)
			)
		)
	)
	(zone
		(layer "In2.Cu")
		(hatch none 0.5)
		(connect_pads
			(clearance 0)
		)
		(min_thickness 0.25)
		(keepout
			(tracks allowed)
			(vias allowed)
			(pads allowed)
			(copperpour allowed)
			(footprints allowed)
		)
		(placement
			(enabled no)
			(sheetname "")
		)
		(fill
			(thermal_gap 0.5)
			(thermal_bridge_width 0.5)
			(island_removal_mode 0)
		)
		(polygon
			(pts
				(xy 173.038262 -234.434634) (xy 173.038262 -234.963208) (xy 172.502322 -234.963208) (xy 172.502322 -234.434634)
			)
		)
	)
	(zone
		(layer "In2.Cu")
		(hatch none 0.5)
		(connect_pads
			(clearance 0)
		)
		(min_thickness 0.25)
		(keepout
			(tracks allowed)
			(vias allowed)
			(pads allowed)
			(copperpour allowed)
			(footprints allowed)
		)
		(placement
			(enabled no)
			(sheetname "")
		)
		(fill
			(thermal_gap 0.5)
			(thermal_bridge_width 0.5)
			(island_removal_mode 0)
		)
		(polygon
			(pts
				(xy 351.053146 -290.63315) (xy 354.276152 -290.63315) (xy 354.274628 -213.220554) (xy 335.750154 -213.220808)
				(xy 332.874874 -216.096088) (xy 332.875128 -218.372182) (xy 334.238092 -219.735146) (xy 334.238092 -220.216476)
				(xy 332.53426 -221.920308) (xy 332.53426 -222.47987) (xy 332.056994 -222.47987) (xy 331.85608 -222.680784)
				(xy 331.85608 -223.896428) (xy 332.00086 -224.041208) (xy 332.00086 -224.283524) (xy 331.86624 -224.418144)
				(xy 331.819758 -224.464626) (xy 331.819758 -224.637346) (xy 332.08722 -224.904808) (xy 332.08722 -225.120708)
				(xy 331.796136 -225.411792) (xy 331.796136 -227.676964) (xy 333.111348 -228.992176) (xy 333.111348 -229.592886)
				(xy 331.613764 -231.09047) (xy 331.613764 -231.218994) (xy 331.8129 -231.41813) (xy 331.8129 -231.506268)
				(xy 330.720192 -232.598976) (xy 330.720192 -232.702608) (xy 330.929996 -232.912412) (xy 331.031088 -232.912412)
				(xy 331.031088 -234.886246) (xy 330.64704 -235.270294) (xy 330.64704 -240.017554) (xy 330.94168 -240.312194)
				(xy 330.94168 -247.242838) (xy 331.052678 -247.353836) (xy 331.38491 -247.353836) (xy 331.517244 -247.48617)
				(xy 331.517244 -248.668794) (xy 331.681836 -248.833386) (xy 332.110588 -248.833386) (xy 332.171294 -248.894092)
				(xy 332.171294 -250.352814) (xy 332.303374 -250.484894) (xy 334.019398 -250.484894) (xy 334.256888 -250.247404)
				(xy 338.820506 -250.247404) (xy 338.820506 -249.69343) (xy 339.348826 -249.16511) (xy 341.309706 -249.16511)
				(xy 341.573866 -249.42927) (xy 341.876126 -249.42927) (xy 341.919306 -249.38609) (xy 342.264746 -249.38609)
				(xy 342.396826 -249.51817) (xy 342.396826 -249.83059) (xy 342.27008 -249.83059) (xy 342.17991 -249.921014)
				(xy 342.17991 -250.256294) (xy 342.236806 -250.31319) (xy 343.145618 -250.31319) (xy 343.145618 -251.336556)
				(xy 341.13597 -253.346204) (xy 331.589888 -253.346204) (xy 331.589888 -256.97053) (xy 331.381354 -256.97053)
				(xy 331.381354 -258.46659) (xy 329.42784 -260.420104) (xy 329.42784 -261.800848) (xy 329.32878 -261.899908)
				(xy 328.89444 -261.899908) (xy 328.89444 -263.2329) (xy 329.11796 -263.2329) (xy 329.11796 -264.840466)
				(xy 328.74458 -265.213846) (xy 328.74458 -265.331448) (xy 332.64856 -269.235428) (xy 332.64856 -269.597886)
				(xy 331.95768 -270.288766) (xy 331.95768 -270.365728) (xy 333.57566 -271.983708) (xy 333.57566 -272.084546)
				(xy 331.865478 -273.794728) (xy 331.865478 -274.465288) (xy 331.967586 -274.567396) (xy 331.967586 -277.103078)
				(xy 331.627988 -277.442676) (xy 331.627988 -277.664418) (xy 332.668118 -278.704548) (xy 332.668118 -278.758142)
				(xy 332.36662 -279.05964) (xy 332.36662 -279.174448) (xy 333.404464 -280.212292) (xy 333.404464 -280.491692)
				(xy 333.13624 -280.759916) (xy 333.13624 -281.657044) (xy 332.81874 -281.974544) (xy 332.81874 -282.565348)
				(xy 333.020924 -282.767532) (xy 333.020924 -284.08503) (xy 333.418434 -284.48254) (xy 333.418434 -289.46221)
				(xy 334.567276 -290.610798) (xy 338.61756 -290.610798) (xy 338.61756 -290.375086) (xy 338.978494 -290.375086)
				(xy 338.978494 -290.610798) (xy 351.075752 -290.610544)
			)
		)
	)
	(zone
		(layer "In2.Cu")
		(hatch none 0.5)
		(connect_pads
			(clearance 0)
		)
		(min_thickness 0.25)
		(keepout
			(tracks allowed)
			(vias allowed)
			(pads allowed)
			(copperpour allowed)
			(footprints allowed)
		)
		(placement
			(enabled no)
			(sheetname "")
		)
		(fill
			(thermal_gap 0.5)
			(thermal_bridge_width 0.5)
			(island_removal_mode 0)
		)
		(polygon
			(pts
				(xy 420.97833 -305.834288) (xy 420.97833 -306.362862) (xy 420.44239 -306.362862) (xy 420.44239 -305.834288)
			)
		)
	)
	(zone
		(layer "In2.Cu")
		(hatch none 0.5)
		(connect_pads
			(clearance 0)
		)
		(min_thickness 0.25)
		(keepout
			(tracks allowed)
			(vias allowed)
			(pads allowed)
			(copperpour allowed)
			(footprints allowed)
		)
		(placement
			(enabled no)
			(sheetname "")
		)
		(fill
			(thermal_gap 0.5)
			(thermal_bridge_width 0.5)
			(island_removal_mode 0)
		)
		(polygon
			(pts
				(xy 405.89073 -226.784408) (xy 405.89073 -227.312982) (xy 405.35479 -227.312982) (xy 405.35479 -226.784408)
			)
		)
	)
	(zone
		(layer "In2.Cu")
		(hatch none 0.5)
		(connect_pads
			(clearance 0)
		)
		(min_thickness 0.25)
		(keepout
			(tracks allowed)
			(vias allowed)
			(pads allowed)
			(copperpour allowed)
			(footprints allowed)
		)
		(placement
			(enabled no)
			(sheetname "")
		)
		(fill
			(thermal_gap 0.5)
			(thermal_bridge_width 0.5)
			(island_removal_mode 0)
		)
		(polygon
			(pts
				(xy 50.959004 -145.186654) (xy 50.959004 -144.211802) (xy 51.261264 -143.909542) (xy 54.213252 -143.909542)
				(xy 54.638956 -144.335246) (xy 54.638956 -145.021808) (xy 54.240684 -145.42008) (xy 51.19243 -145.42008)
			)
		)
	)
	(zone
		(layer "In2.Cu")
		(hatch none 0.5)
		(connect_pads
			(clearance 0)
		)
		(min_thickness 0.25)
		(keepout
			(tracks allowed)
			(vias allowed)
			(pads allowed)
			(copperpour allowed)
			(footprints allowed)
		)
		(placement
			(enabled no)
			(sheetname "")
		)
		(fill
			(thermal_gap 0.5)
			(thermal_bridge_width 0.5)
			(island_removal_mode 0)
		)
		(polygon
			(pts
				(xy 298.698158 -234.980226) (xy 298.698158 -234.43692) (xy 299.252894 -234.43692) (xy 299.252894 -234.980226)
			)
		)
	)
	(zone
		(layer "In2.Cu")
		(hatch none 0.5)
		(connect_pads
			(clearance 0)
		)
		(min_thickness 0.25)
		(keepout
			(tracks allowed)
			(vias allowed)
			(pads allowed)
			(copperpour allowed)
			(footprints allowed)
		)
		(placement
			(enabled no)
			(sheetname "")
		)
		(fill
			(thermal_gap 0.5)
			(thermal_bridge_width 0.5)
			(island_removal_mode 0)
		)
		(polygon
			(pts
				(xy 157.950662 -301.584614) (xy 157.950662 -302.113188) (xy 157.414722 -302.113188) (xy 157.414722 -301.584614)
			)
		)
	)
	(zone
		(layer "In2.Cu")
		(hatch none 0.5)
		(connect_pads
			(clearance 0)
		)
		(min_thickness 0.25)
		(keepout
			(tracks allowed)
			(vias allowed)
			(pads allowed)
			(copperpour allowed)
			(footprints allowed)
		)
		(placement
			(enabled no)
			(sheetname "")
		)
		(fill
			(thermal_gap 0.5)
			(thermal_bridge_width 0.5)
			(island_removal_mode 0)
		)
		(polygon
			(pts
				(xy 420.97833 -206.384398) (xy 420.97833 -206.912972) (xy 420.44239 -206.912972) (xy 420.44239 -206.384398)
			)
		)
	)
	(zone
		(layer "In2.Cu")
		(hatch none 0.5)
		(connect_pads
			(clearance 0)
		)
		(min_thickness 0.25)
		(keepout
			(tracks allowed)
			(vias allowed)
			(pads allowed)
			(copperpour allowed)
			(footprints allowed)
		)
		(placement
			(enabled no)
			(sheetname "")
		)
		(fill
			(thermal_gap 0.5)
			(thermal_bridge_width 0.5)
			(island_removal_mode 0)
		)
		(polygon
			(pts
				(xy 420.97833 -270.134842) (xy 420.97833 -270.663416) (xy 420.44239 -270.663416) (xy 420.44239 -270.134842)
			)
		)
	)
	(zone
		(layer "In2.Cu")
		(hatch none 0.5)
		(connect_pads
			(clearance 0)
		)
		(min_thickness 0.25)
		(keepout
			(tracks allowed)
			(vias allowed)
			(pads allowed)
			(copperpour allowed)
			(footprints allowed)
		)
		(placement
			(enabled no)
			(sheetname "")
		)
		(fill
			(thermal_gap 0.5)
			(thermal_bridge_width 0.5)
			(island_removal_mode 0)
		)
		(polygon
			(pts
				(xy 420.97833 -275.2344) (xy 420.97833 -275.762974) (xy 420.44239 -275.762974) (xy 420.44239 -275.2344)
			)
		)
	)
	(zone
		(layer "In2.Cu")
		(hatch none 0.5)
		(connect_pads
			(clearance 0)
		)
		(min_thickness 0.25)
		(keepout
			(tracks allowed)
			(vias allowed)
			(pads allowed)
			(copperpour allowed)
			(footprints allowed)
		)
		(placement
			(enabled no)
			(sheetname "")
		)
		(fill
			(thermal_gap 0.5)
			(thermal_bridge_width 0.5)
			(island_removal_mode 0)
		)
		(polygon
			(pts
				(xy 173.038262 -285.434278) (xy 173.038262 -285.962852) (xy 172.502322 -285.962852) (xy 172.502322 -285.434278)
			)
		)
	)
	(zone
		(layer "In2.Cu")
		(hatch none 0.5)
		(connect_pads
			(clearance 0)
		)
		(min_thickness 0.25)
		(keepout
			(tracks allowed)
			(vias allowed)
			(pads allowed)
			(copperpour allowed)
			(footprints allowed)
		)
		(placement
			(enabled no)
			(sheetname "")
		)
		(fill
			(thermal_gap 0.5)
			(thermal_bridge_width 0.5)
			(island_removal_mode 0)
		)
		(polygon
			(pts
				(xy 50.75809 -233.280458) (xy 50.75809 -232.737152) (xy 51.312826 -232.737152) (xy 51.312826 -233.280458)
			)
		)
	)
	(zone
		(layer "In2.Cu")
		(hatch none 0.5)
		(connect_pads
			(clearance 0)
		)
		(min_thickness 0.25)
		(keepout
			(tracks allowed)
			(vias allowed)
			(pads allowed)
			(copperpour allowed)
			(footprints allowed)
		)
		(placement
			(enabled no)
			(sheetname "")
		)
		(fill
			(thermal_gap 0.5)
			(thermal_bridge_width 0.5)
			(island_removal_mode 0)
		)
		(polygon
			(pts
				(xy 298.723558 -276.630638) (xy 298.723558 -276.087332) (xy 299.278294 -276.087332) (xy 299.278294 -276.630638)
			)
		)
	)
	(zone
		(layer "In2.Cu")
		(hatch none 0.5)
		(connect_pads
			(clearance 0)
		)
		(min_thickness 0.25)
		(keepout
			(tracks allowed)
			(vias allowed)
			(pads allowed)
			(copperpour allowed)
			(footprints allowed)
		)
		(placement
			(enabled no)
			(sheetname "")
		)
		(fill
			(thermal_gap 0.5)
			(thermal_bridge_width 0.5)
			(island_removal_mode 0)
		)
		(polygon
			(pts
				(xy 405.89073 -299.884592) (xy 405.89073 -300.413166) (xy 405.35479 -300.413166) (xy 405.35479 -299.884592)
			)
		)
	)
	(zone
		(layer "In2.Cu")
		(hatch none 0.5)
		(connect_pads
			(clearance 0)
		)
		(min_thickness 0.25)
		(keepout
			(tracks allowed)
			(vias allowed)
			(pads allowed)
			(copperpour allowed)
			(footprints allowed)
		)
		(placement
			(enabled no)
			(sheetname "")
		)
		(fill
			(thermal_gap 0.5)
			(thermal_bridge_width 0.5)
			(island_removal_mode 0)
		)
		(polygon
			(pts
				(xy 157.950662 -299.884592) (xy 157.950662 -300.413166) (xy 157.414722 -300.413166) (xy 157.414722 -299.884592)
			)
		)
	)
	(zone
		(layer "In2.Cu")
		(hatch none 0.5)
		(connect_pads
			(clearance 0)
		)
		(min_thickness 0.25)
		(keepout
			(tracks allowed)
			(vias allowed)
			(pads allowed)
			(copperpour allowed)
			(footprints allowed)
		)
		(placement
			(enabled no)
			(sheetname "")
		)
		(fill
			(thermal_gap 0.5)
			(thermal_bridge_width 0.5)
			(island_removal_mode 0)
		)
		(polygon
			(pts
				(xy 173.038262 -311.784492) (xy 173.038262 -312.313066) (xy 172.502322 -312.313066) (xy 172.502322 -311.784492)
			)
		)
	)
	(zone
		(layer "In2.Cu")
		(hatch none 0.5)
		(connect_pads
			(clearance 0)
		)
		(min_thickness 0.25)
		(keepout
			(tracks allowed)
			(vias allowed)
			(pads allowed)
			(copperpour allowed)
			(footprints allowed)
		)
		(placement
			(enabled no)
			(sheetname "")
		)
		(fill
			(thermal_gap 0.5)
			(thermal_bridge_width 0.5)
			(island_removal_mode 0)
		)
		(polygon
			(pts
				(xy 420.97833 -276.084538) (xy 420.97833 -276.613112) (xy 420.44239 -276.613112) (xy 420.44239 -276.084538)
			)
		)
	)
	(zone
		(layer "In2.Cu")
		(hatch none 0.5)
		(connect_pads
			(clearance 0)
		)
		(min_thickness 0.25)
		(keepout
			(tracks allowed)
			(vias allowed)
			(pads allowed)
			(copperpour allowed)
			(footprints allowed)
		)
		(placement
			(enabled no)
			(sheetname "")
		)
		(fill
			(thermal_gap 0.5)
			(thermal_bridge_width 0.5)
			(island_removal_mode 0)
		)
		(polygon
			(pts
				(xy 173.038262 -220.834458) (xy 173.038262 -221.363032) (xy 172.502322 -221.363032) (xy 172.502322 -220.834458)
			)
		)
	)
	(zone
		(layer "In2.Cu")
		(hatch none 0.5)
		(connect_pads
			(clearance 0)
		)
		(min_thickness 0.25)
		(keepout
			(tracks allowed)
			(vias allowed)
			(pads allowed)
			(copperpour allowed)
			(footprints allowed)
		)
		(placement
			(enabled no)
			(sheetname "")
		)
		(fill
			(thermal_gap 0.5)
			(thermal_bridge_width 0.5)
			(island_removal_mode 0)
		)
		(polygon
			(pts
				(xy 425.078398 -260.784594) (xy 425.078398 -261.313168) (xy 424.542458 -261.313168) (xy 424.542458 -260.784594)
			)
		)
	)
	(zone
		(layer "In2.Cu")
		(hatch none 0.5)
		(connect_pads
			(clearance 0)
		)
		(min_thickness 0.25)
		(keepout
			(tracks allowed)
			(vias allowed)
			(pads allowed)
			(copperpour allowed)
			(footprints allowed)
		)
		(placement
			(enabled no)
			(sheetname "")
		)
		(fill
			(thermal_gap 0.5)
			(thermal_bridge_width 0.5)
			(island_removal_mode 0)
		)
		(polygon
			(pts
				(xy 420.97833 -242.084606) (xy 420.97833 -242.61318) (xy 420.44239 -242.61318) (xy 420.44239 -242.084606)
			)
		)
	)
	(zone
		(layer "In2.Cu")
		(hatch none 0.5)
		(connect_pads
			(clearance 0)
		)
		(min_thickness 0.25)
		(keepout
			(tracks allowed)
			(vias allowed)
			(pads allowed)
			(copperpour allowed)
			(footprints allowed)
		)
		(placement
			(enabled no)
			(sheetname "")
		)
		(fill
			(thermal_gap 0.5)
			(thermal_bridge_width 0.5)
			(island_removal_mode 0)
		)
		(polygon
			(pts
				(xy 420.97833 -315.184536) (xy 420.97833 -315.71311) (xy 420.44239 -315.71311) (xy 420.44239 -315.184536)
			)
		)
	)
	(zone
		(layer "In2.Cu")
		(hatch none 0.5)
		(connect_pads
			(clearance 0)
		)
		(min_thickness 0.25)
		(keepout
			(tracks allowed)
			(vias allowed)
			(pads allowed)
			(copperpour allowed)
			(footprints allowed)
		)
		(placement
			(enabled no)
			(sheetname "")
		)
		(fill
			(thermal_gap 0.5)
			(thermal_bridge_width 0.5)
			(island_removal_mode 0)
		)
		(polygon
			(pts
				(xy 420.97833 -262.484616) (xy 420.97833 -263.01319) (xy 420.44239 -263.01319) (xy 420.44239 -262.484616)
			)
		)
	)
	(zone
		(layer "In2.Cu")
		(hatch none 0.5)
		(connect_pads
			(clearance 0)
		)
		(min_thickness 0.25)
		(keepout
			(tracks allowed)
			(vias allowed)
			(pads allowed)
			(copperpour allowed)
			(footprints allowed)
		)
		(placement
			(enabled no)
			(sheetname "")
		)
		(fill
			(thermal_gap 0.5)
			(thermal_bridge_width 0.5)
			(island_removal_mode 0)
		)
		(polygon
			(pts
				(xy 298.698158 -236.680248) (xy 298.698158 -236.136942) (xy 299.252894 -236.136942) (xy 299.252894 -236.680248)
			)
		)
	)
	(zone
		(layer "In2.Cu")
		(hatch none 0.5)
		(connect_pads
			(clearance 0)
		)
		(min_thickness 0.25)
		(keepout
			(tracks allowed)
			(vias allowed)
			(pads allowed)
			(copperpour allowed)
			(footprints allowed)
		)
		(placement
			(enabled no)
			(sheetname "")
		)
		(fill
			(thermal_gap 0.5)
			(thermal_bridge_width 0.5)
			(island_removal_mode 0)
		)
		(polygon
			(pts
				(xy 173.038262 -219.984574) (xy 173.038262 -220.513148) (xy 172.502322 -220.513148) (xy 172.502322 -219.984574)
			)
		)
	)
	(zone
		(layer "In2.Cu")
		(hatch none 0.5)
		(connect_pads
			(clearance 0)
		)
		(min_thickness 0.25)
		(keepout
			(tracks allowed)
			(vias allowed)
			(pads allowed)
			(copperpour allowed)
			(footprints allowed)
		)
		(placement
			(enabled no)
			(sheetname "")
		)
		(fill
			(thermal_gap 0.5)
			(thermal_bridge_width 0.5)
			(island_removal_mode 0)
		)
		(polygon
			(pts
				(xy 157.950662 -228.484684) (xy 157.950662 -229.013258) (xy 157.414722 -229.013258) (xy 157.414722 -228.484684)
			)
		)
	)
	(zone
		(layer "In2.Cu")
		(hatch none 0.5)
		(connect_pads
			(clearance 0)
		)
		(min_thickness 0.25)
		(keepout
			(tracks allowed)
			(vias allowed)
			(pads allowed)
			(copperpour allowed)
			(footprints allowed)
		)
		(placement
			(enabled no)
			(sheetname "")
		)
		(fill
			(thermal_gap 0.5)
			(thermal_bridge_width 0.5)
			(island_removal_mode 0)
		)
		(polygon
			(pts
				(xy 173.038262 -293.084504) (xy 173.038262 -293.613078) (xy 172.502322 -293.613078) (xy 171.974256 -293.613078)
				(xy 171.974256 -293.084504) (xy 172.502322 -293.084504)
			)
		)
	)
	(zone
		(layer "In2.Cu")
		(hatch none 0.5)
		(connect_pads
			(clearance 0)
		)
		(min_thickness 0.25)
		(keepout
			(tracks allowed)
			(vias allowed)
			(pads allowed)
			(copperpour allowed)
			(footprints allowed)
		)
		(placement
			(enabled no)
			(sheetname "")
		)
		(fill
			(thermal_gap 0.5)
			(thermal_bridge_width 0.5)
			(island_removal_mode 0)
		)
		(polygon
			(pts
				(xy 405.89073 -225.08464) (xy 405.89073 -225.613214) (xy 405.35479 -225.613214) (xy 405.35479 -225.08464)
			)
		)
	)
	(zone
		(layer "In2.Cu")
		(hatch none 0.5)
		(connect_pads
			(clearance 0)
		)
		(min_thickness 0.25)
		(keepout
			(tracks allowed)
			(vias allowed)
			(pads allowed)
			(copperpour allowed)
			(footprints allowed)
		)
		(placement
			(enabled no)
			(sheetname "")
		)
		(fill
			(thermal_gap 0.5)
			(thermal_bridge_width 0.5)
			(island_removal_mode 0)
		)
		(polygon
			(pts
				(xy 420.97833 -211.484718) (xy 420.97833 -212.013292) (xy 420.44239 -212.013292) (xy 420.44239 -211.484718)
			)
		)
	)
	(zone
		(layer "In2.Cu")
		(hatch none 0.5)
		(connect_pads
			(clearance 0)
		)
		(min_thickness 0.25)
		(keepout
			(tracks allowed)
			(vias allowed)
			(pads allowed)
			(copperpour allowed)
			(footprints allowed)
		)
		(placement
			(enabled no)
			(sheetname "")
		)
		(fill
			(thermal_gap 0.5)
			(thermal_bridge_width 0.5)
			(island_removal_mode 0)
		)
		(polygon
			(pts
				(xy 397.466566 -283.595572) (xy 394.306298 -283.595572) (xy 394.306298 -283.100018) (xy 392.233404 -281.027124)
				(xy 391.65657 -280.00579) (xy 391.119614 -278.554434) (xy 391.119614 -278.059134) (xy 388.986014 -275.925534)
				(xy 388.98449 -275.925534) (xy 388.89686 -275.837904) (xy 388.89686 -270.71447) (xy 390.023096 -270.71447)
				(xy 390.217914 -270.909288) (xy 395.262354 -275.953474) (xy 395.262354 -277.190454) (xy 396.263114 -278.191214)
				(xy 396.263114 -278.919432) (xy 400.344894 -283.001212) (xy 400.344894 -283.224732) (xy 400.207734 -283.361892)
				(xy 400.037554 -283.361892) (xy 397.865854 -283.361892) (xy 397.632174 -283.595572)
			)
		)
	)
	(zone
		(layer "In2.Cu")
		(hatch none 0.5)
		(connect_pads
			(clearance 0)
		)
		(min_thickness 0.25)
		(keepout
			(tracks allowed)
			(vias allowed)
			(pads allowed)
			(copperpour allowed)
			(footprints allowed)
		)
		(placement
			(enabled no)
			(sheetname "")
		)
		(fill
			(thermal_gap 0.5)
			(thermal_bridge_width 0.5)
			(island_removal_mode 0)
		)
		(polygon
			(pts
				(xy 313.785758 -268.980412) (xy 313.785758 -268.437106) (xy 314.340494 -268.437106) (xy 314.340494 -268.980412)
			)
		)
	)
	(zone
		(layer "In2.Cu")
		(hatch none 0.5)
		(connect_pads
			(clearance 0)
		)
		(min_thickness 0.25)
		(keepout
			(tracks allowed)
			(vias allowed)
			(pads allowed)
			(copperpour allowed)
			(footprints allowed)
		)
		(placement
			(enabled no)
			(sheetname "")
		)
		(fill
			(thermal_gap 0.5)
			(thermal_bridge_width 0.5)
			(island_removal_mode 0)
		)
		(polygon
			(pts
				(xy 173.038262 -206.384652) (xy 173.038262 -206.913226) (xy 172.502322 -206.913226) (xy 172.502322 -206.384652)
			)
		)
	)
	(zone
		(layer "In2.Cu")
		(hatch none 0.5)
		(connect_pads
			(clearance 0)
		)
		(min_thickness 0.25)
		(keepout
			(tracks allowed)
			(vias allowed)
			(pads allowed)
			(copperpour allowed)
			(footprints allowed)
		)
		(placement
			(enabled no)
			(sheetname "")
		)
		(fill
			(thermal_gap 0.5)
			(thermal_bridge_width 0.5)
			(island_removal_mode 0)
		)
		(polygon
			(pts
				(xy 420.97833 -216.58453) (xy 420.97833 -217.113104) (xy 420.44239 -217.113104) (xy 420.44239 -216.58453)
			)
		)
	)
	(zone
		(layer "In2.Cu")
		(hatch none 0.5)
		(connect_pads
			(clearance 0)
		)
		(min_thickness 0.25)
		(keepout
			(tracks allowed)
			(vias allowed)
			(pads allowed)
			(copperpour allowed)
			(footprints allowed)
		)
		(placement
			(enabled no)
			(sheetname "")
		)
		(fill
			(thermal_gap 0.5)
			(thermal_bridge_width 0.5)
			(island_removal_mode 0)
		)
		(polygon
			(pts
				(xy 50.75809 -222.230442) (xy 50.75809 -221.687136) (xy 51.312826 -221.687136) (xy 51.312826 -222.230442)
			)
		)
	)
	(zone
		(layer "In2.Cu")
		(hatch none 0.5)
		(connect_pads
			(clearance 0)
		)
		(min_thickness 0.25)
		(keepout
			(tracks allowed)
			(vias allowed)
			(pads allowed)
			(copperpour allowed)
			(footprints allowed)
		)
		(placement
			(enabled no)
			(sheetname "")
		)
		(fill
			(thermal_gap 0.5)
			(thermal_bridge_width 0.5)
			(island_removal_mode 0)
		)
		(polygon
			(pts
				(xy 420.97833 -216.584784) (xy 420.97833 -217.113358) (xy 420.44239 -217.113358) (xy 420.44239 -216.584784)
			)
		)
	)
	(zone
		(layer "In2.Cu")
		(hatch none 0.5)
		(connect_pads
			(clearance 0)
		)
		(min_thickness 0.25)
		(keepout
			(tracks allowed)
			(vias allowed)
			(pads allowed)
			(copperpour allowed)
			(footprints allowed)
		)
		(placement
			(enabled no)
			(sheetname "")
		)
		(fill
			(thermal_gap 0.5)
			(thermal_bridge_width 0.5)
			(island_removal_mode 0)
		)
		(polygon
			(pts
				(xy 420.97833 -308.384448) (xy 420.97833 -308.913022) (xy 420.44239 -308.913022) (xy 420.44239 -308.384448)
			)
		)
	)
	(zone
		(layer "In2.Cu")
		(hatch none 0.5)
		(connect_pads
			(clearance 0)
		)
		(min_thickness 0.25)
		(keepout
			(tracks allowed)
			(vias allowed)
			(pads allowed)
			(copperpour allowed)
			(footprints allowed)
		)
		(placement
			(enabled no)
			(sheetname "")
		)
		(fill
			(thermal_gap 0.5)
			(thermal_bridge_width 0.5)
			(island_removal_mode 0)
		)
		(polygon
			(pts
				(xy 177.84064 -356.436168) (xy 177.84064 -355.364288) (xy 179.40274 -355.364288) (xy 179.40274 -356.436168)
			)
		)
	)
	(zone
		(layer "In2.Cu")
		(hatch none 0.5)
		(connect_pads
			(clearance 0)
		)
		(min_thickness 0.25)
		(keepout
			(tracks allowed)
			(vias allowed)
			(pads allowed)
			(copperpour allowed)
			(footprints allowed)
		)
		(placement
			(enabled no)
			(sheetname "")
		)
		(fill
			(thermal_gap 0.5)
			(thermal_bridge_width 0.5)
			(island_removal_mode 0)
		)
		(polygon
			(pts
				(xy 420.97833 -249.734578) (xy 420.97833 -250.263152) (xy 420.44239 -250.263152) (xy 420.44239 -249.734578)
			)
		)
	)
	(zone
		(layer "In2.Cu")
		(hatch none 0.5)
		(connect_pads
			(clearance 0)
		)
		(min_thickness 0.25)
		(keepout
			(tracks allowed)
			(vias allowed)
			(pads allowed)
			(copperpour allowed)
			(footprints allowed)
		)
		(placement
			(enabled no)
			(sheetname "")
		)
		(fill
			(thermal_gap 0.5)
			(thermal_bridge_width 0.5)
			(island_removal_mode 0)
		)
		(polygon
			(pts
				(xy 50.78349 -298.730416) (xy 50.78349 -298.18711) (xy 51.338226 -298.18711) (xy 51.338226 -298.730416)
			)
		)
	)
	(zone
		(layer "In2.Cu")
		(hatch none 0.5)
		(connect_pads
			(clearance 0)
		)
		(min_thickness 0.25)
		(keepout
			(tracks allowed)
			(vias allowed)
			(pads allowed)
			(copperpour allowed)
			(footprints allowed)
		)
		(placement
			(enabled no)
			(sheetname "")
		)
		(fill
			(thermal_gap 0.5)
			(thermal_bridge_width 0.5)
			(island_removal_mode 0)
		)
		(polygon
			(pts
				(xy 173.038262 -236.134402) (xy 173.038262 -236.662976) (xy 172.502322 -236.662976) (xy 172.502322 -236.134402)
			)
		)
	)
	(zone
		(layer "In2.Cu")
		(hatch none 0.5)
		(connect_pads
			(clearance 0)
		)
		(min_thickness 0.25)
		(keepout
			(tracks allowed)
			(vias allowed)
			(pads allowed)
			(copperpour allowed)
			(footprints allowed)
		)
		(placement
			(enabled no)
			(sheetname "")
		)
		(fill
			(thermal_gap 0.5)
			(thermal_bridge_width 0.5)
			(island_removal_mode 0)
		)
		(polygon
			(pts
				(xy 420.97833 -263.3345) (xy 420.97833 -263.863074) (xy 420.44239 -263.863074) (xy 420.44239 -263.3345)
			)
		)
	)
	(zone
		(layer "In2.Cu")
		(hatch none 0.5)
		(connect_pads
			(clearance 0)
		)
		(min_thickness 0.25)
		(keepout
			(tracks allowed)
			(vias allowed)
			(pads allowed)
			(copperpour allowed)
			(footprints allowed)
		)
		(placement
			(enabled no)
			(sheetname "")
		)
		(fill
			(thermal_gap 0.5)
			(thermal_bridge_width 0.5)
			(island_removal_mode 0)
		)
		(polygon
			(pts
				(xy 420.97833 -288.834322) (xy 420.97833 -289.362896) (xy 420.44239 -289.362896) (xy 420.44239 -288.834322)
			)
		)
	)
	(zone
		(layer "In2.Cu")
		(hatch none 0.5)
		(connect_pads
			(clearance 0)
		)
		(min_thickness 0.25)
		(keepout
			(tracks allowed)
			(vias allowed)
			(pads allowed)
			(copperpour allowed)
			(footprints allowed)
		)
		(placement
			(enabled no)
			(sheetname "")
		)
		(fill
			(thermal_gap 0.5)
			(thermal_bridge_width 0.5)
			(island_removal_mode 0)
		)
		(polygon
			(pts
				(xy 157.925262 -303.284382) (xy 157.925262 -303.812956) (xy 157.389322 -303.812956) (xy 157.389322 -303.284382)
			)
		)
	)
	(zone
		(layer "In2.Cu")
		(hatch none 0.5)
		(connect_pads
			(clearance 0)
		)
		(min_thickness 0.25)
		(keepout
			(tracks allowed)
			(vias allowed)
			(pads allowed)
			(copperpour allowed)
			(footprints allowed)
		)
		(placement
			(enabled no)
			(sheetname "")
		)
		(fill
			(thermal_gap 0.5)
			(thermal_bridge_width 0.5)
			(island_removal_mode 0)
		)
		(polygon
			(pts
				(xy 423.21353 -267.584428) (xy 423.21353 -268.113002) (xy 422.67759 -268.113002) (xy 422.67759 -267.584428)
			)
		)
	)
	(zone
		(layer "In2.Cu")
		(hatch none 0.5)
		(connect_pads
			(clearance 0)
		)
		(min_thickness 0.25)
		(keepout
			(tracks allowed)
			(vias allowed)
			(pads allowed)
			(copperpour allowed)
			(footprints allowed)
		)
		(placement
			(enabled no)
			(sheetname "")
		)
		(fill
			(thermal_gap 0.5)
			(thermal_bridge_width 0.5)
			(island_removal_mode 0)
		)
		(polygon
			(pts
				(xy 420.97833 -234.43438) (xy 420.97833 -234.962954) (xy 420.44239 -234.962954) (xy 420.44239 -234.43438)
			)
		)
	)
	(zone
		(layer "In2.Cu")
		(hatch none 0.5)
		(connect_pads
			(clearance 0)
		)
		(min_thickness 0.25)
		(keepout
			(tracks allowed)
			(vias allowed)
			(pads allowed)
			(copperpour allowed)
			(footprints allowed)
		)
		(placement
			(enabled no)
			(sheetname "")
		)
		(fill
			(thermal_gap 0.5)
			(thermal_bridge_width 0.5)
			(island_removal_mode 0)
		)
		(polygon
			(pts
				(xy 420.97833 -294.784526) (xy 420.97833 -295.3131) (xy 420.44239 -295.3131) (xy 420.44239 -294.784526)
			)
		)
	)
	(zone
		(layer "In2.Cu")
		(hatch none 0.5)
		(connect_pads
			(clearance 0)
		)
		(min_thickness 0.25)
		(keepout
			(tracks allowed)
			(vias allowed)
			(pads allowed)
			(copperpour allowed)
			(footprints allowed)
		)
		(placement
			(enabled no)
			(sheetname "")
		)
		(fill
			(thermal_gap 0.5)
			(thermal_bridge_width 0.5)
			(island_removal_mode 0)
		)
		(polygon
			(pts
				(xy 173.038262 -316.03442) (xy 173.038262 -316.562994) (xy 172.502322 -316.562994) (xy 172.502322 -316.03442)
			)
		)
	)
	(zone
		(layer "In2.Cu")
		(hatch none 0.5)
		(connect_pads
			(clearance 0)
		)
		(min_thickness 0.25)
		(keepout
			(tracks allowed)
			(vias allowed)
			(pads allowed)
			(copperpour allowed)
			(footprints allowed)
		)
		(placement
			(enabled no)
			(sheetname "")
		)
		(fill
			(thermal_gap 0.5)
			(thermal_bridge_width 0.5)
			(island_removal_mode 0)
		)
		(polygon
			(pts
				(xy 173.038262 -283.73451) (xy 173.038262 -284.263084) (xy 172.502322 -284.263084) (xy 172.502322 -283.73451)
			)
		)
	)
	(zone
		(layer "In2.Cu")
		(hatch none 0.5)
		(connect_pads
			(clearance 0)
		)
		(min_thickness 0.25)
		(keepout
			(tracks allowed)
			(vias allowed)
			(pads allowed)
			(copperpour allowed)
			(footprints allowed)
		)
		(placement
			(enabled no)
			(sheetname "")
		)
		(fill
			(thermal_gap 0.5)
			(thermal_bridge_width 0.5)
			(island_removal_mode 0)
		)
		(polygon
			(pts
				(xy 420.97833 -208.934558) (xy 420.97833 -209.463132) (xy 420.44239 -209.463132) (xy 420.44239 -208.934558)
			)
		)
	)
	(zone
		(layer "In2.Cu")
		(hatch none 0.5)
		(connect_pads
			(clearance 0)
		)
		(min_thickness 0.25)
		(keepout
			(tracks allowed)
			(vias allowed)
			(pads allowed)
			(copperpour allowed)
			(footprints allowed)
		)
		(placement
			(enabled no)
			(sheetname "")
		)
		(fill
			(thermal_gap 0.5)
			(thermal_bridge_width 0.5)
			(island_removal_mode 0)
		)
		(polygon
			(pts
				(xy 405.89073 -225.934524) (xy 405.89073 -226.463098) (xy 405.35479 -226.463098) (xy 405.35479 -225.934524)
			)
		)
	)
	(zone
		(layer "In2.Cu")
		(hatch none 0.5)
		(connect_pads
			(clearance 0)
		)
		(min_thickness 0.25)
		(keepout
			(tracks allowed)
			(vias allowed)
			(pads allowed)
			(copperpour allowed)
			(footprints allowed)
		)
		(placement
			(enabled no)
			(sheetname "")
		)
		(fill
			(thermal_gap 0.5)
			(thermal_bridge_width 0.5)
			(island_removal_mode 0)
		)
		(polygon
			(pts
				(xy 162.05073 -231.884474) (xy 162.05073 -232.413048) (xy 161.51479 -232.413048) (xy 161.51479 -231.884474)
			)
		)
	)
	(zone
		(layer "In2.Cu")
		(hatch none 0.5)
		(connect_pads
			(clearance 0)
		)
		(min_thickness 0.25)
		(keepout
			(tracks allowed)
			(vias allowed)
			(pads allowed)
			(copperpour allowed)
			(footprints allowed)
		)
		(placement
			(enabled no)
			(sheetname "")
		)
		(fill
			(thermal_gap 0.5)
			(thermal_bridge_width 0.5)
			(island_removal_mode 0)
		)
		(polygon
			(pts
				(xy 394.458952 -254.06477) (xy 392.886184 -254.06477) (xy 392.884406 -254.062992) (xy 392.423142 -254.524256)
				(xy 390.617964 -254.524256) (xy 390.016492 -253.922784) (xy 388.74573 -253.923038) (xy 388.53364 -254.135128)
				(xy 388.53364 -255.666748) (xy 388.458964 -255.741424) (xy 388.04723 -255.741424) (xy 388.004812 -255.783842)
				(xy 388.004812 -255.847088) (xy 388.004812 -256.54889) (xy 388.097776 -256.641854) (xy 388.82701 -256.641854)
				(xy 388.89686 -256.711704) (xy 388.89686 -260.366764) (xy 393.584176 -260.366764) (xy 395.053058 -261.835392)
				(xy 395.193012 -261.835392) (xy 396.281656 -260.746494) (xy 396.281656 -254.309626) (xy 395.804136 -253.832106)
				(xy 394.885164 -253.832106) (xy 394.691616 -253.832106)
			)
		)
	)
	(zone
		(layer "In2.Cu")
		(hatch none 0.5)
		(connect_pads
			(clearance 0)
		)
		(min_thickness 0.25)
		(keepout
			(tracks allowed)
			(vias allowed)
			(pads allowed)
			(copperpour allowed)
			(footprints allowed)
		)
		(placement
			(enabled no)
			(sheetname "")
		)
		(fill
			(thermal_gap 0.5)
			(thermal_bridge_width 0.5)
			(island_removal_mode 0)
		)
		(polygon
			(pts
				(xy 298.723558 -293.630604) (xy 298.723558 -293.087298) (xy 299.278294 -293.087298) (xy 299.278294 -293.630604)
			)
		)
	)
	(zone
		(layer "In2.Cu")
		(hatch none 0.5)
		(connect_pads
			(clearance 0)
		)
		(min_thickness 0.25)
		(keepout
			(tracks allowed)
			(vias allowed)
			(pads allowed)
			(copperpour allowed)
			(footprints allowed)
		)
		(placement
			(enabled no)
			(sheetname "")
		)
		(fill
			(thermal_gap 0.5)
			(thermal_bridge_width 0.5)
			(island_removal_mode 0)
		)
		(polygon
			(pts
				(xy 405.86533 -302.434498) (xy 405.86533 -302.963072) (xy 405.32939 -302.963072) (xy 405.32939 -302.434498)
			)
		)
	)
	(zone
		(layer "In2.Cu")
		(hatch none 0.5)
		(connect_pads
			(clearance 0)
		)
		(min_thickness 0.25)
		(keepout
			(tracks allowed)
			(vias allowed)
			(pads allowed)
			(copperpour allowed)
			(footprints allowed)
		)
		(placement
			(enabled no)
			(sheetname "")
		)
		(fill
			(thermal_gap 0.5)
			(thermal_bridge_width 0.5)
			(island_removal_mode 0)
		)
		(polygon
			(pts
				(xy 50.75809 -231.580436) (xy 50.75809 -231.03713) (xy 51.312826 -231.03713) (xy 51.312826 -231.580436)
			)
		)
	)
	(zone
		(layer "In2.Cu")
		(hatch none 0.5)
		(connect_pads
			(clearance 0)
		)
		(min_thickness 0.25)
		(keepout
			(tracks allowed)
			(vias allowed)
			(pads allowed)
			(copperpour allowed)
			(footprints allowed)
		)
		(placement
			(enabled no)
			(sheetname "")
		)
		(fill
			(thermal_gap 0.5)
			(thermal_bridge_width 0.5)
			(island_removal_mode 0)
		)
		(polygon
			(pts
				(xy 50.959004 -162.458654) (xy 50.959004 -161.483802) (xy 51.261264 -161.181542) (xy 54.213252 -161.181542)
				(xy 54.638956 -161.607246) (xy 54.638956 -162.293808) (xy 54.240684 -162.69208) (xy 51.19243 -162.69208)
			)
		)
	)
	(zone
		(layer "In2.Cu")
		(hatch none 0.5)
		(connect_pads
			(clearance 0)
		)
		(min_thickness 0.25)
		(keepout
			(tracks allowed)
			(vias allowed)
			(pads allowed)
			(copperpour allowed)
			(footprints allowed)
		)
		(placement
			(enabled no)
			(sheetname "")
		)
		(fill
			(thermal_gap 0.5)
			(thermal_bridge_width 0.5)
			(island_removal_mode 0)
		)
		(polygon
			(pts
				(xy 420.97833 -265.034522) (xy 420.97833 -265.563096) (xy 420.44239 -265.563096) (xy 420.44239 -265.034522)
			)
		)
	)
	(zone
		(layer "In2.Cu")
		(hatch none 0.5)
		(connect_pads
			(clearance 0)
		)
		(min_thickness 0.25)
		(keepout
			(tracks allowed)
			(vias allowed)
			(pads allowed)
			(copperpour allowed)
			(footprints allowed)
		)
		(placement
			(enabled no)
			(sheetname "")
		)
		(fill
			(thermal_gap 0.5)
			(thermal_bridge_width 0.5)
			(island_removal_mode 0)
		)
		(polygon
			(pts
				(xy 50.75809 -285.980378) (xy 50.75809 -285.437072) (xy 51.312826 -285.437072) (xy 51.312826 -285.980378)
			)
		)
	)
	(zone
		(layer "In2.Cu")
		(hatch none 0.5)
		(connect_pads
			(clearance 0)
		)
		(min_thickness 0.25)
		(keepout
			(tracks allowed)
			(vias allowed)
			(pads allowed)
			(copperpour allowed)
			(footprints allowed)
		)
		(placement
			(enabled no)
			(sheetname "")
		)
		(fill
			(thermal_gap 0.5)
			(thermal_bridge_width 0.5)
			(island_removal_mode 0)
		)
		(polygon
			(pts
				(xy 405.86533 -227.6348) (xy 405.86533 -228.163374) (xy 405.32939 -228.163374) (xy 405.32939 -227.6348)
			)
		)
	)
	(zone
		(layer "In2.Cu")
		(hatch none 0.5)
		(connect_pads
			(clearance 0)
		)
		(min_thickness 0.25)
		(keepout
			(tracks allowed)
			(vias allowed)
			(pads allowed)
			(copperpour allowed)
			(footprints allowed)
		)
		(placement
			(enabled no)
			(sheetname "")
		)
		(fill
			(thermal_gap 0.5)
			(thermal_bridge_width 0.5)
			(island_removal_mode 0)
		)
		(polygon
			(pts
				(xy 50.78349 -295.330372) (xy 50.78349 -294.787066) (xy 51.338226 -294.787066) (xy 51.338226 -295.330372)
			)
		)
	)
	(zone
		(layer "In2.Cu")
		(hatch none 0.5)
		(connect_pads
			(clearance 0)
		)
		(min_thickness 0.25)
		(keepout
			(tracks allowed)
			(vias allowed)
			(pads allowed)
			(copperpour allowed)
			(footprints allowed)
		)
		(placement
			(enabled no)
			(sheetname "")
		)
		(fill
			(thermal_gap 0.5)
			(thermal_bridge_width 0.5)
			(island_removal_mode 0)
		)
		(polygon
			(pts
				(xy 420.97833 -264.184638) (xy 420.97833 -264.713212) (xy 420.44239 -264.713212) (xy 420.44239 -264.184638)
			)
		)
	)
	(zone
		(layer "In2.Cu")
		(hatch none 0.5)
		(connect_pads
			(clearance 0)
		)
		(min_thickness 0.25)
		(keepout
			(tracks allowed)
			(vias allowed)
			(pads allowed)
			(copperpour allowed)
			(footprints allowed)
		)
		(placement
			(enabled no)
			(sheetname "")
		)
		(fill
			(thermal_gap 0.5)
			(thermal_bridge_width 0.5)
			(island_removal_mode 0)
		)
		(polygon
			(pts
				(xy 157.950662 -225.934524) (xy 157.950662 -226.463098) (xy 157.414722 -226.463098) (xy 157.414722 -225.934524)
			)
		)
	)
	(zone
		(layer "In2.Cu")
		(hatch none 0.5)
		(connect_pads
			(clearance 0)
		)
		(min_thickness 0.25)
		(keepout
			(tracks allowed)
			(vias allowed)
			(pads allowed)
			(copperpour allowed)
			(footprints allowed)
		)
		(placement
			(enabled no)
			(sheetname "")
		)
		(fill
			(thermal_gap 0.5)
			(thermal_bridge_width 0.5)
			(island_removal_mode 0)
		)
		(polygon
			(pts
				(xy 65.84569 -229.880414) (xy 65.84569 -229.337108) (xy 66.400426 -229.337108) (xy 66.696844 -229.337108)
				(xy 66.696844 -229.880414) (xy 66.400426 -229.880414)
			)
		)
	)
	(zone
		(layer "In2.Cu")
		(hatch none 0.5)
		(connect_pads
			(clearance 0)
		)
		(min_thickness 0.25)
		(keepout
			(tracks allowed)
			(vias allowed)
			(pads allowed)
			(copperpour allowed)
			(footprints allowed)
		)
		(placement
			(enabled no)
			(sheetname "")
		)
		(fill
			(thermal_gap 0.5)
			(thermal_bridge_width 0.5)
			(island_removal_mode 0)
		)
		(polygon
			(pts
				(xy 298.698158 -250.280424) (xy 298.698158 -249.737118) (xy 299.252894 -249.737118) (xy 299.252894 -250.280424)
			)
		)
	)
	(zone
		(layer "In2.Cu")
		(hatch none 0.5)
		(connect_pads
			(clearance 0)
		)
		(min_thickness 0.25)
		(keepout
			(tracks allowed)
			(vias allowed)
			(pads allowed)
			(copperpour allowed)
			(footprints allowed)
		)
		(placement
			(enabled no)
			(sheetname "")
		)
		(fill
			(thermal_gap 0.5)
			(thermal_bridge_width 0.5)
			(island_removal_mode 0)
		)
		(polygon
			(pts
				(xy 65.84569 -268.980412) (xy 65.84569 -268.437106) (xy 66.400426 -268.437106) (xy 66.400426 -268.980412)
			)
		)
	)
	(zone
		(layer "In2.Cu")
		(hatch none 0.5)
		(connect_pads
			(clearance 0)
		)
		(min_thickness 0.25)
		(keepout
			(tracks allowed)
			(vias allowed)
			(pads allowed)
			(copperpour allowed)
			(footprints allowed)
		)
		(placement
			(enabled no)
			(sheetname "")
		)
		(fill
			(thermal_gap 0.5)
			(thermal_bridge_width 0.5)
			(island_removal_mode 0)
		)
		(polygon
			(pts
				(xy 298.723558 -265.580368) (xy 298.723558 -265.037062) (xy 299.278294 -265.037062) (xy 299.278294 -265.580368)
			)
		)
	)
	(zone
		(layer "In2.Cu")
		(hatch none 0.5)
		(connect_pads
			(clearance 0)
		)
		(min_thickness 0.25)
		(keepout
			(tracks allowed)
			(vias allowed)
			(pads allowed)
			(copperpour allowed)
			(footprints allowed)
		)
		(placement
			(enabled no)
			(sheetname "")
		)
		(fill
			(thermal_gap 0.5)
			(thermal_bridge_width 0.5)
			(island_removal_mode 0)
		)
		(polygon
			(pts
				(xy 298.698158 -212.880448) (xy 298.698158 -212.337142) (xy 299.252894 -212.337142) (xy 299.620686 -212.337142)
				(xy 299.620686 -212.880448) (xy 299.252894 -212.880448)
			)
		)
	)
	(zone
		(layer "In2.Cu")
		(hatch none 0.5)
		(connect_pads
			(clearance 0)
		)
		(min_thickness 0.25)
		(keepout
			(tracks allowed)
			(vias allowed)
			(pads allowed)
			(copperpour allowed)
			(footprints allowed)
		)
		(placement
			(enabled no)
			(sheetname "")
		)
		(fill
			(thermal_gap 0.5)
			(thermal_bridge_width 0.5)
			(island_removal_mode 0)
		)
		(polygon
			(pts
				(xy 173.038262 -295.63441) (xy 173.038262 -296.162984) (xy 172.502322 -296.162984) (xy 172.502322 -295.63441)
			)
		)
	)
	(zone
		(layer "In2.Cu")
		(hatch none 0.5)
		(connect_pads
			(clearance 0)
		)
		(min_thickness 0.25)
		(keepout
			(tracks allowed)
			(vias allowed)
			(pads allowed)
			(copperpour allowed)
			(footprints allowed)
		)
		(placement
			(enabled no)
			(sheetname "")
		)
		(fill
			(thermal_gap 0.5)
			(thermal_bridge_width 0.5)
			(island_removal_mode 0)
		)
		(polygon
			(pts
				(xy 405.89073 -301.584614) (xy 405.89073 -302.113188) (xy 405.35479 -302.113188) (xy 405.35479 -301.584614)
			)
		)
	)
	(zone
		(layer "In2.Cu")
		(hatch none 0.5)
		(connect_pads
			(clearance 0)
		)
		(min_thickness 0.25)
		(keepout
			(tracks allowed)
			(vias allowed)
			(pads allowed)
			(copperpour allowed)
			(footprints allowed)
		)
		(placement
			(enabled no)
			(sheetname "")
		)
		(fill
			(thermal_gap 0.5)
			(thermal_bridge_width 0.5)
			(island_removal_mode 0)
		)
		(polygon
			(pts
				(xy 116.19992 -354.889308) (xy 116.19992 -353.619308) (xy 117.26164 -353.619308) (xy 117.26164 -354.889308)
			)
		)
	)
	(zone
		(layer "In2.Cu")
		(hatch none 0.5)
		(connect_pads
			(clearance 0)
		)
		(min_thickness 0.25)
		(keepout
			(tracks allowed)
			(vias allowed)
			(pads allowed)
			(copperpour allowed)
			(footprints allowed)
		)
		(placement
			(enabled no)
			(sheetname "")
		)
		(fill
			(thermal_gap 0.5)
			(thermal_bridge_width 0.5)
			(island_removal_mode 0)
		)
		(polygon
			(pts
				(xy 423.21353 -266.734544) (xy 423.21353 -267.263118) (xy 422.67759 -267.263118) (xy 422.67759 -266.734544)
			)
		)
	)
	(zone
		(layer "In2.Cu")
		(hatch none 0.5)
		(connect_pads
			(clearance 0)
		)
		(min_thickness 0.25)
		(keepout
			(tracks allowed)
			(vias allowed)
			(pads allowed)
			(copperpour allowed)
			(footprints allowed)
		)
		(placement
			(enabled no)
			(sheetname "")
		)
		(fill
			(thermal_gap 0.5)
			(thermal_bridge_width 0.5)
			(island_removal_mode 0)
		)
		(polygon
			(pts
				(xy 50.78349 -274.930616) (xy 50.78349 -274.38731) (xy 51.338226 -274.38731) (xy 51.338226 -274.930616)
			)
		)
	)
	(zone
		(layer "In2.Cu")
		(hatch none 0.5)
		(connect_pads
			(clearance 0)
		)
		(min_thickness 0.25)
		(keepout
			(tracks allowed)
			(vias allowed)
			(pads allowed)
			(copperpour allowed)
			(footprints allowed)
		)
		(placement
			(enabled no)
			(sheetname "")
		)
		(fill
			(thermal_gap 0.5)
			(thermal_bridge_width 0.5)
			(island_removal_mode 0)
		)
		(polygon
			(pts
				(xy 420.97833 -310.08447) (xy 420.97833 -310.613044) (xy 420.44239 -310.613044) (xy 420.44239 -310.08447)
			)
		)
	)
	(zone
		(layer "In2.Cu")
		(hatch none 0.5)
		(connect_pads
			(clearance 0)
		)
		(min_thickness 0.25)
		(keepout
			(tracks allowed)
			(vias allowed)
			(pads allowed)
			(copperpour allowed)
			(footprints allowed)
		)
		(placement
			(enabled no)
			(sheetname "")
		)
		(fill
			(thermal_gap 0.5)
			(thermal_bridge_width 0.5)
			(island_removal_mode 0)
		)
		(polygon
			(pts
				(xy 50.78349 -311.480454) (xy 50.78349 -310.937148) (xy 51.338226 -310.937148) (xy 51.338226 -311.480454)
			)
		)
	)
	(zone
		(layer "In2.Cu")
		(hatch none 0.5)
		(connect_pads
			(clearance 0)
		)
		(min_thickness 0.25)
		(keepout
			(tracks allowed)
			(vias allowed)
			(pads allowed)
			(copperpour allowed)
			(footprints allowed)
		)
		(placement
			(enabled no)
			(sheetname "")
		)
		(fill
			(thermal_gap 0.5)
			(thermal_bridge_width 0.5)
			(island_removal_mode 0)
		)
		(polygon
			(pts
				(xy 387.779514 -283.546296) (xy 387.779514 -282.948888) (xy 387.779514 -282.803092) (xy 387.068314 -282.091892)
				(xy 387.068314 -281.653488) (xy 387.068314 -281.104848) (xy 387.28269 -280.890472) (xy 387.28269 -280.827734)
				(xy 387.068314 -280.613358) (xy 387.068314 -280.549096) (xy 387.229096 -280.388314) (xy 387.229096 -280.234644)
				(xy 387.161278 -280.166826) (xy 387.161278 -279.289002) (xy 387.181598 -279.268682) (xy 387.453632 -279.268682)
				(xy 387.942328 -279.757378) (xy 388.001256 -279.757378) (xy 388.416038 -279.342596) (xy 388.416038 -279.230328)
				(xy 387.8072 -278.62149) (xy 387.8072 -278.569928) (xy 389.241792 -277.135336) (xy 389.458962 -277.135336)
				(xy 389.46201 -277.138384) (xy 390.102598 -277.778718) (xy 390.623298 -277.778718) (xy 390.992614 -278.148034)
				(xy 390.992614 -278.633174) (xy 390.994646 -278.63546) (xy 391.520426 -280.112978) (xy 392.041634 -281.038554)
				(xy 393.697714 -282.694634) (xy 394.149834 -283.146754) (xy 394.149834 -283.857192) (xy 393.646914 -284.360112)
				(xy 388.089394 -284.360112) (xy 387.779514 -284.050232)
			)
		)
	)
	(zone
		(layer "In2.Cu")
		(hatch none 0.5)
		(connect_pads
			(clearance 0)
		)
		(min_thickness 0.25)
		(keepout
			(tracks allowed)
			(vias allowed)
			(pads allowed)
			(copperpour allowed)
			(footprints allowed)
		)
		(placement
			(enabled no)
			(sheetname "")
		)
		(fill
			(thermal_gap 0.5)
			(thermal_bridge_width 0.5)
			(island_removal_mode 0)
		)
		(polygon
			(pts
				(xy 298.698158 -245.180358) (xy 298.698158 -244.637052) (xy 299.252894 -244.637052) (xy 299.252894 -245.180358)
			)
		)
	)
	(zone
		(layer "In2.Cu")
		(hatch none 0.5)
		(connect_pads
			(clearance 0)
		)
		(min_thickness 0.25)
		(keepout
			(tracks allowed)
			(vias allowed)
			(pads allowed)
			(copperpour allowed)
			(footprints allowed)
		)
		(placement
			(enabled no)
			(sheetname "")
		)
		(fill
			(thermal_gap 0.5)
			(thermal_bridge_width 0.5)
			(island_removal_mode 0)
		)
		(polygon
			(pts
				(xy 313.785758 -300.430438) (xy 313.785758 -299.887132) (xy 314.340494 -299.887132) (xy 314.340494 -300.430438)
			)
		)
	)
	(zone
		(layer "In2.Cu")
		(hatch none 0.5)
		(connect_pads
			(clearance 0)
		)
		(min_thickness 0.25)
		(keepout
			(tracks allowed)
			(vias allowed)
			(pads allowed)
			(copperpour allowed)
			(footprints allowed)
		)
		(placement
			(enabled no)
			(sheetname "")
		)
		(fill
			(thermal_gap 0.5)
			(thermal_bridge_width 0.5)
			(island_removal_mode 0)
		)
		(polygon
			(pts
				(xy 173.038262 -248.88444) (xy 173.038262 -249.413014) (xy 172.502322 -249.413014) (xy 172.502322 -248.88444)
			)
		)
	)
	(zone
		(layer "In2.Cu")
		(hatch none 0.5)
		(connect_pads
			(clearance 0)
		)
		(min_thickness 0.25)
		(keepout
			(tracks allowed)
			(vias allowed)
			(pads allowed)
			(copperpour allowed)
			(footprints allowed)
		)
		(placement
			(enabled no)
			(sheetname "")
		)
		(fill
			(thermal_gap 0.5)
			(thermal_bridge_width 0.5)
			(island_removal_mode 0)
		)
		(polygon
			(pts
				(xy 420.97833 -207.234536) (xy 420.97833 -207.76311) (xy 420.44239 -207.76311) (xy 419.714934 -207.76311)
				(xy 419.714934 -206.90205) (xy 420.042594 -206.90205) (xy 420.37508 -207.234536) (xy 420.44239 -207.234536)
			)
		)
	)
	(zone
		(layer "In2.Cu")
		(hatch none 0.5)
		(connect_pads
			(clearance 0)
		)
		(min_thickness 0.25)
		(keepout
			(tracks allowed)
			(vias allowed)
			(pads allowed)
			(copperpour allowed)
			(footprints allowed)
		)
		(placement
			(enabled no)
			(sheetname "")
		)
		(fill
			(thermal_gap 0.5)
			(thermal_bridge_width 0.5)
			(island_removal_mode 0)
		)
		(polygon
			(pts
				(xy 173.038262 -234.43438) (xy 173.038262 -234.962954) (xy 172.502322 -234.962954) (xy 172.502322 -234.43438)
			)
		)
	)
	(zone
		(layer "In2.Cu")
		(hatch none 0.5)
		(connect_pads
			(clearance 0)
		)
		(min_thickness 0.25)
		(keepout
			(tracks allowed)
			(vias allowed)
			(pads allowed)
			(copperpour allowed)
			(footprints allowed)
		)
		(placement
			(enabled no)
			(sheetname "")
		)
		(fill
			(thermal_gap 0.5)
			(thermal_bridge_width 0.5)
			(island_removal_mode 0)
		)
		(polygon
			(pts
				(xy 173.038262 -212.334856) (xy 173.038262 -212.86343) (xy 172.502322 -212.86343) (xy 172.502322 -212.334856)
			)
		)
	)
	(zone
		(layer "In2.Cu")
		(hatch none 0.5)
		(connect_pads
			(clearance 0)
		)
		(min_thickness 0.25)
		(keepout
			(tracks allowed)
			(vias allowed)
			(pads allowed)
			(copperpour allowed)
			(footprints allowed)
		)
		(placement
			(enabled no)
			(sheetname "")
		)
		(fill
			(thermal_gap 0.5)
			(thermal_bridge_width 0.5)
			(island_removal_mode 0)
		)
		(polygon
			(pts
				(xy 50.78349 -272.380456) (xy 50.78349 -271.83715) (xy 51.338226 -271.83715) (xy 51.338226 -272.380456)
			)
		)
	)
	(zone
		(layer "In2.Cu")
		(hatch none 0.5)
		(connect_pads
			(clearance 0)
		)
		(min_thickness 0.25)
		(keepout
			(tracks allowed)
			(vias allowed)
			(pads allowed)
			(copperpour allowed)
			(footprints allowed)
		)
		(placement
			(enabled no)
			(sheetname "")
		)
		(fill
			(thermal_gap 0.5)
			(thermal_bridge_width 0.5)
			(island_removal_mode 0)
		)
		(polygon
			(pts
				(xy 50.78349 -267.28039) (xy 50.78349 -266.737084) (xy 51.338226 -266.737084) (xy 51.614324 -266.737084)
				(xy 51.614324 -267.28039) (xy 51.338226 -267.28039)
			)
		)
	)
	(zone
		(layer "In2.Cu")
		(hatch none 0.5)
		(connect_pads
			(clearance 0)
		)
		(min_thickness 0.25)
		(keepout
			(tracks allowed)
			(vias allowed)
			(pads allowed)
			(copperpour allowed)
			(footprints allowed)
		)
		(placement
			(enabled no)
			(sheetname "")
		)
		(fill
			(thermal_gap 0.5)
			(thermal_bridge_width 0.5)
			(island_removal_mode 0)
		)
		(polygon
			(pts
				(xy 173.038262 -237.834678) (xy 173.038262 -238.363252) (xy 172.502322 -238.363252) (xy 172.502322 -237.834678)
			)
		)
	)
	(zone
		(layer "In2.Cu")
		(hatch none 0.5)
		(connect_pads
			(clearance 0)
		)
		(min_thickness 0.25)
		(keepout
			(tracks allowed)
			(vias allowed)
			(pads allowed)
			(copperpour allowed)
			(footprints allowed)
		)
		(placement
			(enabled no)
			(sheetname "")
		)
		(fill
			(thermal_gap 0.5)
			(thermal_bridge_width 0.5)
			(island_removal_mode 0)
		)
		(polygon
			(pts
				(xy 157.950662 -225.08464) (xy 157.950662 -225.613214) (xy 157.414722 -225.613214) (xy 157.414722 -225.08464)
			)
		)
	)
	(zone
		(layer "In2.Cu")
		(hatch none 0.5)
		(connect_pads
			(clearance 0)
		)
		(min_thickness 0.25)
		(keepout
			(tracks allowed)
			(vias allowed)
			(pads allowed)
			(copperpour allowed)
			(footprints allowed)
		)
		(placement
			(enabled no)
			(sheetname "")
		)
		(fill
			(thermal_gap 0.5)
			(thermal_bridge_width 0.5)
			(island_removal_mode 0)
		)
		(polygon
			(pts
				(xy 420.97833 -268.434566) (xy 420.97833 -268.96314) (xy 420.44239 -268.96314) (xy 420.44239 -268.6304)
				(xy 420.638224 -268.434566)
			)
		)
	)
	(zone
		(layer "In2.Cu")
		(hatch none 0.5)
		(connect_pads
			(clearance 0)
		)
		(min_thickness 0.25)
		(keepout
			(tracks allowed)
			(vias allowed)
			(pads allowed)
			(copperpour allowed)
			(footprints allowed)
		)
		(placement
			(enabled no)
			(sheetname "")
		)
		(fill
			(thermal_gap 0.5)
			(thermal_bridge_width 0.5)
			(island_removal_mode 0)
		)
		(polygon
			(pts
				(xy 47.06874 -356.530148) (xy 47.06874 -354.955348) (xy 48.87214 -354.955348) (xy 48.87214 -356.530148)
			)
		)
	)
	(zone
		(layer "In2.Cu")
		(hatch none 0.5)
		(connect_pads
			(clearance 0)
		)
		(min_thickness 0.25)
		(keepout
			(tracks allowed)
			(vias allowed)
			(pads allowed)
			(copperpour allowed)
			(footprints allowed)
		)
		(placement
			(enabled no)
			(sheetname "")
		)
		(fill
			(thermal_gap 0.5)
			(thermal_bridge_width 0.5)
			(island_removal_mode 0)
		)
		(polygon
			(pts
				(xy 420.97833 -292.234366) (xy 420.97833 -292.76294) (xy 420.44239 -292.76294) (xy 420.44239 -292.234366)
			)
		)
	)
	(zone
		(layer "In2.Cu")
		(hatch none 0.5)
		(connect_pads
			(clearance 0)
		)
		(min_thickness 0.25)
		(keepout
			(tracks allowed)
			(vias allowed)
			(pads allowed)
			(copperpour allowed)
			(footprints allowed)
		)
		(placement
			(enabled no)
			(sheetname "")
		)
		(fill
			(thermal_gap 0.5)
			(thermal_bridge_width 0.5)
			(island_removal_mode 0)
		)
		(polygon
			(pts
				(xy 420.97833 -215.734646) (xy 420.97833 -216.26322) (xy 420.44239 -216.26322) (xy 420.44239 -215.734646)
			)
		)
	)
	(zone
		(layer "In2.Cu")
		(hatch none 0.5)
		(connect_pads
			(clearance 0)
		)
		(min_thickness 0.25)
		(keepout
			(tracks allowed)
			(vias allowed)
			(pads allowed)
			(copperpour allowed)
			(footprints allowed)
		)
		(placement
			(enabled no)
			(sheetname "")
		)
		(fill
			(thermal_gap 0.5)
			(thermal_bridge_width 0.5)
			(island_removal_mode 0)
		)
		(polygon
			(pts
				(xy 298.723558 -298.730416) (xy 298.723558 -298.18711) (xy 299.278294 -298.18711) (xy 299.278294 -298.730416)
			)
		)
	)
	(zone
		(layer "In2.Cu")
		(hatch none 0.5)
		(connect_pads
			(clearance 0)
		)
		(min_thickness 0.25)
		(keepout
			(tracks allowed)
			(vias allowed)
			(pads allowed)
			(copperpour allowed)
			(footprints allowed)
		)
		(placement
			(enabled no)
			(sheetname "")
		)
		(fill
			(thermal_gap 0.5)
			(thermal_bridge_width 0.5)
			(island_removal_mode 0)
		)
		(polygon
			(pts
				(xy 65.84569 -304.680366) (xy 65.84569 -304.13706) (xy 66.400426 -304.13706) (xy 66.713354 -304.13706)
				(xy 66.713354 -304.680366) (xy 66.400426 -304.680366)
			)
		)
	)
	(zone
		(layer "In2.Cu")
		(hatch none 0.5)
		(connect_pads
			(clearance 0)
		)
		(min_thickness 0.25)
		(keepout
			(tracks allowed)
			(vias allowed)
			(pads allowed)
			(copperpour allowed)
			(footprints allowed)
		)
		(placement
			(enabled no)
			(sheetname "")
		)
		(fill
			(thermal_gap 0.5)
			(thermal_bridge_width 0.5)
			(island_removal_mode 0)
		)
		(polygon
			(pts
				(xy 298.698158 -231.580436) (xy 298.698158 -231.03713) (xy 299.252894 -231.03713) (xy 299.252894 -231.580436)
			)
		)
	)
	(zone
		(layer "In2.Cu")
		(hatch none 0.5)
		(connect_pads
			(clearance 0)
		)
		(min_thickness 0.25)
		(keepout
			(tracks allowed)
			(vias allowed)
			(pads allowed)
			(copperpour allowed)
			(footprints allowed)
		)
		(placement
			(enabled no)
			(sheetname "")
		)
		(fill
			(thermal_gap 0.5)
			(thermal_bridge_width 0.5)
			(island_removal_mode 0)
		)
		(polygon
			(pts
				(xy 337.10626 -341.429848) (xy 337.10626 -338.356448) (xy 332.99908 -338.356448) (xy 332.99908 -341.429848)
			)
		)
	)
	(zone
		(layer "In2.Cu")
		(hatch none 0.5)
		(connect_pads
			(clearance 0)
		)
		(min_thickness 0.25)
		(keepout
			(tracks allowed)
			(vias allowed)
			(pads allowed)
			(copperpour allowed)
			(footprints allowed)
		)
		(placement
			(enabled no)
			(sheetname "")
		)
		(fill
			(thermal_gap 0.5)
			(thermal_bridge_width 0.5)
			(island_removal_mode 0)
		)
		(polygon
			(pts
				(xy 405.89073 -230.184706) (xy 405.89073 -230.71328) (xy 405.35479 -230.71328) (xy 405.35479 -230.184706)
			)
		)
	)
	(zone
		(layer "In2.Cu")
		(hatch none 0.5)
		(connect_pads
			(clearance 0)
		)
		(min_thickness 0.25)
		(keepout
			(tracks allowed)
			(vias allowed)
			(pads allowed)
			(copperpour allowed)
			(footprints allowed)
		)
		(placement
			(enabled no)
			(sheetname "")
		)
		(fill
			(thermal_gap 0.5)
			(thermal_bridge_width 0.5)
			(island_removal_mode 0)
		)
		(polygon
			(pts
				(xy 298.723558 -274.080224) (xy 298.723558 -273.536918) (xy 299.278294 -273.536918) (xy 299.278294 -274.080224)
			)
		)
	)
	(zone
		(layer "In2.Cu")
		(hatch none 0.5)
		(connect_pads
			(clearance 0)
		)
		(min_thickness 0.25)
		(keepout
			(tracks allowed)
			(vias allowed)
			(pads allowed)
			(copperpour allowed)
			(footprints allowed)
		)
		(placement
			(enabled no)
			(sheetname "")
		)
		(fill
			(thermal_gap 0.5)
			(thermal_bridge_width 0.5)
			(island_removal_mode 0)
		)
		(polygon
			(pts
				(xy 85.478366 -287.058862) (xy 85.478366 -284.48254) (xy 85.09508 -284.099254) (xy 85.09508 -282.743148)
				(xy 84.89188 -282.539948) (xy 84.89188 -282.006548) (xy 85.28558 -281.612848) (xy 85.28558 -280.670508)
				(xy 85.55228 -280.403808) (xy 85.55228 -280.304748) (xy 84.40928 -279.161748) (xy 84.40928 -279.076912)
				(xy 84.76488 -278.721312) (xy 84.76488 -278.628348) (xy 83.68792 -277.551388) (xy 83.68792 -277.442676)
				(xy 84.027518 -277.103078) (xy 84.027518 -274.567396) (xy 83.92541 -274.465288) (xy 83.92541 -273.794728)
				(xy 85.62848 -272.091658) (xy 85.62848 -271.973548) (xy 84.00288 -270.347948) (xy 84.00288 -270.303498)
				(xy 84.708492 -269.597886) (xy 84.708492 -269.27556) (xy 84.009992 -268.57706) (xy 80.936846 -271.65046)
				(xy 80.936846 -271.709388) (xy 79.818992 -272.827242) (xy 79.818992 -273.33448) (xy 79.750666 -273.402806)
				(xy 79.750666 -275.006816) (xy 80.172814 -275.428964) (xy 80.172814 -276.236684) (xy 80.172814 -277.257002)
				(xy 77.599032 -279.830784) (xy 76.890626 -280.53919) (xy 76.890626 -280.757376) (xy 76.890626 -280.943304)
				(xy 76.933806 -280.986484) (xy 77.119734 -280.986484) (xy 80.618076 -280.986484) (xy 80.618076 -281.197558)
				(xy 81.183988 -281.76347) (xy 81.183988 -282.385516) (xy 84.215986 -285.417514) (xy 84.215986 -285.796482)
			)
		)
	)
	(zone
		(layer "In2.Cu")
		(hatch none 0.5)
		(connect_pads
			(clearance 0)
		)
		(min_thickness 0.25)
		(keepout
			(tracks allowed)
			(vias allowed)
			(pads allowed)
			(copperpour allowed)
			(footprints allowed)
		)
		(placement
			(enabled no)
			(sheetname "")
		)
		(fill
			(thermal_gap 0.5)
			(thermal_bridge_width 0.5)
			(island_removal_mode 0)
		)
		(polygon
			(pts
				(xy 83.760056 -268.327124) (xy 80.935576 -271.151858) (xy 79.594964 -272.492216) (xy 79.402432 -272.684748)
				(xy 79.402432 -273.539204) (xy 78.505812 -273.539204) (xy 77.753972 -272.787364) (xy 77.416152 -272.787364)
				(xy 77.415898 -272.787872) (xy 76.792582 -272.164556) (xy 79.223362 -269.733776) (xy 79.223362 -269.32763)
				(xy 78.682596 -268.786864) (xy 77.870304 -268.786864) (xy 77.772006 -268.885162) (xy 77.221588 -268.885162)
				(xy 76.946506 -268.61008) (xy 76.946506 -268.262608) (xy 77.925676 -267.283438) (xy 78.207616 -267.283438)
				(xy 80.231488 -265.259566) (xy 80.692498 -265.259566)
			)
		)
	)
	(zone
		(layer "In2.Cu")
		(hatch none 0.5)
		(connect_pads
			(clearance 0)
		)
		(min_thickness 0.25)
		(keepout
			(tracks allowed)
			(vias allowed)
			(pads allowed)
			(copperpour allowed)
			(footprints allowed)
		)
		(placement
			(enabled no)
			(sheetname "")
		)
		(fill
			(thermal_gap 0.5)
			(thermal_bridge_width 0.5)
			(island_removal_mode 0)
		)
		(polygon
			(pts
				(xy 173.038262 -221.684596) (xy 173.038262 -222.21317) (xy 172.502322 -222.21317) (xy 172.502322 -221.684596)
			)
		)
	)
	(zone
		(layer "In2.Cu")
		(hatch none 0.5)
		(connect_pads
			(clearance 0)
		)
		(min_thickness 0.25)
		(keepout
			(tracks allowed)
			(vias allowed)
			(pads allowed)
			(copperpour allowed)
			(footprints allowed)
		)
		(placement
			(enabled no)
			(sheetname "")
		)
		(fill
			(thermal_gap 0.5)
			(thermal_bridge_width 0.5)
			(island_removal_mode 0)
		)
		(polygon
			(pts
				(xy 177.13833 -245.484396) (xy 177.13833 -246.01297) (xy 176.60239 -246.01297) (xy 176.60239 -245.484396)
			)
		)
	)
	(zone
		(layer "In2.Cu")
		(hatch none 0.5)
		(connect_pads
			(clearance 0)
		)
		(min_thickness 0.25)
		(keepout
			(tracks allowed)
			(vias allowed)
			(pads allowed)
			(copperpour allowed)
			(footprints allowed)
		)
		(placement
			(enabled no)
			(sheetname "")
		)
		(fill
			(thermal_gap 0.5)
			(thermal_bridge_width 0.5)
			(island_removal_mode 0)
		)
		(polygon
			(pts
				(xy 173.038262 -206.384398) (xy 173.038262 -206.912972) (xy 172.502322 -206.912972) (xy 172.502322 -206.384398)
			)
		)
	)
	(zone
		(layer "In2.Cu")
		(hatch none 0.5)
		(connect_pads
			(clearance 0)
		)
		(min_thickness 0.25)
		(keepout
			(tracks allowed)
			(vias allowed)
			(pads allowed)
			(copperpour allowed)
			(footprints allowed)
		)
		(placement
			(enabled no)
			(sheetname "")
		)
		(fill
			(thermal_gap 0.5)
			(thermal_bridge_width 0.5)
			(island_removal_mode 0)
		)
		(polygon
			(pts
				(xy 173.038262 -270.984726) (xy 173.038262 -271.5133) (xy 172.502322 -271.5133) (xy 171.988988 -271.5133)
				(xy 171.988988 -270.984726) (xy 172.502322 -270.984726)
			)
		)
	)
	(zone
		(layer "In2.Cu")
		(hatch none 0.5)
		(connect_pads
			(clearance 0)
		)
		(min_thickness 0.25)
		(keepout
			(tracks allowed)
			(vias allowed)
			(pads allowed)
			(copperpour allowed)
			(footprints allowed)
		)
		(placement
			(enabled no)
			(sheetname "")
		)
		(fill
			(thermal_gap 0.5)
			(thermal_bridge_width 0.5)
			(island_removal_mode 0)
		)
		(polygon
			(pts
				(xy 143.89608 -266.039346) (xy 146.53768 -268.680946) (xy 147.110704 -268.680946) (xy 147.25269 -268.822932)
				(xy 148.020786 -268.822932) (xy 148.020786 -269.943072) (xy 147.898866 -269.943072) (xy 147.898866 -271.954752)
				(xy 147.441666 -271.954752) (xy 147.441666 -272.803112) (xy 147.162266 -272.803112) (xy 147.104608 -272.86077)
				(xy 147.104608 -273.53641) (xy 148.617432 -275.049234) (xy 147.549616 -276.117304) (xy 145.419572 -273.987514)
				(xy 145.419572 -273.593814) (xy 144.588992 -272.763234) (xy 142.099792 -270.274034) (xy 141.286992 -270.274034)
				(xy 141.261592 -270.299434) (xy 140.95476 -270.299434) (xy 140.95476 -265.563604) (xy 143.420338 -265.563604)
			)
		)
	)
	(zone
		(layer "In2.Cu")
		(hatch none 0.5)
		(connect_pads
			(clearance 0)
		)
		(min_thickness 0.25)
		(keepout
			(tracks allowed)
			(vias allowed)
			(pads allowed)
			(copperpour allowed)
			(footprints allowed)
		)
		(placement
			(enabled no)
			(sheetname "")
		)
		(fill
			(thermal_gap 0.5)
			(thermal_bridge_width 0.5)
			(island_removal_mode 0)
		)
		(polygon
			(pts
				(xy 420.97833 -222.53448) (xy 420.97833 -223.063054) (xy 420.44239 -223.063054) (xy 420.44239 -222.53448)
			)
		)
	)
	(zone
		(layer "In2.Cu")
		(hatch none 0.5)
		(connect_pads
			(clearance 0)
		)
		(min_thickness 0.25)
		(keepout
			(tracks allowed)
			(vias allowed)
			(pads allowed)
			(copperpour allowed)
			(footprints allowed)
		)
		(placement
			(enabled no)
			(sheetname "")
		)
		(fill
			(thermal_gap 0.5)
			(thermal_bridge_width 0.5)
			(island_removal_mode 0)
		)
		(polygon
			(pts
				(xy 65.84569 -302.980344) (xy 65.84569 -302.437038) (xy 66.400426 -302.437038) (xy 66.400426 -302.980344)
			)
		)
	)
	(zone
		(layer "In2.Cu")
		(hatch none 0.5)
		(connect_pads
			(clearance 0)
		)
		(min_thickness 0.25)
		(keepout
			(tracks allowed)
			(vias allowed)
			(pads allowed)
			(copperpour allowed)
			(footprints allowed)
		)
		(placement
			(enabled no)
			(sheetname "")
		)
		(fill
			(thermal_gap 0.5)
			(thermal_bridge_width 0.5)
			(island_removal_mode 0)
		)
		(polygon
			(pts
				(xy 298.723558 -262.180324) (xy 298.723558 -261.637018) (xy 299.278294 -261.637018) (xy 299.527468 -261.637018)
				(xy 299.527468 -262.180324) (xy 299.278294 -262.180324)
			)
		)
	)
	(zone
		(layer "In2.Cu")
		(hatch none 0.5)
		(connect_pads
			(clearance 0)
		)
		(min_thickness 0.25)
		(keepout
			(tracks allowed)
			(vias allowed)
			(pads allowed)
			(copperpour allowed)
			(footprints allowed)
		)
		(placement
			(enabled no)
			(sheetname "")
		)
		(fill
			(thermal_gap 0.5)
			(thermal_bridge_width 0.5)
			(island_removal_mode 0)
		)
		(polygon
			(pts
				(xy 313.785758 -304.680366) (xy 313.785758 -304.13706) (xy 314.340494 -304.13706) (xy 314.653422 -304.13706)
				(xy 314.653422 -304.680366) (xy 314.340494 -304.680366)
			)
		)
	)
	(zone
		(layer "In2.Cu")
		(hatch none 0.5)
		(connect_pads
			(clearance 0)
		)
		(min_thickness 0.25)
		(keepout
			(tracks allowed)
			(vias allowed)
			(pads allowed)
			(copperpour allowed)
			(footprints allowed)
		)
		(placement
			(enabled no)
			(sheetname "")
		)
		(fill
			(thermal_gap 0.5)
			(thermal_bridge_width 0.5)
			(island_removal_mode 0)
		)
		(polygon
			(pts
				(xy 157.925262 -223.384618) (xy 157.925262 -223.913192) (xy 157.389322 -223.913192) (xy 157.389322 -223.384618)
			)
		)
	)
	(zone
		(layer "In2.Cu")
		(hatch none 0.5)
		(connect_pads
			(clearance 0)
		)
		(min_thickness 0.25)
		(keepout
			(tracks allowed)
			(vias allowed)
			(pads allowed)
			(copperpour allowed)
			(footprints allowed)
		)
		(placement
			(enabled no)
			(sheetname "")
		)
		(fill
			(thermal_gap 0.5)
			(thermal_bridge_width 0.5)
			(island_removal_mode 0)
		)
		(polygon
			(pts
				(xy 333.418434 -287.058862) (xy 333.418434 -284.48254) (xy 333.01559 -284.079696) (xy 333.01559 -282.762198)
				(xy 332.81874 -282.565348) (xy 332.81874 -281.974544) (xy 333.13624 -281.657044) (xy 333.13624 -280.759916)
				(xy 333.404464 -280.491692) (xy 333.404464 -280.212292) (xy 332.36662 -279.174448) (xy 332.36662 -279.05964)
				(xy 332.668118 -278.758142) (xy 332.668118 -278.704548) (xy 331.627988 -277.664418) (xy 331.627988 -277.442676)
				(xy 331.967586 -277.103078) (xy 331.967586 -274.567396) (xy 331.865478 -274.465288) (xy 331.865478 -273.794728)
				(xy 333.57566 -272.084546) (xy 333.57566 -271.983708) (xy 331.95768 -270.365728) (xy 331.95768 -270.288766)
				(xy 332.64856 -269.597886) (xy 332.64856 -269.235428) (xy 331.97038 -268.557248) (xy 328.876914 -271.65046)
				(xy 328.876914 -271.709388) (xy 327.75906 -272.827242) (xy 327.75906 -273.33448) (xy 327.690734 -273.402806)
				(xy 327.690734 -275.006816) (xy 328.112882 -275.428964) (xy 328.112882 -276.236684) (xy 328.112882 -277.257002)
				(xy 325.5391 -279.830784) (xy 324.830694 -280.53919) (xy 324.830694 -280.757376) (xy 324.830694 -280.943304)
				(xy 324.873874 -280.986484) (xy 325.059802 -280.986484) (xy 328.558144 -280.986484) (xy 328.558144 -281.197558)
				(xy 329.124056 -281.76347) (xy 329.124056 -282.385516) (xy 332.156054 -285.417514) (xy 332.156054 -285.796482)
			)
		)
	)
	(zone
		(layer "In2.Cu")
		(hatch none 0.5)
		(connect_pads
			(clearance 0)
		)
		(min_thickness 0.25)
		(keepout
			(tracks allowed)
			(vias allowed)
			(pads allowed)
			(copperpour allowed)
			(footprints allowed)
		)
		(placement
			(enabled no)
			(sheetname "")
		)
		(fill
			(thermal_gap 0.5)
			(thermal_bridge_width 0.5)
			(island_removal_mode 0)
		)
		(polygon
			(pts
				(xy 331.720444 -268.307312) (xy 328.875644 -271.151858) (xy 327.535032 -272.492216) (xy 327.3425 -272.684748)
				(xy 327.3425 -273.539204) (xy 326.44588 -273.539204) (xy 325.69404 -272.787364) (xy 325.35622 -272.787364)
				(xy 325.355966 -272.787872) (xy 324.73265 -272.164556) (xy 327.16343 -269.733776) (xy 327.16343 -269.32763)
				(xy 326.622664 -268.786864) (xy 325.810372 -268.786864) (xy 325.712074 -268.885162) (xy 325.161656 -268.885162)
				(xy 324.886574 -268.61008) (xy 324.886574 -268.262608) (xy 325.865744 -267.283438) (xy 326.147684 -267.283438)
				(xy 328.171556 -265.259566) (xy 328.672698 -265.259566)
			)
		)
	)
	(zone
		(layer "In2.Cu")
		(hatch none 0.5)
		(connect_pads
			(clearance 0)
		)
		(min_thickness 0.25)
		(keepout
			(tracks allowed)
			(vias allowed)
			(pads allowed)
			(copperpour allowed)
			(footprints allowed)
		)
		(placement
			(enabled no)
			(sheetname "")
		)
		(fill
			(thermal_gap 0.5)
			(thermal_bridge_width 0.5)
			(island_removal_mode 0)
		)
		(polygon
			(pts
				(xy 173.038262 -274.384516) (xy 173.038262 -274.91309) (xy 172.502322 -274.91309) (xy 172.502322 -274.384516)
			)
		)
	)
	(zone
		(layer "In2.Cu")
		(hatch none 0.5)
		(connect_pads
			(clearance 0)
		)
		(min_thickness 0.25)
		(keepout
			(tracks allowed)
			(vias allowed)
			(pads allowed)
			(copperpour allowed)
			(footprints allowed)
		)
		(placement
			(enabled no)
			(sheetname "")
		)
		(fill
			(thermal_gap 0.5)
			(thermal_bridge_width 0.5)
			(island_removal_mode 0)
		)
		(polygon
			(pts
				(xy 405.86533 -226.784662) (xy 405.86533 -227.313236) (xy 405.32939 -227.313236) (xy 405.32939 -226.784662)
			)
		)
	)
	(zone
		(layer "In2.Cu")
		(hatch none 0.5)
		(connect_pads
			(clearance 0)
		)
		(min_thickness 0.25)
		(keepout
			(tracks allowed)
			(vias allowed)
			(pads allowed)
			(copperpour allowed)
			(footprints allowed)
		)
		(placement
			(enabled no)
			(sheetname "")
		)
		(fill
			(thermal_gap 0.5)
			(thermal_bridge_width 0.5)
			(island_removal_mode 0)
		)
		(polygon
			(pts
				(xy 50.78349 -280.030428) (xy 50.78349 -279.487122) (xy 51.338226 -279.487122) (xy 51.338226 -280.030428)
			)
		)
	)
	(zone
		(layer "In2.Cu")
		(hatch none 0.5)
		(connect_pads
			(clearance 0)
		)
		(min_thickness 0.25)
		(keepout
			(tracks allowed)
			(vias allowed)
			(pads allowed)
			(copperpour allowed)
			(footprints allowed)
		)
		(placement
			(enabled no)
			(sheetname "")
		)
		(fill
			(thermal_gap 0.5)
			(thermal_bridge_width 0.5)
			(island_removal_mode 0)
		)
		(polygon
			(pts
				(xy 46.658022 -243.480336) (xy 46.658022 -242.93703) (xy 47.212758 -242.93703) (xy 47.212758 -243.480336)
			)
		)
	)
	(zone
		(layer "In2.Cu")
		(hatch none 0.5)
		(connect_pads
			(clearance 0)
		)
		(min_thickness 0.25)
		(keepout
			(tracks allowed)
			(vias allowed)
			(pads allowed)
			(copperpour allowed)
			(footprints allowed)
		)
		(placement
			(enabled no)
			(sheetname "")
		)
		(fill
			(thermal_gap 0.5)
			(thermal_bridge_width 0.5)
			(island_removal_mode 0)
		)
		(polygon
			(pts
				(xy 50.78349 -297.030394) (xy 50.78349 -296.487088) (xy 51.338226 -296.487088) (xy 51.338226 -297.030394)
			)
		)
	)
	(zone
		(layer "In2.Cu")
		(hatch none 0.5)
		(connect_pads
			(clearance 0)
		)
		(min_thickness 0.25)
		(keepout
			(tracks allowed)
			(vias allowed)
			(pads allowed)
			(copperpour allowed)
			(footprints allowed)
		)
		(placement
			(enabled no)
			(sheetname "")
		)
		(fill
			(thermal_gap 0.5)
			(thermal_bridge_width 0.5)
			(island_removal_mode 0)
		)
		(polygon
			(pts
				(xy 149.526498 -283.595572) (xy 146.36623 -283.595572) (xy 146.36623 -283.100018) (xy 144.293336 -281.027124)
				(xy 143.716502 -280.00579) (xy 143.179546 -278.554434) (xy 143.179546 -278.059134) (xy 141.045946 -275.925534)
				(xy 141.044422 -275.925534) (xy 140.95476 -275.835872) (xy 140.95476 -270.71447) (xy 142.083028 -270.71447)
				(xy 142.277846 -270.909288) (xy 147.322286 -275.953474) (xy 147.322286 -277.190454) (xy 148.323046 -278.191214)
				(xy 148.323046 -278.919432) (xy 152.404826 -283.001212) (xy 152.404826 -283.224732) (xy 152.267666 -283.361892)
				(xy 152.097486 -283.361892) (xy 149.925786 -283.361892) (xy 149.692106 -283.595572)
			)
		)
	)
	(zone
		(layer "In2.Cu")
		(hatch none 0.5)
		(connect_pads
			(clearance 0)
		)
		(min_thickness 0.25)
		(keepout
			(tracks allowed)
			(vias allowed)
			(pads allowed)
			(copperpour allowed)
			(footprints allowed)
		)
		(placement
			(enabled no)
			(sheetname "")
		)
		(fill
			(thermal_gap 0.5)
			(thermal_bridge_width 0.5)
			(island_removal_mode 0)
		)
		(polygon
			(pts
				(xy 173.038262 -214.034624) (xy 173.038262 -214.563198) (xy 172.502322 -214.563198) (xy 172.502322 -214.034624)
			)
		)
	)
	(zone
		(layer "In2.Cu")
		(hatch none 0.5)
		(connect_pads
			(clearance 0)
		)
		(min_thickness 0.25)
		(keepout
			(tracks allowed)
			(vias allowed)
			(pads allowed)
			(copperpour allowed)
			(footprints allowed)
		)
		(placement
			(enabled no)
			(sheetname "")
		)
		(fill
			(thermal_gap 0.5)
			(thermal_bridge_width 0.5)
			(island_removal_mode 0)
		)
		(polygon
			(pts
				(xy 175.273462 -267.584428) (xy 175.273462 -268.113002) (xy 174.737522 -268.113002) (xy 174.737522 -267.584428)
			)
		)
	)
	(zone
		(layer "In2.Cu")
		(hatch none 0.5)
		(connect_pads
			(clearance 0)
		)
		(min_thickness 0.25)
		(keepout
			(tracks allowed)
			(vias allowed)
			(pads allowed)
			(copperpour allowed)
			(footprints allowed)
		)
		(placement
			(enabled no)
			(sheetname "")
		)
		(fill
			(thermal_gap 0.5)
			(thermal_bridge_width 0.5)
			(island_removal_mode 0)
		)
		(polygon
			(pts
				(xy 180.556662 -242.93449) (xy 180.556662 -243.463064) (xy 180.020722 -243.463064) (xy 180.020722 -242.93449)
			)
		)
	)
	(zone
		(layer "In2.Cu")
		(hatch none 0.5)
		(connect_pads
			(clearance 0)
		)
		(min_thickness 0.25)
		(keepout
			(tracks allowed)
			(vias allowed)
			(pads allowed)
			(copperpour allowed)
			(footprints allowed)
		)
		(placement
			(enabled no)
			(sheetname "")
		)
		(fill
			(thermal_gap 0.5)
			(thermal_bridge_width 0.5)
			(island_removal_mode 0)
		)
		(polygon
			(pts
				(xy 420.97833 -208.08442) (xy 420.97833 -208.612994) (xy 420.44239 -208.612994) (xy 420.44239 -208.08442)
			)
		)
	)
	(zone
		(layer "In2.Cu")
		(hatch none 0.5)
		(connect_pads
			(clearance 0)
		)
		(min_thickness 0.25)
		(keepout
			(tracks allowed)
			(vias allowed)
			(pads allowed)
			(copperpour allowed)
			(footprints allowed)
		)
		(placement
			(enabled no)
			(sheetname "")
		)
		(fill
			(thermal_gap 0.5)
			(thermal_bridge_width 0.5)
			(island_removal_mode 0)
		)
		(polygon
			(pts
				(xy 173.038262 -294.784526) (xy 173.038262 -295.3131) (xy 172.502322 -295.3131) (xy 172.502322 -294.784526)
			)
		)
	)
	(zone
		(layer "In2.Cu")
		(hatch none 0.5)
		(connect_pads
			(clearance 0)
		)
		(min_thickness 0.25)
		(keepout
			(tracks allowed)
			(vias allowed)
			(pads allowed)
			(copperpour allowed)
			(footprints allowed)
		)
		(placement
			(enabled no)
			(sheetname "")
		)
		(fill
			(thermal_gap 0.5)
			(thermal_bridge_width 0.5)
			(island_removal_mode 0)
		)
		(polygon
			(pts
				(xy 405.89073 -304.13452) (xy 405.89073 -304.663094) (xy 405.35479 -304.663094) (xy 405.35479 -304.13452)
			)
		)
	)
	(zone
		(layer "In2.Cu")
		(hatch none 0.5)
		(connect_pads
			(clearance 0)
		)
		(min_thickness 0.25)
		(keepout
			(tracks allowed)
			(vias allowed)
			(pads allowed)
			(copperpour allowed)
			(footprints allowed)
		)
		(placement
			(enabled no)
			(sheetname "")
		)
		(fill
			(thermal_gap 0.5)
			(thermal_bridge_width 0.5)
			(island_removal_mode 0)
		)
		(polygon
			(pts
				(xy 173.038262 -265.034522) (xy 173.038262 -265.563096) (xy 172.502322 -265.563096) (xy 172.502322 -265.034522)
			)
		)
	)
	(zone
		(layer "In2.Cu")
		(hatch none 0.5)
		(connect_pads
			(clearance 0)
		)
		(min_thickness 0.25)
		(keepout
			(tracks allowed)
			(vias allowed)
			(pads allowed)
			(copperpour allowed)
			(footprints allowed)
		)
		(placement
			(enabled no)
			(sheetname "")
		)
		(fill
			(thermal_gap 0.5)
			(thermal_bridge_width 0.5)
			(island_removal_mode 0)
		)
		(polygon
			(pts
				(xy 420.97833 -240.384584) (xy 420.97833 -240.913158) (xy 420.44239 -240.913158) (xy 420.44239 -240.384584)
			)
		)
	)
	(zone
		(layer "In2.Cu")
		(hatch none 0.5)
		(connect_pads
			(clearance 0)
		)
		(min_thickness 0.25)
		(keepout
			(tracks allowed)
			(vias allowed)
			(pads allowed)
			(copperpour allowed)
			(footprints allowed)
		)
		(placement
			(enabled no)
			(sheetname "")
		)
		(fill
			(thermal_gap 0.5)
			(thermal_bridge_width 0.5)
			(island_removal_mode 0)
		)
		(polygon
			(pts
				(xy 173.038262 -218.284552) (xy 173.038262 -218.813126) (xy 172.502322 -218.813126) (xy 172.502322 -218.284552)
			)
		)
	)
	(zone
		(layer "In2.Cu")
		(hatch none 0.5)
		(connect_pads
			(clearance 0)
		)
		(min_thickness 0.25)
		(keepout
			(tracks allowed)
			(vias allowed)
			(pads allowed)
			(copperpour allowed)
			(footprints allowed)
		)
		(placement
			(enabled no)
			(sheetname "")
		)
		(fill
			(thermal_gap 0.5)
			(thermal_bridge_width 0.5)
			(island_removal_mode 0)
		)
		(polygon
			(pts
				(xy 162.05073 -231.03459) (xy 162.05073 -231.563164) (xy 161.51479 -231.563164) (xy 161.51479 -231.03459)
				(xy 160.67913 -231.03459) (xy 160.67913 -230.220774) (xy 162.05073 -230.220774)
			)
		)
	)
	(zone
		(layer "In2.Cu")
		(hatch none 0.5)
		(connect_pads
			(clearance 0)
		)
		(min_thickness 0.25)
		(keepout
			(tracks allowed)
			(vias allowed)
			(pads allowed)
			(copperpour allowed)
			(footprints allowed)
		)
		(placement
			(enabled no)
			(sheetname "")
		)
		(fill
			(thermal_gap 0.5)
			(thermal_bridge_width 0.5)
			(island_removal_mode 0)
		)
		(polygon
			(pts
				(xy 173.038262 -222.53448) (xy 173.038262 -223.063054) (xy 172.502322 -223.063054) (xy 172.502322 -222.53448)
			)
		)
	)
	(zone
		(layer "In2.Cu")
		(hatch none 0.5)
		(connect_pads
			(clearance 0)
		)
		(min_thickness 0.25)
		(keepout
			(tracks allowed)
			(vias allowed)
			(pads allowed)
			(copperpour allowed)
			(footprints allowed)
		)
		(placement
			(enabled no)
			(sheetname "")
		)
		(fill
			(thermal_gap 0.5)
			(thermal_bridge_width 0.5)
			(island_removal_mode 0)
		)
		(polygon
			(pts
				(xy 46.658022 -266.430252) (xy 46.658022 -265.886946) (xy 47.212758 -265.886946) (xy 47.212758 -266.430252)
			)
		)
	)
	(zone
		(layer "In2.Cu")
		(hatch none 0.5)
		(connect_pads
			(clearance 0)
		)
		(min_thickness 0.25)
		(keepout
			(tracks allowed)
			(vias allowed)
			(pads allowed)
			(copperpour allowed)
			(footprints allowed)
		)
		(placement
			(enabled no)
			(sheetname "")
		)
		(fill
			(thermal_gap 0.5)
			(thermal_bridge_width 0.5)
			(island_removal_mode 0)
		)
		(polygon
			(pts
				(xy 420.97833 -243.784628) (xy 420.97833 -244.313202) (xy 420.44239 -244.313202) (xy 420.44239 -243.784628)
			)
		)
	)
	(zone
		(layer "In2.Cu")
		(hatch none 0.5)
		(connect_pads
			(clearance 0)
		)
		(min_thickness 0.25)
		(keepout
			(tracks allowed)
			(vias allowed)
			(pads allowed)
			(copperpour allowed)
			(footprints allowed)
		)
		(placement
			(enabled no)
			(sheetname "")
		)
		(fill
			(thermal_gap 0.5)
			(thermal_bridge_width 0.5)
			(island_removal_mode 0)
		)
		(polygon
			(pts
				(xy 379.316742 -221.351602) (xy 381.99441 -221.351602) (xy 382.344676 -221.701868) (xy 382.344676 -222.452692)
				(xy 381.99441 -222.802958) (xy 379.36678 -222.802958) (xy 379.11659 -222.552768) (xy 379.11659 -221.551754)
			)
		)
	)
	(zone
		(layer "In2.Cu")
		(hatch none 0.5)
		(connect_pads
			(clearance 0)
		)
		(min_thickness 0.25)
		(keepout
			(tracks allowed)
			(vias allowed)
			(pads allowed)
			(copperpour allowed)
			(footprints allowed)
		)
		(placement
			(enabled no)
			(sheetname "")
		)
		(fill
			(thermal_gap 0.5)
			(thermal_bridge_width 0.5)
			(island_removal_mode 0)
		)
		(polygon
			(pts
				(xy 313.785758 -228.180392) (xy 313.785758 -227.637086) (xy 314.340494 -227.637086) (xy 314.340494 -228.180392)
			)
		)
	)
	(zone
		(layer "In2.Cu")
		(hatch none 0.5)
		(connect_pads
			(clearance 0)
		)
		(min_thickness 0.25)
		(keepout
			(tracks allowed)
			(vias allowed)
			(pads allowed)
			(copperpour allowed)
			(footprints allowed)
		)
		(placement
			(enabled no)
			(sheetname "")
		)
		(fill
			(thermal_gap 0.5)
			(thermal_bridge_width 0.5)
			(island_removal_mode 0)
		)
		(polygon
			(pts
				(xy 173.038262 -207.234536) (xy 173.038262 -207.76311) (xy 172.502322 -207.76311) (xy 171.774866 -207.76311)
				(xy 171.774866 -206.90205) (xy 172.102526 -206.90205) (xy 172.435012 -207.234536) (xy 172.502322 -207.234536)
			)
		)
	)
	(zone
		(layer "In2.Cu")
		(hatch none 0.5)
		(connect_pads
			(clearance 0)
		)
		(min_thickness 0.25)
		(keepout
			(tracks allowed)
			(vias allowed)
			(pads allowed)
			(copperpour allowed)
			(footprints allowed)
		)
		(placement
			(enabled no)
			(sheetname "")
		)
		(fill
			(thermal_gap 0.5)
			(thermal_bridge_width 0.5)
			(island_removal_mode 0)
		)
		(polygon
			(pts
				(xy 50.75809 -206.930244) (xy 50.75809 -206.386938) (xy 51.312826 -206.386938) (xy 51.312826 -206.930244)
			)
		)
	)
	(zone
		(layer "In2.Cu")
		(hatch none 0.5)
		(connect_pads
			(clearance 0)
		)
		(min_thickness 0.25)
		(keepout
			(tracks allowed)
			(vias allowed)
			(pads allowed)
			(copperpour allowed)
			(footprints allowed)
		)
		(placement
			(enabled no)
			(sheetname "")
		)
		(fill
			(thermal_gap 0.5)
			(thermal_bridge_width 0.5)
			(island_removal_mode 0)
		)
		(polygon
			(pts
				(xy 78.189836 -238.883952) (xy 79.666084 -237.407704) (xy 81.774284 -235.299504) (xy 82.70748 -235.29925)
				(xy 82.70748 -239.858804) (xy 82.542126 -240.024158) (xy 78.696058 -240.024412) (xy 77.816964 -240.024412)
				(xy 77.778864 -239.986312) (xy 77.778864 -239.294924)
			)
		)
	)
	(zone
		(layer "In2.Cu")
		(hatch none 0.5)
		(connect_pads
			(clearance 0)
		)
		(min_thickness 0.25)
		(keepout
			(tracks allowed)
			(vias allowed)
			(pads allowed)
			(copperpour allowed)
			(footprints allowed)
		)
		(placement
			(enabled no)
			(sheetname "")
		)
		(fill
			(thermal_gap 0.5)
			(thermal_bridge_width 0.5)
			(island_removal_mode 0)
		)
		(polygon
			(pts
				(xy 420.97833 -286.284416) (xy 420.97833 -286.81299) (xy 420.44239 -286.81299) (xy 420.44239 -286.284416)
			)
		)
	)
	(zone
		(layer "In2.Cu")
		(hatch none 0.5)
		(connect_pads
			(clearance 0)
		)
		(min_thickness 0.25)
		(keepout
			(tracks allowed)
			(vias allowed)
			(pads allowed)
			(copperpour allowed)
			(footprints allowed)
		)
		(placement
			(enabled no)
			(sheetname "")
		)
		(fill
			(thermal_gap 0.5)
			(thermal_bridge_width 0.5)
			(island_removal_mode 0)
		)
		(polygon
			(pts
				(xy 157.950662 -226.784662) (xy 157.950662 -227.313236) (xy 157.414722 -227.313236) (xy 157.414722 -226.784662)
			)
		)
	)
	(zone
		(layer "In2.Cu")
		(hatch none 0.5)
		(connect_pads
			(clearance 0)
		)
		(min_thickness 0.25)
		(keepout
			(tracks allowed)
			(vias allowed)
			(pads allowed)
			(copperpour allowed)
			(footprints allowed)
		)
		(placement
			(enabled no)
			(sheetname "")
		)
		(fill
			(thermal_gap 0.5)
			(thermal_bridge_width 0.5)
			(island_removal_mode 0)
		)
		(polygon
			(pts
				(xy 420.97833 -239.5347) (xy 420.97833 -240.063274) (xy 420.44239 -240.063274) (xy 420.44239 -239.5347)
			)
		)
	)
	(zone
		(layer "In2.Cu")
		(hatch none 0.5)
		(connect_pads
			(clearance 0)
		)
		(min_thickness 0.25)
		(keepout
			(tracks allowed)
			(vias allowed)
			(pads allowed)
			(copperpour allowed)
			(footprints allowed)
		)
		(placement
			(enabled no)
			(sheetname "")
		)
		(fill
			(thermal_gap 0.5)
			(thermal_bridge_width 0.5)
			(island_removal_mode 0)
		)
		(polygon
			(pts
				(xy 405.89073 -224.234502) (xy 405.89073 -224.763076) (xy 405.35479 -224.763076) (xy 405.35479 -224.234502)
			)
		)
	)
	(zone
		(layer "In2.Cu")
		(hatch none 0.5)
		(connect_pads
			(clearance 0)
		)
		(min_thickness 0.25)
		(keepout
			(tracks allowed)
			(vias allowed)
			(pads allowed)
			(copperpour allowed)
			(footprints allowed)
		)
		(placement
			(enabled no)
			(sheetname "")
		)
		(fill
			(thermal_gap 0.5)
			(thermal_bridge_width 0.5)
			(island_removal_mode 0)
		)
		(polygon
			(pts
				(xy 420.97833 -272.68424) (xy 420.97833 -273.212814) (xy 420.44239 -273.212814) (xy 420.44239 -272.68424)
			)
		)
	)
	(zone
		(layer "In2.Cu")
		(hatch none 0.5)
		(connect_pads
			(clearance 0)
		)
		(min_thickness 0.25)
		(keepout
			(tracks allowed)
			(vias allowed)
			(pads allowed)
			(copperpour allowed)
			(footprints allowed)
		)
		(placement
			(enabled no)
			(sheetname "")
		)
		(fill
			(thermal_gap 0.5)
			(thermal_bridge_width 0.5)
			(island_removal_mode 0)
		)
		(polygon
			(pts
				(xy 173.038262 -292.234366) (xy 173.038262 -292.76294) (xy 172.502322 -292.76294) (xy 172.502322 -292.234366)
			)
		)
	)
	(zone
		(layer "In2.Cu")
		(hatch none 0.5)
		(connect_pads
			(clearance 0)
		)
		(min_thickness 0.25)
		(keepout
			(tracks allowed)
			(vias allowed)
			(pads allowed)
			(copperpour allowed)
			(footprints allowed)
		)
		(placement
			(enabled no)
			(sheetname "")
		)
		(fill
			(thermal_gap 0.5)
			(thermal_bridge_width 0.5)
			(island_removal_mode 0)
		)
		(polygon
			(pts
				(xy 298.723558 -270.680434) (xy 298.723558 -270.137128) (xy 299.278294 -270.137128) (xy 299.278294 -270.680434)
			)
		)
	)
	(zone
		(layer "In2.Cu")
		(hatch none 0.5)
		(connect_pads
			(clearance 0)
		)
		(min_thickness 0.25)
		(keepout
			(tracks allowed)
			(vias allowed)
			(pads allowed)
			(copperpour allowed)
			(footprints allowed)
		)
		(placement
			(enabled no)
			(sheetname "")
		)
		(fill
			(thermal_gap 0.5)
			(thermal_bridge_width 0.5)
			(island_removal_mode 0)
		)
		(polygon
			(pts
				(xy 173.038262 -290.534344) (xy 173.038262 -291.062918) (xy 172.502322 -291.062918) (xy 172.502322 -290.534344)
			)
		)
	)
	(zone
		(layer "In2.Cu")
		(hatch none 0.5)
		(connect_pads
			(clearance 0)
		)
		(min_thickness 0.25)
		(keepout
			(tracks allowed)
			(vias allowed)
			(pads allowed)
			(copperpour allowed)
			(footprints allowed)
		)
		(placement
			(enabled no)
			(sheetname "")
		)
		(fill
			(thermal_gap 0.5)
			(thermal_bridge_width 0.5)
			(island_removal_mode 0)
		)
		(polygon
			(pts
				(xy 420.97833 -293.934388) (xy 420.97833 -294.462962) (xy 420.44239 -294.462962) (xy 420.44239 -293.934388)
			)
		)
	)
	(zone
		(layer "In2.Cu")
		(hatch none 0.5)
		(connect_pads
			(clearance 0)
		)
		(min_thickness 0.25)
		(keepout
			(tracks allowed)
			(vias allowed)
			(pads allowed)
			(copperpour allowed)
			(footprints allowed)
		)
		(placement
			(enabled no)
			(sheetname "")
		)
		(fill
			(thermal_gap 0.5)
			(thermal_bridge_width 0.5)
			(island_removal_mode 0)
		)
		(polygon
			(pts
				(xy 420.97833 -267.584682) (xy 420.97833 -268.113256) (xy 420.44239 -268.113256) (xy 419.980618 -268.113256)
				(xy 419.980618 -267.584682) (xy 420.44239 -267.584682)
			)
		)
	)
	(zone
		(layer "In2.Cu")
		(hatch none 0.5)
		(connect_pads
			(clearance 0)
		)
		(min_thickness 0.25)
		(keepout
			(tracks allowed)
			(vias allowed)
			(pads allowed)
			(copperpour allowed)
			(footprints allowed)
		)
		(placement
			(enabled no)
			(sheetname "")
		)
		(fill
			(thermal_gap 0.5)
			(thermal_bridge_width 0.5)
			(island_removal_mode 0)
		)
		(polygon
			(pts
				(xy 173.038262 -212.334602) (xy 173.038262 -212.863176) (xy 172.502322 -212.863176) (xy 172.502322 -212.334602)
			)
		)
	)
	(zone
		(layer "In2.Cu")
		(hatch none 0.5)
		(connect_pads
			(clearance 0)
		)
		(min_thickness 0.25)
		(keepout
			(tracks allowed)
			(vias allowed)
			(pads allowed)
			(copperpour allowed)
			(footprints allowed)
		)
		(placement
			(enabled no)
			(sheetname "")
		)
		(fill
			(thermal_gap 0.5)
			(thermal_bridge_width 0.5)
			(island_removal_mode 0)
		)
		(polygon
			(pts
				(xy 157.950662 -230.184706) (xy 157.950662 -230.71328) (xy 157.414722 -230.71328) (xy 157.414722 -230.184706)
			)
		)
	)
	(zone
		(layer "In2.Cu")
		(hatch none 0.5)
		(connect_pads
			(clearance 0)
		)
		(min_thickness 0.25)
		(keepout
			(tracks allowed)
			(vias allowed)
			(pads allowed)
			(copperpour allowed)
			(footprints allowed)
		)
		(placement
			(enabled no)
			(sheetname "")
		)
		(fill
			(thermal_gap 0.5)
			(thermal_bridge_width 0.5)
			(island_removal_mode 0)
		)
		(polygon
			(pts
				(xy 420.97833 -210.63458) (xy 420.97833 -211.163154) (xy 420.44239 -211.163154) (xy 420.44239 -210.63458)
			)
		)
	)
	(zone
		(layer "In2.Cu")
		(hatch none 0.5)
		(connect_pads
			(clearance 0)
		)
		(min_thickness 0.25)
		(keepout
			(tracks allowed)
			(vias allowed)
			(pads allowed)
			(copperpour allowed)
			(footprints allowed)
		)
		(placement
			(enabled no)
			(sheetname "")
		)
		(fill
			(thermal_gap 0.5)
			(thermal_bridge_width 0.5)
			(island_removal_mode 0)
		)
		(polygon
			(pts
				(xy 79.23276 -347.917008) (xy 79.23276 -346.398088) (xy 81.17332 -346.398088) (xy 81.17332 -347.917008)
			)
		)
	)
	(zone
		(layer "In2.Cu")
		(hatch none 0.5)
		(connect_pads
			(clearance 0)
		)
		(min_thickness 0.25)
		(keepout
			(tracks allowed)
			(vias allowed)
			(pads allowed)
			(copperpour allowed)
			(footprints allowed)
		)
		(placement
			(enabled no)
			(sheetname "")
		)
		(fill
			(thermal_gap 0.5)
			(thermal_bridge_width 0.5)
			(island_removal_mode 0)
		)
		(polygon
			(pts
				(xy 298.723558 -267.28039) (xy 298.723558 -266.737084) (xy 299.278294 -266.737084) (xy 299.554392 -266.737084)
				(xy 299.554392 -267.28039) (xy 299.278294 -267.28039)
			)
		)
	)
	(zone
		(layer "In2.Cu")
		(hatch none 0.5)
		(connect_pads
			(clearance 0)
		)
		(min_thickness 0.25)
		(keepout
			(tracks allowed)
			(vias allowed)
			(pads allowed)
			(copperpour allowed)
			(footprints allowed)
		)
		(placement
			(enabled no)
			(sheetname "")
		)
		(fill
			(thermal_gap 0.5)
			(thermal_bridge_width 0.5)
			(island_removal_mode 0)
		)
		(polygon
			(pts
				(xy 173.038262 -218.284806) (xy 173.038262 -218.81338) (xy 172.502322 -218.81338) (xy 172.502322 -218.284806)
			)
		)
	)
	(zone
		(layer "In2.Cu")
		(hatch none 0.5)
		(connect_pads
			(clearance 0)
		)
		(min_thickness 0.25)
		(keepout
			(tracks allowed)
			(vias allowed)
			(pads allowed)
			(copperpour allowed)
			(footprints allowed)
		)
		(placement
			(enabled no)
			(sheetname "")
		)
		(fill
			(thermal_gap 0.5)
			(thermal_bridge_width 0.5)
			(island_removal_mode 0)
		)
		(polygon
			(pts
				(xy 50.75809 -218.830398) (xy 50.75809 -218.287092) (xy 51.312826 -218.287092) (xy 51.312826 -218.830398)
			)
		)
	)
	(zone
		(layer "In2.Cu")
		(hatch none 0.5)
		(connect_pads
			(clearance 0)
		)
		(min_thickness 0.25)
		(keepout
			(tracks allowed)
			(vias allowed)
			(pads allowed)
			(copperpour allowed)
			(footprints allowed)
		)
		(placement
			(enabled no)
			(sheetname "")
		)
		(fill
			(thermal_gap 0.5)
			(thermal_bridge_width 0.5)
			(island_removal_mode 0)
		)
		(polygon
			(pts
				(xy 173.038262 -282.884372) (xy 173.038262 -283.412946) (xy 172.502322 -283.412946) (xy 172.502322 -282.884372)
			)
		)
	)
	(zone
		(layer "In2.Cu")
		(hatch none 0.5)
		(connect_pads
			(clearance 0)
		)
		(min_thickness 0.25)
		(keepout
			(tracks allowed)
			(vias allowed)
			(pads allowed)
			(copperpour allowed)
			(footprints allowed)
		)
		(placement
			(enabled no)
			(sheetname "")
		)
		(fill
			(thermal_gap 0.5)
			(thermal_bridge_width 0.5)
			(island_removal_mode 0)
		)
		(polygon
			(pts
				(xy 173.038262 -216.584784) (xy 173.038262 -217.113358) (xy 172.502322 -217.113358) (xy 172.502322 -216.584784)
			)
		)
	)
	(zone
		(layer "In2.Cu")
		(hatch none 0.5)
		(connect_pads
			(clearance 0)
		)
		(min_thickness 0.25)
		(keepout
			(tracks allowed)
			(vias allowed)
			(pads allowed)
			(copperpour allowed)
			(footprints allowed)
		)
		(placement
			(enabled no)
			(sheetname "")
		)
		(fill
			(thermal_gap 0.5)
			(thermal_bridge_width 0.5)
			(island_removal_mode 0)
		)
		(polygon
			(pts
				(xy 140.95476 -265.417046) (xy 143.50238 -265.417046) (xy 146.605752 -268.520418) (xy 147.13966 -268.520418)
				(xy 147.306792 -268.353286) (xy 147.306792 -267.819378) (xy 147.306792 -264.927588) (xy 147.381976 -264.927588)
				(xy 147.458176 -264.851388) (xy 147.458176 -262.514588) (xy 145.310098 -260.366764) (xy 140.95476 -260.366764)
			)
		)
	)
	(zone
		(layer "In2.Cu")
		(hatch none 0.5)
		(connect_pads
			(clearance 0)
		)
		(min_thickness 0.25)
		(keepout
			(tracks allowed)
			(vias allowed)
			(pads allowed)
			(copperpour allowed)
			(footprints allowed)
		)
		(placement
			(enabled no)
			(sheetname "")
		)
		(fill
			(thermal_gap 0.5)
			(thermal_bridge_width 0.5)
			(island_removal_mode 0)
		)
		(polygon
			(pts
				(xy 162.05073 -231.884728) (xy 162.05073 -232.413302) (xy 161.51479 -232.413302) (xy 161.51479 -231.884728)
			)
		)
	)
	(zone
		(layer "In2.Cu")
		(hatch none 0.5)
		(connect_pads
			(clearance 0)
		)
		(min_thickness 0.25)
		(keepout
			(tracks allowed)
			(vias allowed)
			(pads allowed)
			(copperpour allowed)
			(footprints allowed)
		)
		(placement
			(enabled no)
			(sheetname "")
		)
		(fill
			(thermal_gap 0.5)
			(thermal_bridge_width 0.5)
			(island_removal_mode 0)
		)
		(polygon
			(pts
				(xy 420.97833 -232.734612) (xy 420.97833 -233.263186) (xy 420.44239 -233.263186) (xy 420.44239 -232.734612)
			)
		)
	)
	(zone
		(layers "In2.Cu" "In4.Cu" "In6.Cu" "In8.Cu" "In9.Cu" "In11.Cu" "In13.Cu"
			"In15.Cu"
		)
		(hatch none 0.5)
		(connect_pads
			(clearance 0)
		)
		(min_thickness 0.25)
		(keepout
			(tracks not_allowed)
			(vias allowed)
			(pads allowed)
			(copperpour not_allowed)
			(footprints allowed)
		)
		(placement
			(enabled no)
			(sheetname "")
		)
		(fill yes
			(thermal_gap 0.5)
			(thermal_bridge_width 0.5)
			(island_removal_mode 0)
		)
		(polygon
			(pts
				(arc
					(start 464.070446 -435.600094)
					(mid 453.529446 -435.600094)
					(end 464.070446 -435.600094)
				)
			)
		)
	)
	(zone
		(layers "In2.Cu" "In4.Cu" "In6.Cu" "In8.Cu" "In9.Cu" "In11.Cu" "In13.Cu"
			"In15.Cu"
		)
		(hatch none 0.5)
		(connect_pads
			(clearance 0)
		)
		(min_thickness 0.25)
		(keepout
			(tracks not_allowed)
			(vias allowed)
			(pads allowed)
			(copperpour not_allowed)
			(footprints allowed)
		)
		(placement
			(enabled no)
			(sheetname "")
		)
		(fill yes
			(thermal_gap 0.5)
			(thermal_bridge_width 0.5)
			(island_removal_mode 0)
		)
		(polygon
			(pts
				(arc
					(start 173.170342 -160.50006)
					(mid 162.629342 -160.50006)
					(end 173.170342 -160.50006)
				)
			)
		)
	)
	(zone
		(layers "In2.Cu" "In4.Cu" "In6.Cu" "In8.Cu" "In9.Cu" "In11.Cu" "In13.Cu"
			"In15.Cu"
		)
		(hatch none 0.5)
		(connect_pads
			(clearance 0)
		)
		(min_thickness 0.25)
		(keepout
			(tracks not_allowed)
			(vias allowed)
			(pads allowed)
			(copperpour not_allowed)
			(footprints allowed)
		)
		(placement
			(enabled no)
			(sheetname "")
		)
		(fill yes
			(thermal_gap 0.5)
			(thermal_bridge_width 0.5)
			(island_removal_mode 0)
		)
		(polygon
			(pts
				(arc
					(start 103.71201 -47.049944)
					(mid 97.053654 -47.049944)
					(end 103.71201 -47.049944)
				)
			)
		)
	)
	(zone
		(layers "In2.Cu" "In4.Cu" "In6.Cu" "In8.Cu" "In9.Cu" "In11.Cu" "In13.Cu"
			"In15.Cu"
		)
		(hatch none 0.5)
		(connect_pads
			(clearance 0)
		)
		(min_thickness 0.25)
		(keepout
			(tracks not_allowed)
			(vias allowed)
			(pads allowed)
			(copperpour not_allowed)
			(footprints allowed)
		)
		(placement
			(enabled no)
			(sheetname "")
		)
		(fill yes
			(thermal_gap 0.5)
			(thermal_bridge_width 0.5)
			(island_removal_mode 0)
		)
		(polygon
			(pts
				(arc
					(start 363.685328 -431.359818)
					(mid 355.86416 -431.359818)
					(end 363.685328 -431.359818)
				)
			)
		)
	)
	(zone
		(layers "In2.Cu" "In4.Cu" "In6.Cu" "In8.Cu" "In9.Cu" "In11.Cu" "In13.Cu"
			"In15.Cu"
		)
		(hatch none 0.5)
		(connect_pads
			(clearance 0)
		)
		(min_thickness 0.25)
		(keepout
			(tracks not_allowed)
			(vias allowed)
			(pads allowed)
			(copperpour not_allowed)
			(footprints allowed)
		)
		(placement
			(enabled no)
			(sheetname "")
		)
		(fill yes
			(thermal_gap 0.5)
			(thermal_bridge_width 0.5)
			(island_removal_mode 0)
		)
		(polygon
			(pts
				(arc
					(start 15.610332 -160.50006)
					(mid 5.069332 -160.50006)
					(end 15.610332 -160.50006)
				)
			)
		)
	)
	(zone
		(layers "In2.Cu" "In4.Cu" "In6.Cu" "In8.Cu" "In9.Cu" "In11.Cu" "In13.Cu"
			"In15.Cu"
		)
		(hatch none 0.5)
		(connect_pads
			(clearance 0)
		)
		(min_thickness 0.25)
		(keepout
			(tracks not_allowed)
			(vias allowed)
			(pads allowed)
			(copperpour not_allowed)
			(footprints allowed)
		)
		(placement
			(enabled no)
			(sheetname "")
		)
		(fill yes
			(thermal_gap 0.5)
			(thermal_bridge_width 0.5)
			(island_removal_mode 0)
		)
		(polygon
			(pts
				(arc
					(start 386.170424 -22.29993)
					(mid 375.629424 -22.29993)
					(end 386.170424 -22.29993)
				)
			)
		)
	)
	(zone
		(layers "In2.Cu" "In4.Cu" "In6.Cu" "In8.Cu" "In9.Cu" "In11.Cu" "In13.Cu"
			"In15.Cu"
		)
		(hatch none 0.5)
		(connect_pads
			(clearance 0)
		)
		(min_thickness 0.25)
		(keepout
			(tracks not_allowed)
			(vias allowed)
			(pads allowed)
			(copperpour not_allowed)
			(footprints allowed)
		)
		(placement
			(enabled no)
			(sheetname "")
		)
		(fill yes
			(thermal_gap 0.5)
			(thermal_bridge_width 0.5)
			(island_removal_mode 0)
		)
		(polygon
			(pts
				(arc
					(start 18.270474 -435.600094)
					(mid 7.729474 -435.600094)
					(end 18.270474 -435.600094)
				)
			)
		)
	)
	(zone
		(layers "In2.Cu" "In4.Cu" "In6.Cu" "In8.Cu" "In9.Cu" "In11.Cu" "In13.Cu"
			"In15.Cu"
		)
		(hatch none 0.5)
		(connect_pads
			(clearance 0)
		)
		(min_thickness 0.25)
		(keepout
			(tracks not_allowed)
			(vias allowed)
			(pads allowed)
			(copperpour not_allowed)
			(footprints allowed)
		)
		(placement
			(enabled no)
			(sheetname "")
		)
		(fill yes
			(thermal_gap 0.5)
			(thermal_bridge_width 0.5)
			(island_removal_mode 0)
		)
		(polygon
			(pts
				(arc
					(start 15.610332 -347.699838)
					(mid 5.069332 -347.699838)
					(end 15.610332 -347.699838)
				)
			)
		)
	)
	(zone
		(layers "In2.Cu" "In4.Cu" "In6.Cu" "In8.Cu" "In9.Cu" "In11.Cu" "In13.Cu"
			"In15.Cu"
		)
		(hatch none 0.5)
		(connect_pads
			(clearance 0)
		)
		(min_thickness 0.25)
		(keepout
			(tracks not_allowed)
			(vias allowed)
			(pads allowed)
			(copperpour not_allowed)
			(footprints allowed)
		)
		(placement
			(enabled no)
			(sheetname "")
		)
		(fill yes
			(thermal_gap 0.5)
			(thermal_bridge_width 0.5)
			(island_removal_mode 0)
		)
		(polygon
			(pts
				(arc
					(start 12.270486 -22.29993)
					(mid 1.729486 -22.29993)
					(end 12.270486 -22.29993)
				)
			)
		)
	)
	(zone
		(layers "In2.Cu" "In4.Cu" "In6.Cu" "In8.Cu" "In9.Cu" "In11.Cu" "In13.Cu"
			"In15.Cu"
		)
		(hatch none 0.5)
		(connect_pads
			(clearance 0)
		)
		(min_thickness 0.25)
		(keepout
			(tracks not_allowed)
			(vias allowed)
			(pads allowed)
			(copperpour not_allowed)
			(footprints allowed)
		)
		(placement
			(enabled no)
			(sheetname "")
		)
		(fill yes
			(thermal_gap 0.5)
			(thermal_bridge_width 0.5)
			(island_removal_mode 0)
		)
		(polygon
			(pts
				(arc
					(start 470.070434 -22.29993)
					(mid 459.529434 -22.29993)
					(end 470.070434 -22.29993)
				)
			)
		)
	)
	(zone
		(layers "In2.Cu" "In4.Cu" "In6.Cu" "In8.Cu" "In9.Cu" "In11.Cu" "In13.Cu"
			"In15.Cu"
		)
		(hatch none 0.5)
		(connect_pads
			(clearance 0)
		)
		(min_thickness 0.25)
		(keepout
			(tracks not_allowed)
			(vias allowed)
			(pads allowed)
			(copperpour not_allowed)
			(footprints allowed)
		)
		(placement
			(enabled no)
			(sheetname "")
		)
		(fill yes
			(thermal_gap 0.5)
			(thermal_bridge_width 0.5)
			(island_removal_mode 0)
		)
		(polygon
			(pts
				(arc
					(start 241.920268 -272.499836)
					(mid 231.379268 -272.499836)
					(end 241.920268 -272.499836)
				)
			)
		)
	)
	(zone
		(layers "In2.Cu" "In4.Cu" "In6.Cu" "In8.Cu" "In9.Cu" "In11.Cu" "In13.Cu"
			"In15.Cu"
		)
		(hatch none 0.5)
		(connect_pads
			(clearance 0)
		)
		(min_thickness 0.25)
		(keepout
			(tracks not_allowed)
			(vias allowed)
			(pads allowed)
			(copperpour not_allowed)
			(footprints allowed)
		)
		(placement
			(enabled no)
			(sheetname "")
		)
		(fill yes
			(thermal_gap 0.5)
			(thermal_bridge_width 0.5)
			(island_removal_mode 0)
		)
		(polygon
			(pts
				(arc
					(start 115.935506 -431.360072)
					(mid 108.114338 -431.360072)
					(end 115.935506 -431.360072)
				)
			)
		)
	)
	(zone
		(layers "In2.Cu" "In4.Cu" "In6.Cu" "In8.Cu" "In9.Cu" "In11.Cu" "In13.Cu"
			"In15.Cu"
		)
		(hatch none 0.5)
		(connect_pads
			(clearance 0)
		)
		(min_thickness 0.25)
		(keepout
			(tracks not_allowed)
			(vias allowed)
			(pads allowed)
			(copperpour not_allowed)
			(footprints allowed)
		)
		(placement
			(enabled no)
			(sheetname "")
		)
		(fill yes
			(thermal_gap 0.5)
			(thermal_bridge_width 0.5)
			(island_removal_mode 0)
		)
		(polygon
			(pts
				(arc
					(start 105.77068 -435.600094)
					(mid 95.22968 -435.600094)
					(end 105.77068 -435.600094)
				)
			)
		)
	)
	(zone
		(layers "In2.Cu" "In4.Cu" "In6.Cu" "In8.Cu" "In9.Cu" "In11.Cu" "In13.Cu"
			"In15.Cu"
		)
		(hatch none 0.5)
		(connect_pads
			(clearance 0)
		)
		(min_thickness 0.25)
		(keepout
			(tracks not_allowed)
			(vias allowed)
			(pads allowed)
			(copperpour not_allowed)
			(footprints allowed)
		)
		(placement
			(enabled no)
			(sheetname "")
		)
		(fill yes
			(thermal_gap 0.5)
			(thermal_bridge_width 0.5)
			(island_removal_mode 0)
		)
		(polygon
			(pts
				(arc
					(start 213.67496 -355.73843)
					(mid 218.70031 -360.743754)
					(end 213.715092 -365.78921)
				)
				(xy 213.67496 -365.789464) (xy 213.67496 -366.017556) (xy 213.726014 -366.017556)
				(arc
					(start 213.726268 -366.017556)
					(mid 218.928947 -360.76382)
					(end 213.726268 -355.510084)
				)
				(xy 213.726014 -355.510084) (xy 213.67496 -355.510084)
			)
		)
	)
	(zone
		(layers "In2.Cu" "In4.Cu" "In6.Cu" "In8.Cu" "In9.Cu" "In11.Cu" "In13.Cu"
			"In15.Cu"
		)
		(hatch none 0.5)
		(connect_pads
			(clearance 0)
		)
		(min_thickness 0.25)
		(keepout
			(tracks not_allowed)
			(vias allowed)
			(pads allowed)
			(copperpour not_allowed)
			(footprints allowed)
		)
		(placement
			(enabled no)
			(sheetname "")
		)
		(fill yes
			(thermal_gap 0.5)
			(thermal_bridge_width 0.5)
			(island_removal_mode 0)
		)
		(polygon
			(pts
				(arc
					(start 258.12496 -355.73843)
					(mid 253.09961 -360.743754)
					(end 258.084828 -365.78921)
				)
				(xy 258.12496 -365.789464) (xy 258.12496 -366.017556) (xy 258.073906 -366.017556)
				(arc
					(start 258.073652 -366.017556)
					(mid 252.870973 -360.76382)
					(end 258.073652 -355.510084)
				)
				(xy 258.073906 -355.510084) (xy 258.12496 -355.510084)
			)
		)
	)
	(zone
		(layers "In2.Cu" "In4.Cu" "In6.Cu" "In8.Cu" "In9.Cu" "In11.Cu" "In13.Cu"
			"In15.Cu"
		)
		(hatch none 0.5)
		(connect_pads
			(clearance 0)
		)
		(min_thickness 0.25)
		(keepout
			(tracks not_allowed)
			(vias allowed)
			(pads allowed)
			(copperpour not_allowed)
			(footprints allowed)
		)
		(placement
			(enabled no)
			(sheetname "")
		)
		(fill yes
			(thermal_gap 0.5)
			(thermal_bridge_width 0.5)
			(island_removal_mode 0)
		)
		(polygon
			(pts
				(arc
					(start 213.67496 -355.73843)
					(mid 208.64961 -360.743754)
					(end 213.634828 -365.78921)
				)
				(xy 213.67496 -365.789464) (xy 213.67496 -366.017556) (xy 213.623906 -366.017556)
				(arc
					(start 213.623652 -366.017556)
					(mid 208.420973 -360.76382)
					(end 213.623652 -355.510084)
				)
				(xy 213.623906 -355.510084) (xy 213.67496 -355.510084)
			)
		)
	)
	(zone
		(layers "In2.Cu" "In4.Cu" "In6.Cu" "In8.Cu" "In9.Cu" "In11.Cu" "In13.Cu"
			"In15.Cu"
		)
		(hatch none 0.5)
		(connect_pads
			(clearance 0)
		)
		(min_thickness 0.25)
		(keepout
			(tracks not_allowed)
			(vias allowed)
			(pads allowed)
			(copperpour not_allowed)
			(footprints allowed)
		)
		(placement
			(enabled no)
			(sheetname "")
		)
		(fill yes
			(thermal_gap 0.5)
			(thermal_bridge_width 0.5)
			(island_removal_mode 0)
		)
		(polygon
			(pts
				(arc
					(start 73.71207 -47.049944)
					(mid 67.053714 -47.049944)
					(end 73.71207 -47.049944)
				)
			)
		)
	)
	(zone
		(layers "In2.Cu" "In4.Cu" "In6.Cu" "In8.Cu" "In9.Cu" "In11.Cu" "In13.Cu"
			"In15.Cu"
		)
		(hatch none 0.5)
		(connect_pads
			(clearance 0)
		)
		(min_thickness 0.25)
		(keepout
			(tracks not_allowed)
			(vias allowed)
			(pads allowed)
			(copperpour not_allowed)
			(footprints allowed)
		)
		(placement
			(enabled no)
			(sheetname "")
		)
		(fill yes
			(thermal_gap 0.5)
			(thermal_bridge_width 0.5)
			(island_removal_mode 0)
		)
		(polygon
			(pts
				(arc
					(start 208.670398 -22.29993)
					(mid 198.129398 -22.29993)
					(end 208.670398 -22.29993)
				)
			)
		)
	)
	(zone
		(layers "In2.Cu" "In4.Cu" "In6.Cu" "In8.Cu" "In9.Cu" "In11.Cu" "In13.Cu"
			"In15.Cu"
		)
		(hatch none 0.5)
		(connect_pads
			(clearance 0)
		)
		(min_thickness 0.25)
		(keepout
			(tracks not_allowed)
			(vias allowed)
			(pads allowed)
			(copperpour not_allowed)
			(footprints allowed)
		)
		(placement
			(enabled no)
			(sheetname "")
		)
		(fill yes
			(thermal_gap 0.5)
			(thermal_bridge_width 0.5)
			(island_removal_mode 0)
		)
		(polygon
			(pts
				(arc
					(start 328.17054 -160.50006)
					(mid 317.62954 -160.50006)
					(end 328.17054 -160.50006)
				)
			)
		)
	)
	(zone
		(layers "In2.Cu" "In4.Cu" "In6.Cu" "In8.Cu" "In9.Cu" "In11.Cu" "In13.Cu"
			"In15.Cu"
		)
		(hatch none 0.5)
		(connect_pads
			(clearance 0)
		)
		(min_thickness 0.25)
		(keepout
			(tracks not_allowed)
			(vias allowed)
			(pads allowed)
			(copperpour not_allowed)
			(footprints allowed)
		)
		(placement
			(enabled no)
			(sheetname "")
		)
		(fill yes
			(thermal_gap 0.5)
			(thermal_bridge_width 0.5)
			(island_removal_mode 0)
		)
		(polygon
			(pts
				(arc
					(start 258.12496 -355.73843)
					(mid 263.15031 -360.743754)
					(end 258.165092 -365.78921)
				)
				(xy 258.12496 -365.789464) (xy 258.12496 -366.017556) (xy 258.176014 -366.017556)
				(arc
					(start 258.176268 -366.017556)
					(mid 263.378947 -360.76382)
					(end 258.176268 -355.510084)
				)
				(xy 258.176014 -355.510084) (xy 258.12496 -355.510084)
			)
		)
	)
	(zone
		(layers "In2.Cu" "In4.Cu" "In6.Cu" "In8.Cu" "In9.Cu" "In11.Cu" "In13.Cu"
			"In15.Cu"
		)
		(hatch none 0.5)
		(connect_pads
			(clearance 0)
		)
		(min_thickness 0.25)
		(keepout
			(tracks not_allowed)
			(vias allowed)
			(pads allowed)
			(copperpour not_allowed)
			(footprints allowed)
		)
		(placement
			(enabled no)
			(sheetname "")
		)
		(fill yes
			(thermal_gap 0.5)
			(thermal_bridge_width 0.5)
			(island_removal_mode 0)
		)
		(polygon
			(pts
				(arc
					(start 209.91576 -51.999896)
					(mid 199.37476 -51.999896)
					(end 209.91576 -51.999896)
				)
			)
		)
	)
	(zone
		(layers "In2.Cu" "In4.Cu" "In6.Cu" "In8.Cu" "In9.Cu" "In11.Cu" "In13.Cu"
			"In15.Cu"
		)
		(hatch none 0.5)
		(connect_pads
			(clearance 0)
		)
		(min_thickness 0.25)
		(keepout
			(tracks not_allowed)
			(vias allowed)
			(pads allowed)
			(copperpour not_allowed)
			(footprints allowed)
		)
		(placement
			(enabled no)
			(sheetname "")
		)
		(fill yes
			(thermal_gap 0.5)
			(thermal_bridge_width 0.5)
			(island_removal_mode 0)
		)
		(polygon
			(pts
				(arc
					(start 376.56897 -435.600094)
					(mid 366.02797 -435.600094)
					(end 376.56897 -435.600094)
				)
			)
		)
	)
	(zone
		(layers "In2.Cu" "In4.Cu" "In6.Cu" "In8.Cu" "In9.Cu" "In11.Cu" "In13.Cu"
			"In15.Cu"
		)
		(hatch none 0.5)
		(connect_pads
			(clearance 0)
		)
		(min_thickness 0.25)
		(keepout
			(tracks not_allowed)
			(vias allowed)
			(pads allowed)
			(copperpour not_allowed)
			(footprints allowed)
		)
		(placement
			(enabled no)
			(sheetname "")
		)
		(fill yes
			(thermal_gap 0.5)
			(thermal_bridge_width 0.5)
			(island_removal_mode 0)
		)
		(polygon
			(pts
				(arc
					(start 466.730334 -347.699838)
					(mid 456.189334 -347.699838)
					(end 466.730334 -347.699838)
				)
			)
		)
	)
	(zone
		(layers "In2.Cu" "In4.Cu" "In6.Cu" "In8.Cu" "In9.Cu" "In11.Cu" "In13.Cu"
			"In15.Cu"
		)
		(hatch none 0.5)
		(connect_pads
			(clearance 0)
		)
		(min_thickness 0.25)
		(keepout
			(tracks not_allowed)
			(vias allowed)
			(pads allowed)
			(copperpour not_allowed)
			(footprints allowed)
		)
		(placement
			(enabled no)
			(sheetname "")
		)
		(fill yes
			(thermal_gap 0.5)
			(thermal_bridge_width 0.5)
			(island_removal_mode 0)
		)
		(polygon
			(pts
				(arc
					(start 241.920268 -352.49993)
					(mid 231.379268 -352.49993)
					(end 241.920268 -352.49993)
				)
			)
		)
	)
	(zone
		(layers "In2.Cu" "In4.Cu" "In6.Cu" "In8.Cu" "In9.Cu" "In11.Cu" "In13.Cu"
			"In15.Cu"
		)
		(hatch none 0.5)
		(connect_pads
			(clearance 0)
		)
		(min_thickness 0.25)
		(keepout
			(tracks not_allowed)
			(vias allowed)
			(pads allowed)
			(copperpour not_allowed)
			(footprints allowed)
		)
		(placement
			(enabled no)
			(sheetname "")
		)
		(fill yes
			(thermal_gap 0.5)
			(thermal_bridge_width 0.5)
			(island_removal_mode 0)
		)
		(polygon
			(pts
				(arc
					(start 273.915632 -51.999896)
					(mid 263.374632 -51.999896)
					(end 273.915632 -51.999896)
				)
			)
		)
	)
	(zone
		(layers "In2.Cu" "In4.Cu" "In6.Cu" "In8.Cu" "In9.Cu" "In11.Cu" "In13.Cu"
			"In15.Cu"
		)
		(hatch none 0.5)
		(connect_pads
			(clearance 0)
		)
		(min_thickness 0.25)
		(keepout
			(tracks not_allowed)
			(vias allowed)
			(pads allowed)
			(copperpour not_allowed)
			(footprints allowed)
		)
		(placement
			(enabled no)
			(sheetname "")
		)
		(fill yes
			(thermal_gap 0.5)
			(thermal_bridge_width 0.5)
			(island_removal_mode 0)
		)
		(polygon
			(pts
				(arc
					(start 100.170488 -22.29993)
					(mid 89.629488 -22.29993)
					(end 100.170488 -22.29993)
				)
			)
		)
	)
	(zone
		(layers "In2.Cu" "In4.Cu" "In6.Cu" "In8.Cu" "In9.Cu" "In11.Cu" "In13.Cu"
			"In15.Cu"
		)
		(hatch none 0.5)
		(connect_pads
			(clearance 0)
		)
		(min_thickness 0.25)
		(keepout
			(tracks not_allowed)
			(vias allowed)
			(pads allowed)
			(copperpour not_allowed)
			(footprints allowed)
		)
		(placement
			(enabled no)
			(sheetname "")
		)
		(fill yes
			(thermal_gap 0.5)
			(thermal_bridge_width 0.5)
			(island_removal_mode 0)
		)
		(polygon
			(pts
				(arc
					(start 241.170206 -81.699862)
					(mid 230.629206 -81.699862)
					(end 241.170206 -81.699862)
				)
			)
		)
	)
	(zone
		(layers "In2.Cu" "In4.Cu" "In6.Cu" "In8.Cu" "In9.Cu" "In11.Cu" "In13.Cu"
			"In15.Cu"
		)
		(hatch none 0.5)
		(connect_pads
			(clearance 0)
		)
		(min_thickness 0.25)
		(keepout
			(tracks not_allowed)
			(vias allowed)
			(pads allowed)
			(copperpour not_allowed)
			(footprints allowed)
		)
		(placement
			(enabled no)
			(sheetname "")
		)
		(fill yes
			(thermal_gap 0.5)
			(thermal_bridge_width 0.5)
			(island_removal_mode 0)
		)
		(polygon
			(pts
				(arc
					(start 270.92021 -22.29993)
					(mid 260.37921 -22.29993)
					(end 270.92021 -22.29993)
				)
			)
		)
	)
	(zone
		(layers "In2.Cu" "In4.Cu" "In6.Cu" "In8.Cu" "In9.Cu" "In11.Cu" "In13.Cu"
			"In15.Cu"
		)
		(hatch none 0.5)
		(connect_pads
			(clearance 0)
		)
		(min_thickness 0.25)
		(keepout
			(tracks not_allowed)
			(vias allowed)
			(pads allowed)
			(copperpour not_allowed)
			(footprints allowed)
		)
		(placement
			(enabled no)
			(sheetname "")
		)
		(fill yes
			(thermal_gap 0.5)
			(thermal_bridge_width 0.5)
			(island_removal_mode 0)
		)
		(polygon
			(pts
				(arc
					(start 466.730334 -160.50006)
					(mid 456.189334 -160.50006)
					(end 466.730334 -160.50006)
				)
			)
		)
	)
	(zone
		(layers "In2.Cu" "In4.Cu" "In6.Cu" "In8.Cu" "In9.Cu" "In11.Cu" "In13.Cu"
			"In15.Cu"
		)
		(hatch none 0.5)
		(connect_pads
			(clearance 0)
		)
		(min_thickness 0.25)
		(keepout
			(tracks not_allowed)
			(vias allowed)
			(pads allowed)
			(copperpour not_allowed)
			(footprints allowed)
		)
		(placement
			(enabled no)
			(sheetname "")
		)
		(fill yes
			(thermal_gap 0.5)
			(thermal_bridge_width 0.5)
			(island_removal_mode 0)
		)
		(polygon
			(pts
				(arc
					(start 241.920268 -192.499996)
					(mid 231.379268 -192.499996)
					(end 241.920268 -192.499996)
				)
			)
		)
	)
	(zone
		(layers "In2.Cu" "In4.Cu" "In6.Cu" "In11.Cu" "In13.Cu")
		(hatch none 0.5)
		(connect_pads
			(clearance 0)
		)
		(min_thickness 0.25)
		(keepout
			(tracks not_allowed)
			(vias allowed)
			(pads allowed)
			(copperpour not_allowed)
			(footprints allowed)
		)
		(placement
			(enabled no)
			(sheetname "")
		)
		(fill yes
			(thermal_gap 0.5)
			(thermal_bridge_width 0.5)
			(island_removal_mode 0)
		)
		(polygon
			(pts
				(arc
					(start 401.32 -183.429148)
					(mid 399.796 -183.429148)
					(end 401.32 -183.429148)
				)
			)
		)
	)
	(zone
		(layers "In2.Cu" "In4.Cu" "In6.Cu" "In11.Cu" "In13.Cu")
		(hatch none 0.5)
		(connect_pads
			(clearance 0)
		)
		(min_thickness 0.25)
		(keepout
			(tracks not_allowed)
			(vias allowed)
			(pads allowed)
			(copperpour not_allowed)
			(footprints allowed)
		)
		(placement
			(enabled no)
			(sheetname "")
		)
		(fill yes
			(thermal_gap 0.5)
			(thermal_bridge_width 0.5)
			(island_removal_mode 0)
		)
		(polygon
			(pts
				(arc
					(start 70.685406 -154.36469)
					(mid 69.161406 -154.36469)
					(end 70.685406 -154.36469)
				)
			)
		)
	)
	(zone
		(layers "In2.Cu" "In4.Cu" "In6.Cu" "In11.Cu" "In13.Cu")
		(hatch none 0.5)
		(connect_pads
			(clearance 0)
		)
		(min_thickness 0.25)
		(keepout
			(tracks not_allowed)
			(vias allowed)
			(pads allowed)
			(copperpour not_allowed)
			(footprints allowed)
		)
		(placement
			(enabled no)
			(sheetname "")
		)
		(fill yes
			(thermal_gap 0.5)
			(thermal_bridge_width 0.5)
			(island_removal_mode 0)
		)
		(polygon
			(pts
				(arc
					(start 401.32 -170.983148)
					(mid 399.796 -170.983148)
					(end 401.32 -170.983148)
				)
			)
		)
	)
	(zone
		(layers "In2.Cu" "In4.Cu" "In6.Cu" "In11.Cu" "In13.Cu")
		(hatch none 0.5)
		(connect_pads
			(clearance 0)
		)
		(min_thickness 0.25)
		(keepout
			(tracks not_allowed)
			(vias allowed)
			(pads allowed)
			(copperpour not_allowed)
			(footprints allowed)
		)
		(placement
			(enabled no)
			(sheetname "")
		)
		(fill yes
			(thermal_gap 0.5)
			(thermal_bridge_width 0.5)
			(island_removal_mode 0)
		)
		(polygon
			(pts
				(arc
					(start 70.685406 -148.228304)
					(mid 69.161406 -148.228304)
					(end 70.685406 -148.228304)
				)
			)
		)
	)
	(zone
		(layers "In2.Cu" "In4.Cu" "In6.Cu" "In11.Cu" "In13.Cu")
		(hatch none 0.5)
		(connect_pads
			(clearance 0)
		)
		(min_thickness 0.25)
		(keepout
			(tracks not_allowed)
			(vias allowed)
			(pads allowed)
			(copperpour not_allowed)
			(footprints allowed)
		)
		(placement
			(enabled no)
			(sheetname "")
		)
		(fill yes
			(thermal_gap 0.5)
			(thermal_bridge_width 0.5)
			(island_removal_mode 0)
		)
		(polygon
			(pts
				(arc
					(start 401.32 -177.206148)
					(mid 399.796 -177.206148)
					(end 401.32 -177.206148)
				)
			)
		)
	)
	(zone
		(layers "In2.Cu" "In4.Cu" "In6.Cu" "In11.Cu" "In13.Cu")
		(hatch none 0.5)
		(connect_pads
			(clearance 0)
		)
		(min_thickness 0.25)
		(keepout
			(tracks not_allowed)
			(vias allowed)
			(pads allowed)
			(copperpour not_allowed)
			(footprints allowed)
		)
		(placement
			(enabled no)
			(sheetname "")
		)
		(fill yes
			(thermal_gap 0.5)
			(thermal_bridge_width 0.5)
			(island_removal_mode 0)
		)
		(polygon
			(pts
				(arc
					(start 70.685406 -160.499806)
					(mid 69.161406 -160.499806)
					(end 70.685406 -160.499806)
				)
			)
		)
	)
	(zone
		(layers "In2.Cu" "In4.Cu" "In6.Cu" "In11.Cu" "In13.Cu" "In15.Cu")
		(hatch none 0.5)
		(connect_pads
			(clearance 0)
		)
		(min_thickness 0.25)
		(keepout
			(tracks not_allowed)
			(vias allowed)
			(pads allowed)
			(copperpour not_allowed)
			(footprints allowed)
		)
		(placement
			(enabled no)
			(sheetname "")
		)
		(fill yes
			(thermal_gap 0.5)
			(thermal_bridge_width 0.5)
			(island_removal_mode 0)
		)
		(polygon
			(pts
				(arc
					(start 185.020458 -435.600094)
					(mid 174.479458 -435.600094)
					(end 185.020458 -435.600094)
				)
			)
		)
	)
	(zone
		(layers "In2.Cu" "In4.Cu" "In6.Cu" "In11.Cu" "In15.Cu")
		(hatch none 0.5)
		(connect_pads
			(clearance 0)
		)
		(min_thickness 0.25)
		(keepout
			(tracks not_allowed)
			(vias allowed)
			(pads allowed)
			(copperpour not_allowed)
			(footprints allowed)
		)
		(placement
			(enabled no)
			(sheetname "")
		)
		(fill yes
			(thermal_gap 0.5)
			(thermal_bridge_width 0.5)
			(island_removal_mode 0)
		)
		(polygon
			(pts
				(arc
					(start 401.32 -164.785548)
					(mid 399.796 -164.785548)
					(end 401.32 -164.785548)
				)
			)
		)
	)
	(zone
		(layers "In2.Cu" "In4.Cu" "In6.Cu" "In11.Cu" "In15.Cu")
		(hatch none 0.5)
		(connect_pads
			(clearance 0)
		)
		(min_thickness 0.25)
		(keepout
			(tracks not_allowed)
			(vias allowed)
			(pads allowed)
			(copperpour not_allowed)
			(footprints allowed)
		)
		(placement
			(enabled no)
			(sheetname "")
		)
		(fill yes
			(thermal_gap 0.5)
			(thermal_bridge_width 0.5)
			(island_removal_mode 0)
		)
		(polygon
			(pts
				(arc
					(start 401.32 -158.562548)
					(mid 399.796 -158.562548)
					(end 401.32 -158.562548)
				)
			)
		)
	)
	(zone
		(layers "In2.Cu" "In4.Cu" "In6.Cu" "In11.Cu" "In15.Cu")
		(hatch none 0.5)
		(connect_pads
			(clearance 0)
		)
		(min_thickness 0.25)
		(keepout
			(tracks not_allowed)
			(vias allowed)
			(pads allowed)
			(copperpour not_allowed)
			(footprints allowed)
		)
		(placement
			(enabled no)
			(sheetname "")
		)
		(fill yes
			(thermal_gap 0.5)
			(thermal_bridge_width 0.5)
			(island_removal_mode 0)
		)
		(polygon
			(pts
				(arc
					(start 69.406008 -177.905156)
					(mid 67.882008 -177.905156)
					(end 69.406008 -177.905156)
				)
			)
		)
	)
	(zone
		(layers "In2.Cu" "In4.Cu" "In6.Cu" "In11.Cu" "In15.Cu")
		(hatch none 0.5)
		(connect_pads
			(clearance 0)
		)
		(min_thickness 0.25)
		(keepout
			(tracks not_allowed)
			(vias allowed)
			(pads allowed)
			(copperpour not_allowed)
			(footprints allowed)
		)
		(placement
			(enabled no)
			(sheetname "")
		)
		(fill yes
			(thermal_gap 0.5)
			(thermal_bridge_width 0.5)
			(island_removal_mode 0)
		)
		(polygon
			(pts
				(arc
					(start 69.406008 -171.77004)
					(mid 67.882008 -171.77004)
					(end 69.406008 -171.77004)
				)
			)
		)
	)
	(zone
		(layers "In2.Cu" "In4.Cu" "In6.Cu" "In11.Cu" "In15.Cu")
		(hatch none 0.5)
		(connect_pads
			(clearance 0)
		)
		(min_thickness 0.25)
		(keepout
			(tracks not_allowed)
			(vias allowed)
			(pads allowed)
			(copperpour not_allowed)
			(footprints allowed)
		)
		(placement
			(enabled no)
			(sheetname "")
		)
		(fill yes
			(thermal_gap 0.5)
			(thermal_bridge_width 0.5)
			(island_removal_mode 0)
		)
		(polygon
			(pts
				(arc
					(start 70.685406 -166.634922)
					(mid 69.161406 -166.634922)
					(end 70.685406 -166.634922)
				)
			)
		)
	)
	(zone
		(layers "In2.Cu" "In4.Cu" "In6.Cu" "In11.Cu" "In15.Cu")
		(hatch none 0.5)
		(connect_pads
			(clearance 0)
		)
		(min_thickness 0.25)
		(keepout
			(tracks not_allowed)
			(vias allowed)
			(pads allowed)
			(copperpour not_allowed)
			(footprints allowed)
		)
		(placement
			(enabled no)
			(sheetname "")
		)
		(fill yes
			(thermal_gap 0.5)
			(thermal_bridge_width 0.5)
			(island_removal_mode 0)
		)
		(polygon
			(pts
				(arc
					(start 401.32 -152.339548)
					(mid 399.796 -152.339548)
					(end 401.32 -152.339548)
				)
			)
		)
	)
	(zone
		(layers "In2.Cu" "In4.Cu" "In13.Cu" "In15.Cu")
		(hatch none 0.5)
		(connect_pads
			(clearance 0)
		)
		(min_thickness 0.25)
		(keepout
			(tracks allowed)
			(vias allowed)
			(pads allowed)
			(copperpour allowed)
			(footprints allowed)
		)
		(placement
			(enabled no)
			(sheetname "")
		)
		(fill yes
			(thermal_gap 0.5)
			(thermal_bridge_width 0.5)
			(island_removal_mode 0)
		)
		(polygon
			(pts
				(xy 912.840186 -85.698076) (xy 929.441626 -85.698076) (xy 930.406826 -84.732876) (xy 930.406826 -68.126356)
				(xy 929.881046 -67.600576) (xy 912.809706 -67.600576) (xy 911.433026 -68.977256) (xy 911.433026 -84.290916)
			)
		)
	)
	(zone
		(layers "In2.Cu" "In4.Cu" "In13.Cu" "In15.Cu")
		(hatch none 0.5)
		(connect_pads
			(clearance 0)
		)
		(min_thickness 0.25)
		(keepout
			(tracks allowed)
			(vias allowed)
			(pads allowed)
			(copperpour allowed)
			(footprints allowed)
		)
		(placement
			(enabled no)
			(sheetname "")
		)
		(fill yes
			(thermal_gap 0.5)
			(thermal_bridge_width 0.5)
			(island_removal_mode 0)
		)
		(polygon
			(pts
				(xy 995.207306 -554.343316) (xy 995.207306 -544.782756) (xy 995.832146 -544.157916) (xy 1009.718326 -544.157916)
				(xy 1010.272046 -544.711636) (xy 1010.272046 -559.263296) (xy 1009.040146 -560.495196) (xy 995.946446 -560.495196)
				(xy 994.793286 -559.342036) (xy 994.793286 -556.868076) (xy 995.105706 -556.555656) (xy 995.207306 -556.454056)
			)
		)
	)
	(zone
		(layers "In3.Cu" "In5.Cu")
		(hatch none 0.5)
		(connect_pads
			(clearance 0)
		)
		(min_thickness 0.25)
		(keepout
			(tracks not_allowed)
			(vias allowed)
			(pads allowed)
			(copperpour not_allowed)
			(footprints allowed)
		)
		(placement
			(enabled no)
			(sheetname "")
		)
		(fill yes
			(thermal_gap 0.5)
			(thermal_bridge_width 0.5)
			(island_removal_mode 0)
		)
		(polygon
			(pts
				(arc
					(start 410.242004 -438.760616)
					(mid 410.264322 -438.814498)
					(end 410.318204 -438.836816)
				)
				(arc
					(start 411.258004 -438.836816)
					(mid 411.311886 -438.814498)
					(end 411.334204 -438.760616)
				)
				(arc
					(start 411.334204 -436.219092)
					(mid 411.311886 -436.16521)
					(end 411.258004 -436.142892)
				)
				(arc
					(start 410.318204 -436.142892)
					(mid 410.264322 -436.16521)
					(end 410.242004 -436.219092)
				)
				(arc
					(start 410.242004 -436.946548)
					(mid 410.244003 -436.963889)
					(end 410.249878 -436.98033)
				)
				(arc
					(start 410.483304 -437.45658)
					(mid 410.491087 -437.490108)
					(end 410.483304 -437.523636)
				)
				(arc
					(start 410.249878 -437.999886)
					(mid 410.243983 -438.016322)
					(end 410.242004 -438.033668)
				)
			)
		)
	)
	(zone
		(layers "In3.Cu" "In5.Cu")
		(hatch none 0.5)
		(connect_pads
			(clearance 0)
		)
		(min_thickness 0.25)
		(keepout
			(tracks not_allowed)
			(vias allowed)
			(pads allowed)
			(copperpour not_allowed)
			(footprints allowed)
		)
		(placement
			(enabled no)
			(sheetname "")
		)
		(fill yes
			(thermal_gap 0.5)
			(thermal_bridge_width 0.5)
			(island_removal_mode 0)
		)
		(polygon
			(pts
				(arc
					(start 68.142104 -436.160418)
					(mid 68.164422 -436.2143)
					(end 68.218304 -436.236618)
				)
				(arc
					(start 69.158104 -436.236618)
					(mid 69.211986 -436.2143)
					(end 69.234304 -436.160418)
				)
				(arc
					(start 69.234304 -433.618894)
					(mid 69.211986 -433.565012)
					(end 69.158104 -433.542694)
				)
				(arc
					(start 68.218304 -433.542694)
					(mid 68.164422 -433.565012)
					(end 68.142104 -433.618894)
				)
				(arc
					(start 68.142104 -434.34635)
					(mid 68.144103 -434.363691)
					(end 68.149978 -434.380132)
				)
				(arc
					(start 68.383404 -434.856382)
					(mid 68.391187 -434.88991)
					(end 68.383404 -434.923438)
				)
				(arc
					(start 68.149978 -435.399688)
					(mid 68.144083 -435.416124)
					(end 68.142104 -435.43347)
				)
			)
		)
	)
	(zone
		(layers "In3.Cu" "In5.Cu")
		(hatch none 0.5)
		(connect_pads
			(clearance 0)
		)
		(min_thickness 0.25)
		(keepout
			(tracks not_allowed)
			(vias allowed)
			(pads allowed)
			(copperpour not_allowed)
			(footprints allowed)
		)
		(placement
			(enabled no)
			(sheetname "")
		)
		(fill yes
			(thermal_gap 0.5)
			(thermal_bridge_width 0.5)
			(island_removal_mode 0)
		)
		(polygon
			(pts
				(arc
					(start 66.142108 -435.16042)
					(mid 66.164426 -435.214302)
					(end 66.218308 -435.23662)
				)
				(arc
					(start 67.158108 -435.23662)
					(mid 67.21199 -435.214302)
					(end 67.234308 -435.16042)
				)
				(arc
					(start 67.234308 -432.618896)
					(mid 67.21199 -432.565014)
					(end 67.158108 -432.542696)
				)
				(arc
					(start 66.218308 -432.542696)
					(mid 66.164426 -432.565014)
					(end 66.142108 -432.618896)
				)
				(arc
					(start 66.142108 -433.346352)
					(mid 66.144107 -433.363693)
					(end 66.149982 -433.380134)
				)
				(arc
					(start 66.383408 -433.856384)
					(mid 66.391191 -433.889912)
					(end 66.383408 -433.92344)
				)
				(arc
					(start 66.149982 -434.39969)
					(mid 66.144087 -434.416126)
					(end 66.142108 -434.433472)
				)
			)
		)
	)
	(zone
		(layers "In3.Cu" "In5.Cu")
		(hatch none 0.5)
		(connect_pads
			(clearance 0)
		)
		(min_thickness 0.25)
		(keepout
			(tracks not_allowed)
			(vias allowed)
			(pads allowed)
			(copperpour not_allowed)
			(footprints allowed)
		)
		(placement
			(enabled no)
			(sheetname "")
		)
		(fill yes
			(thermal_gap 0.5)
			(thermal_bridge_width 0.5)
			(island_removal_mode 0)
		)
		(polygon
			(pts
				(arc
					(start 314.14212 -435.16042)
					(mid 314.164438 -435.214302)
					(end 314.21832 -435.23662)
				)
				(arc
					(start 315.15812 -435.23662)
					(mid 315.212002 -435.214302)
					(end 315.23432 -435.16042)
				)
				(arc
					(start 315.23432 -432.618896)
					(mid 315.212002 -432.565014)
					(end 315.15812 -432.542696)
				)
				(arc
					(start 314.21832 -432.542696)
					(mid 314.164438 -432.565014)
					(end 314.14212 -432.618896)
				)
				(arc
					(start 314.14212 -433.346352)
					(mid 314.144119 -433.363693)
					(end 314.149994 -433.380134)
				)
				(arc
					(start 314.38342 -433.856384)
					(mid 314.391203 -433.889912)
					(end 314.38342 -433.92344)
				)
				(arc
					(start 314.149994 -434.39969)
					(mid 314.144099 -434.416126)
					(end 314.14212 -434.433472)
				)
			)
		)
	)
	(zone
		(layers "In3.Cu" "In5.Cu")
		(hatch none 0.5)
		(connect_pads
			(clearance 0)
		)
		(min_thickness 0.25)
		(keepout
			(tracks not_allowed)
			(vias allowed)
			(pads allowed)
			(copperpour not_allowed)
			(footprints allowed)
		)
		(placement
			(enabled no)
			(sheetname "")
		)
		(fill yes
			(thermal_gap 0.5)
			(thermal_bridge_width 0.5)
			(island_removal_mode 0)
		)
		(polygon
			(pts
				(arc
					(start 345.142058 -436.160418)
					(mid 345.164376 -436.2143)
					(end 345.218258 -436.236618)
				)
				(arc
					(start 346.158058 -436.236618)
					(mid 346.21194 -436.2143)
					(end 346.234258 -436.160418)
				)
				(arc
					(start 346.234258 -433.618894)
					(mid 346.21194 -433.565012)
					(end 346.158058 -433.542694)
				)
				(arc
					(start 345.218258 -433.542694)
					(mid 345.164376 -433.565012)
					(end 345.142058 -433.618894)
				)
				(arc
					(start 345.142058 -434.34635)
					(mid 345.144057 -434.363691)
					(end 345.149932 -434.380132)
				)
				(arc
					(start 345.383358 -434.856382)
					(mid 345.391141 -434.88991)
					(end 345.383358 -434.923438)
				)
				(arc
					(start 345.149932 -435.399688)
					(mid 345.144037 -435.416124)
					(end 345.142058 -435.43347)
				)
			)
		)
	)
	(zone
		(layers "In3.Cu" "In5.Cu")
		(hatch none 0.5)
		(connect_pads
			(clearance 0)
		)
		(min_thickness 0.25)
		(keepout
			(tracks not_allowed)
			(vias allowed)
			(pads allowed)
			(copperpour not_allowed)
			(footprints allowed)
		)
		(placement
			(enabled no)
			(sheetname "")
		)
		(fill yes
			(thermal_gap 0.5)
			(thermal_bridge_width 0.5)
			(island_removal_mode 0)
		)
		(polygon
			(pts
				(arc
					(start 70.1421 -435.16042)
					(mid 70.164418 -435.214302)
					(end 70.2183 -435.23662)
				)
				(arc
					(start 71.1581 -435.23662)
					(mid 71.211982 -435.214302)
					(end 71.2343 -435.16042)
				)
				(arc
					(start 71.2343 -432.618896)
					(mid 71.211982 -432.565014)
					(end 71.1581 -432.542696)
				)
				(arc
					(start 70.2183 -432.542696)
					(mid 70.164418 -432.565014)
					(end 70.1421 -432.618896)
				)
				(arc
					(start 70.1421 -433.346352)
					(mid 70.144099 -433.363693)
					(end 70.149974 -433.380134)
				)
				(arc
					(start 70.3834 -433.856384)
					(mid 70.391183 -433.889912)
					(end 70.3834 -433.92344)
				)
				(arc
					(start 70.149974 -434.39969)
					(mid 70.144079 -434.416126)
					(end 70.1421 -434.433472)
				)
			)
		)
	)
	(zone
		(layers "In3.Cu" "In5.Cu")
		(hatch none 0.5)
		(connect_pads
			(clearance 0)
		)
		(min_thickness 0.25)
		(keepout
			(tracks not_allowed)
			(vias allowed)
			(pads allowed)
			(copperpour not_allowed)
			(footprints allowed)
		)
		(placement
			(enabled no)
			(sheetname "")
		)
		(fill yes
			(thermal_gap 0.5)
			(thermal_bridge_width 0.5)
			(island_removal_mode 0)
		)
		(polygon
			(pts
				(arc
					(start 404.242016 -439.760614)
					(mid 404.264334 -439.814496)
					(end 404.318216 -439.836814)
				)
				(arc
					(start 405.258016 -439.836814)
					(mid 405.311898 -439.814496)
					(end 405.334216 -439.760614)
				)
				(arc
					(start 405.334216 -437.21909)
					(mid 405.311898 -437.165208)
					(end 405.258016 -437.14289)
				)
				(arc
					(start 404.318216 -437.14289)
					(mid 404.264334 -437.165208)
					(end 404.242016 -437.21909)
				)
				(arc
					(start 404.242016 -437.946546)
					(mid 404.244015 -437.963887)
					(end 404.24989 -437.980328)
				)
				(arc
					(start 404.483316 -438.456578)
					(mid 404.491099 -438.490106)
					(end 404.483316 -438.523634)
				)
				(arc
					(start 404.24989 -438.999884)
					(mid 404.243995 -439.01632)
					(end 404.242016 -439.033666)
				)
			)
		)
	)
	(zone
		(layers "In3.Cu" "In5.Cu")
		(hatch none 0.5)
		(connect_pads
			(clearance 0)
		)
		(min_thickness 0.25)
		(keepout
			(tracks not_allowed)
			(vias allowed)
			(pads allowed)
			(copperpour not_allowed)
			(footprints allowed)
		)
		(placement
			(enabled no)
			(sheetname "")
		)
		(fill yes
			(thermal_gap 0.5)
			(thermal_bridge_width 0.5)
			(island_removal_mode 0)
		)
		(polygon
			(pts
				(arc
					(start 335.142078 -435.16042)
					(mid 335.164396 -435.214302)
					(end 335.218278 -435.23662)
				)
				(arc
					(start 336.158078 -435.23662)
					(mid 336.21196 -435.214302)
					(end 336.234278 -435.16042)
				)
				(arc
					(start 336.234278 -432.618896)
					(mid 336.21196 -432.565014)
					(end 336.158078 -432.542696)
				)
				(arc
					(start 335.218278 -432.542696)
					(mid 335.164396 -432.565014)
					(end 335.142078 -432.618896)
				)
				(arc
					(start 335.142078 -433.346352)
					(mid 335.144077 -433.363693)
					(end 335.149952 -433.380134)
				)
				(arc
					(start 335.383378 -433.856384)
					(mid 335.391161 -433.889912)
					(end 335.383378 -433.92344)
				)
				(arc
					(start 335.149952 -434.39969)
					(mid 335.144057 -434.416126)
					(end 335.142078 -434.433472)
				)
			)
		)
	)
	(zone
		(layers "In3.Cu" "In5.Cu")
		(hatch none 0.5)
		(connect_pads
			(clearance 0)
		)
		(min_thickness 0.25)
		(keepout
			(tracks not_allowed)
			(vias allowed)
			(pads allowed)
			(copperpour not_allowed)
			(footprints allowed)
		)
		(placement
			(enabled no)
			(sheetname "")
		)
		(fill yes
			(thermal_gap 0.5)
			(thermal_bridge_width 0.5)
			(island_removal_mode 0)
		)
		(polygon
			(pts
				(arc
					(start 322.142104 -435.16042)
					(mid 322.164422 -435.214302)
					(end 322.218304 -435.23662)
				)
				(arc
					(start 323.158104 -435.23662)
					(mid 323.211986 -435.214302)
					(end 323.234304 -435.16042)
				)
				(arc
					(start 323.234304 -432.618896)
					(mid 323.211986 -432.565014)
					(end 323.158104 -432.542696)
				)
				(arc
					(start 322.218304 -432.542696)
					(mid 322.164422 -432.565014)
					(end 322.142104 -432.618896)
				)
				(arc
					(start 322.142104 -433.346352)
					(mid 322.144103 -433.363693)
					(end 322.149978 -433.380134)
				)
				(arc
					(start 322.383404 -433.856384)
					(mid 322.391187 -433.889912)
					(end 322.383404 -433.92344)
				)
				(arc
					(start 322.149978 -434.39969)
					(mid 322.144083 -434.416126)
					(end 322.142104 -434.433472)
				)
			)
		)
	)
	(zone
		(layers "In3.Cu" "In5.Cu")
		(hatch none 0.5)
		(connect_pads
			(clearance 0)
		)
		(min_thickness 0.25)
		(keepout
			(tracks not_allowed)
			(vias allowed)
			(pads allowed)
			(copperpour not_allowed)
			(footprints allowed)
		)
		(placement
			(enabled no)
			(sheetname "")
		)
		(fill yes
			(thermal_gap 0.5)
			(thermal_bridge_width 0.5)
			(island_removal_mode 0)
		)
		(polygon
			(pts
				(arc
					(start 343.142062 -435.16042)
					(mid 343.16438 -435.214302)
					(end 343.218262 -435.23662)
				)
				(arc
					(start 344.158062 -435.23662)
					(mid 344.211944 -435.214302)
					(end 344.234262 -435.16042)
				)
				(arc
					(start 344.234262 -432.618896)
					(mid 344.211944 -432.565014)
					(end 344.158062 -432.542696)
				)
				(arc
					(start 343.218262 -432.542696)
					(mid 343.16438 -432.565014)
					(end 343.142062 -432.618896)
				)
				(arc
					(start 343.142062 -433.346352)
					(mid 343.144061 -433.363693)
					(end 343.149936 -433.380134)
				)
				(arc
					(start 343.383362 -433.856384)
					(mid 343.391145 -433.889912)
					(end 343.383362 -433.92344)
				)
				(arc
					(start 343.149936 -434.39969)
					(mid 343.144041 -434.416126)
					(end 343.142062 -434.433472)
				)
			)
		)
	)
	(zone
		(layers "In3.Cu" "In5.Cu")
		(hatch none 0.5)
		(connect_pads
			(clearance 0)
		)
		(min_thickness 0.25)
		(keepout
			(tracks not_allowed)
			(vias allowed)
			(pads allowed)
			(copperpour not_allowed)
			(footprints allowed)
		)
		(placement
			(enabled no)
			(sheetname "")
		)
		(fill yes
			(thermal_gap 0.5)
			(thermal_bridge_width 0.5)
			(island_removal_mode 0)
		)
		(polygon
			(pts
				(arc
					(start 137.242042 -438.760616)
					(mid 137.26436 -438.814498)
					(end 137.318242 -438.836816)
				)
				(arc
					(start 138.258042 -438.836816)
					(mid 138.311924 -438.814498)
					(end 138.334242 -438.760616)
				)
				(arc
					(start 138.334242 -436.219092)
					(mid 138.311924 -436.16521)
					(end 138.258042 -436.142892)
				)
				(arc
					(start 137.318242 -436.142892)
					(mid 137.26436 -436.16521)
					(end 137.242042 -436.219092)
				)
				(arc
					(start 137.242042 -436.946548)
					(mid 137.244041 -436.963889)
					(end 137.249916 -436.98033)
				)
				(arc
					(start 137.483342 -437.45658)
					(mid 137.491125 -437.490108)
					(end 137.483342 -437.523636)
				)
				(arc
					(start 137.249916 -437.999886)
					(mid 137.244021 -438.016322)
					(end 137.242042 -438.033668)
				)
			)
		)
	)
	(zone
		(layers "In3.Cu" "In5.Cu")
		(hatch none 0.5)
		(connect_pads
			(clearance 0)
		)
		(min_thickness 0.25)
		(keepout
			(tracks not_allowed)
			(vias allowed)
			(pads allowed)
			(copperpour not_allowed)
			(footprints allowed)
		)
		(placement
			(enabled no)
			(sheetname "")
		)
		(fill yes
			(thermal_gap 0.5)
			(thermal_bridge_width 0.5)
			(island_removal_mode 0)
		)
		(polygon
			(pts
				(arc
					(start 72.142096 -436.160418)
					(mid 72.164414 -436.2143)
					(end 72.218296 -436.236618)
				)
				(arc
					(start 73.158096 -436.236618)
					(mid 73.211978 -436.2143)
					(end 73.234296 -436.160418)
				)
				(arc
					(start 73.234296 -433.618894)
					(mid 73.211978 -433.565012)
					(end 73.158096 -433.542694)
				)
				(arc
					(start 72.218296 -433.542694)
					(mid 72.164414 -433.565012)
					(end 72.142096 -433.618894)
				)
				(arc
					(start 72.142096 -434.34635)
					(mid 72.144095 -434.363691)
					(end 72.14997 -434.380132)
				)
				(arc
					(start 72.383396 -434.856382)
					(mid 72.391179 -434.88991)
					(end 72.383396 -434.923438)
				)
				(arc
					(start 72.14997 -435.399688)
					(mid 72.144075 -435.416124)
					(end 72.142096 -435.43347)
				)
			)
		)
	)
	(zone
		(layers "In3.Cu" "In5.Cu")
		(hatch none 0.5)
		(connect_pads
			(clearance 0)
		)
		(min_thickness 0.25)
		(keepout
			(tracks not_allowed)
			(vias allowed)
			(pads allowed)
			(copperpour not_allowed)
			(footprints allowed)
		)
		(placement
			(enabled no)
			(sheetname "")
		)
		(fill yes
			(thermal_gap 0.5)
			(thermal_bridge_width 0.5)
			(island_removal_mode 0)
		)
		(polygon
			(pts
				(arc
					(start 87.142066 -435.16042)
					(mid 87.164384 -435.214302)
					(end 87.218266 -435.23662)
				)
				(arc
					(start 88.158066 -435.23662)
					(mid 88.211948 -435.214302)
					(end 88.234266 -435.16042)
				)
				(arc
					(start 88.234266 -432.618896)
					(mid 88.211948 -432.565014)
					(end 88.158066 -432.542696)
				)
				(arc
					(start 87.218266 -432.542696)
					(mid 87.164384 -432.565014)
					(end 87.142066 -432.618896)
				)
				(arc
					(start 87.142066 -433.346352)
					(mid 87.144065 -433.363693)
					(end 87.14994 -433.380134)
				)
				(arc
					(start 87.383366 -433.856384)
					(mid 87.391149 -433.889912)
					(end 87.383366 -433.92344)
				)
				(arc
					(start 87.14994 -434.39969)
					(mid 87.144045 -434.416126)
					(end 87.142066 -434.433472)
				)
			)
		)
	)
	(zone
		(layers "In3.Cu" "In5.Cu")
		(hatch none 0.5)
		(connect_pads
			(clearance 0)
		)
		(min_thickness 0.25)
		(keepout
			(tracks not_allowed)
			(vias allowed)
			(pads allowed)
			(copperpour not_allowed)
			(footprints allowed)
		)
		(placement
			(enabled no)
			(sheetname "")
		)
		(fill yes
			(thermal_gap 0.5)
			(thermal_bridge_width 0.5)
			(island_removal_mode 0)
		)
		(polygon
			(pts
				(arc
					(start 398.242028 -438.760616)
					(mid 398.264346 -438.814498)
					(end 398.318228 -438.836816)
				)
				(arc
					(start 399.258028 -438.836816)
					(mid 399.31191 -438.814498)
					(end 399.334228 -438.760616)
				)
				(arc
					(start 399.334228 -436.219092)
					(mid 399.31191 -436.16521)
					(end 399.258028 -436.142892)
				)
				(arc
					(start 398.318228 -436.142892)
					(mid 398.264346 -436.16521)
					(end 398.242028 -436.219092)
				)
				(arc
					(start 398.242028 -436.946548)
					(mid 398.244027 -436.963889)
					(end 398.249902 -436.98033)
				)
				(arc
					(start 398.483328 -437.45658)
					(mid 398.491111 -437.490108)
					(end 398.483328 -437.523636)
				)
				(arc
					(start 398.249902 -437.999886)
					(mid 398.244007 -438.016322)
					(end 398.242028 -438.033668)
				)
			)
		)
	)
	(zone
		(layers "In3.Cu" "In5.Cu")
		(hatch none 0.5)
		(connect_pads
			(clearance 0)
		)
		(min_thickness 0.25)
		(keepout
			(tracks not_allowed)
			(vias allowed)
			(pads allowed)
			(copperpour not_allowed)
			(footprints allowed)
		)
		(placement
			(enabled no)
			(sheetname "")
		)
		(fill yes
			(thermal_gap 0.5)
			(thermal_bridge_width 0.5)
			(island_removal_mode 0)
		)
		(polygon
			(pts
				(arc
					(start 393.242038 -438.760616)
					(mid 393.264356 -438.814498)
					(end 393.318238 -438.836816)
				)
				(arc
					(start 394.258038 -438.836816)
					(mid 394.31192 -438.814498)
					(end 394.334238 -438.760616)
				)
				(arc
					(start 394.334238 -436.219092)
					(mid 394.31192 -436.16521)
					(end 394.258038 -436.142892)
				)
				(arc
					(start 393.318238 -436.142892)
					(mid 393.264356 -436.16521)
					(end 393.242038 -436.219092)
				)
				(arc
					(start 393.242038 -436.946548)
					(mid 393.244037 -436.963889)
					(end 393.249912 -436.98033)
				)
				(arc
					(start 393.483338 -437.45658)
					(mid 393.491121 -437.490108)
					(end 393.483338 -437.523636)
				)
				(arc
					(start 393.249912 -437.999886)
					(mid 393.244017 -438.016322)
					(end 393.242038 -438.033668)
				)
			)
		)
	)
	(zone
		(layers "In3.Cu" "In5.Cu")
		(hatch none 0.5)
		(connect_pads
			(clearance 0)
		)
		(min_thickness 0.25)
		(keepout
			(tracks not_allowed)
			(vias allowed)
			(pads allowed)
			(copperpour not_allowed)
			(footprints allowed)
		)
		(placement
			(enabled no)
			(sheetname "")
		)
		(fill yes
			(thermal_gap 0.5)
			(thermal_bridge_width 0.5)
			(island_removal_mode 0)
		)
		(polygon
			(pts
				(arc
					(start 152.242012 -439.760614)
					(mid 152.26433 -439.814496)
					(end 152.318212 -439.836814)
				)
				(arc
					(start 153.258012 -439.836814)
					(mid 153.311894 -439.814496)
					(end 153.334212 -439.760614)
				)
				(arc
					(start 153.334212 -437.21909)
					(mid 153.311894 -437.165208)
					(end 153.258012 -437.14289)
				)
				(arc
					(start 152.318212 -437.14289)
					(mid 152.26433 -437.165208)
					(end 152.242012 -437.21909)
				)
				(arc
					(start 152.242012 -437.946546)
					(mid 152.244011 -437.963887)
					(end 152.249886 -437.980328)
				)
				(arc
					(start 152.483312 -438.456578)
					(mid 152.491095 -438.490106)
					(end 152.483312 -438.523634)
				)
				(arc
					(start 152.249886 -438.999884)
					(mid 152.243991 -439.01632)
					(end 152.242012 -439.033666)
				)
			)
		)
	)
	(zone
		(layers "In3.Cu" "In5.Cu")
		(hatch none 0.5)
		(connect_pads
			(clearance 0)
		)
		(min_thickness 0.25)
		(keepout
			(tracks not_allowed)
			(vias allowed)
			(pads allowed)
			(copperpour not_allowed)
			(footprints allowed)
		)
		(placement
			(enabled no)
			(sheetname "")
		)
		(fill yes
			(thermal_gap 0.5)
			(thermal_bridge_width 0.5)
			(island_removal_mode 0)
		)
		(polygon
			(pts
				(arc
					(start 81.142078 -436.160418)
					(mid 81.164396 -436.2143)
					(end 81.218278 -436.236618)
				)
				(arc
					(start 82.158078 -436.236618)
					(mid 82.21196 -436.2143)
					(end 82.234278 -436.160418)
				)
				(arc
					(start 82.234278 -433.618894)
					(mid 82.21196 -433.565012)
					(end 82.158078 -433.542694)
				)
				(arc
					(start 81.218278 -433.542694)
					(mid 81.164396 -433.565012)
					(end 81.142078 -433.618894)
				)
				(arc
					(start 81.142078 -434.34635)
					(mid 81.144077 -434.363691)
					(end 81.149952 -434.380132)
				)
				(arc
					(start 81.383378 -434.856382)
					(mid 81.391161 -434.88991)
					(end 81.383378 -434.923438)
				)
				(arc
					(start 81.149952 -435.399688)
					(mid 81.144057 -435.416124)
					(end 81.142078 -435.43347)
				)
			)
		)
	)
	(zone
		(layers "In3.Cu" "In5.Cu")
		(hatch none 0.5)
		(connect_pads
			(clearance 0)
		)
		(min_thickness 0.25)
		(keepout
			(tracks not_allowed)
			(vias allowed)
			(pads allowed)
			(copperpour not_allowed)
			(footprints allowed)
		)
		(placement
			(enabled no)
			(sheetname "")
		)
		(fill yes
			(thermal_gap 0.5)
			(thermal_bridge_width 0.5)
			(island_removal_mode 0)
		)
		(polygon
			(pts
				(arc
					(start 146.242024 -438.760616)
					(mid 146.264342 -438.814498)
					(end 146.318224 -438.836816)
				)
				(arc
					(start 147.258024 -438.836816)
					(mid 147.311906 -438.814498)
					(end 147.334224 -438.760616)
				)
				(arc
					(start 147.334224 -436.219092)
					(mid 147.311906 -436.16521)
					(end 147.258024 -436.142892)
				)
				(arc
					(start 146.318224 -436.142892)
					(mid 146.264342 -436.16521)
					(end 146.242024 -436.219092)
				)
				(arc
					(start 146.242024 -436.946548)
					(mid 146.244023 -436.963889)
					(end 146.249898 -436.98033)
				)
				(arc
					(start 146.483324 -437.45658)
					(mid 146.491107 -437.490108)
					(end 146.483324 -437.523636)
				)
				(arc
					(start 146.249898 -437.999886)
					(mid 146.244003 -438.016322)
					(end 146.242024 -438.033668)
				)
			)
		)
	)
	(zone
		(layers "In3.Cu" "In5.Cu")
		(hatch none 0.5)
		(connect_pads
			(clearance 0)
		)
		(min_thickness 0.25)
		(keepout
			(tracks not_allowed)
			(vias allowed)
			(pads allowed)
			(copperpour not_allowed)
			(footprints allowed)
		)
		(placement
			(enabled no)
			(sheetname "")
		)
		(fill yes
			(thermal_gap 0.5)
			(thermal_bridge_width 0.5)
			(island_removal_mode 0)
		)
		(polygon
			(pts
				(arc
					(start 139.242038 -439.760614)
					(mid 139.264356 -439.814496)
					(end 139.318238 -439.836814)
				)
				(arc
					(start 140.258038 -439.836814)
					(mid 140.31192 -439.814496)
					(end 140.334238 -439.760614)
				)
				(arc
					(start 140.334238 -437.21909)
					(mid 140.31192 -437.165208)
					(end 140.258038 -437.14289)
				)
				(arc
					(start 139.318238 -437.14289)
					(mid 139.264356 -437.165208)
					(end 139.242038 -437.21909)
				)
				(arc
					(start 139.242038 -437.946546)
					(mid 139.244037 -437.963887)
					(end 139.249912 -437.980328)
				)
				(arc
					(start 139.483338 -438.456578)
					(mid 139.491121 -438.490106)
					(end 139.483338 -438.523634)
				)
				(arc
					(start 139.249912 -438.999884)
					(mid 139.244017 -439.01632)
					(end 139.242038 -439.033666)
				)
			)
		)
	)
	(zone
		(layers "In3.Cu" "In5.Cu")
		(hatch none 0.5)
		(connect_pads
			(clearance 0)
		)
		(min_thickness 0.25)
		(keepout
			(tracks not_allowed)
			(vias allowed)
			(pads allowed)
			(copperpour not_allowed)
			(footprints allowed)
		)
		(placement
			(enabled no)
			(sheetname "")
		)
		(fill yes
			(thermal_gap 0.5)
			(thermal_bridge_width 0.5)
			(island_removal_mode 0)
		)
		(polygon
			(pts
				(arc
					(start 318.142112 -435.16042)
					(mid 318.16443 -435.214302)
					(end 318.218312 -435.23662)
				)
				(arc
					(start 319.158112 -435.23662)
					(mid 319.211994 -435.214302)
					(end 319.234312 -435.16042)
				)
				(arc
					(start 319.234312 -432.618896)
					(mid 319.211994 -432.565014)
					(end 319.158112 -432.542696)
				)
				(arc
					(start 318.218312 -432.542696)
					(mid 318.16443 -432.565014)
					(end 318.142112 -432.618896)
				)
				(arc
					(start 318.142112 -433.346352)
					(mid 318.144111 -433.363693)
					(end 318.149986 -433.380134)
				)
				(arc
					(start 318.383412 -433.856384)
					(mid 318.391195 -433.889912)
					(end 318.383412 -433.92344)
				)
				(arc
					(start 318.149986 -434.39969)
					(mid 318.144091 -434.416126)
					(end 318.142112 -434.433472)
				)
			)
		)
	)
	(zone
		(layers "In3.Cu" "In5.Cu")
		(hatch none 0.5)
		(connect_pads
			(clearance 0)
		)
		(min_thickness 0.25)
		(keepout
			(tracks not_allowed)
			(vias allowed)
			(pads allowed)
			(copperpour not_allowed)
			(footprints allowed)
		)
		(placement
			(enabled no)
			(sheetname "")
		)
		(fill yes
			(thermal_gap 0.5)
			(thermal_bridge_width 0.5)
			(island_removal_mode 0)
		)
		(polygon
			(pts
				(arc
					(start 408.242008 -439.760614)
					(mid 408.264326 -439.814496)
					(end 408.318208 -439.836814)
				)
				(arc
					(start 409.258008 -439.836814)
					(mid 409.31189 -439.814496)
					(end 409.334208 -439.760614)
				)
				(arc
					(start 409.334208 -437.21909)
					(mid 409.31189 -437.165208)
					(end 409.258008 -437.14289)
				)
				(arc
					(start 408.318208 -437.14289)
					(mid 408.264326 -437.165208)
					(end 408.242008 -437.21909)
				)
				(arc
					(start 408.242008 -437.946546)
					(mid 408.244007 -437.963887)
					(end 408.249882 -437.980328)
				)
				(arc
					(start 408.483308 -438.456578)
					(mid 408.491091 -438.490106)
					(end 408.483308 -438.523634)
				)
				(arc
					(start 408.249882 -438.999884)
					(mid 408.243987 -439.01632)
					(end 408.242008 -439.033666)
				)
			)
		)
	)
	(zone
		(layers "In3.Cu" "In5.Cu")
		(hatch none 0.5)
		(connect_pads
			(clearance 0)
		)
		(min_thickness 0.25)
		(keepout
			(tracks not_allowed)
			(vias allowed)
			(pads allowed)
			(copperpour not_allowed)
			(footprints allowed)
		)
		(placement
			(enabled no)
			(sheetname "")
		)
		(fill yes
			(thermal_gap 0.5)
			(thermal_bridge_width 0.5)
			(island_removal_mode 0)
		)
		(polygon
			(pts
				(arc
					(start 131.242054 -439.760614)
					(mid 131.264372 -439.814496)
					(end 131.318254 -439.836814)
				)
				(arc
					(start 132.258054 -439.836814)
					(mid 132.311936 -439.814496)
					(end 132.334254 -439.760614)
				)
				(arc
					(start 132.334254 -437.21909)
					(mid 132.311936 -437.165208)
					(end 132.258054 -437.14289)
				)
				(arc
					(start 131.318254 -437.14289)
					(mid 131.264372 -437.165208)
					(end 131.242054 -437.21909)
				)
				(arc
					(start 131.242054 -437.946546)
					(mid 131.244053 -437.963887)
					(end 131.249928 -437.980328)
				)
				(arc
					(start 131.483354 -438.456578)
					(mid 131.491137 -438.490106)
					(end 131.483354 -438.523634)
				)
				(arc
					(start 131.249928 -438.999884)
					(mid 131.244033 -439.01632)
					(end 131.242054 -439.033666)
				)
			)
		)
	)
	(zone
		(layers "In3.Cu" "In5.Cu")
		(hatch none 0.5)
		(connect_pads
			(clearance 0)
		)
		(min_thickness 0.25)
		(keepout
			(tracks not_allowed)
			(vias allowed)
			(pads allowed)
			(copperpour not_allowed)
			(footprints allowed)
		)
		(placement
			(enabled no)
			(sheetname "")
		)
		(fill yes
			(thermal_gap 0.5)
			(thermal_bridge_width 0.5)
			(island_removal_mode 0)
		)
		(polygon
			(pts
				(arc
					(start 324.1421 -436.160418)
					(mid 324.164418 -436.2143)
					(end 324.2183 -436.236618)
				)
				(arc
					(start 325.1581 -436.236618)
					(mid 325.211982 -436.2143)
					(end 325.2343 -436.160418)
				)
				(arc
					(start 325.2343 -433.618894)
					(mid 325.211982 -433.565012)
					(end 325.1581 -433.542694)
				)
				(arc
					(start 324.2183 -433.542694)
					(mid 324.164418 -433.565012)
					(end 324.1421 -433.618894)
				)
				(arc
					(start 324.1421 -434.34635)
					(mid 324.144099 -434.363691)
					(end 324.149974 -434.380132)
				)
				(arc
					(start 324.3834 -434.856382)
					(mid 324.391183 -434.88991)
					(end 324.3834 -434.923438)
				)
				(arc
					(start 324.149974 -435.399688)
					(mid 324.144079 -435.416124)
					(end 324.1421 -435.43347)
				)
			)
		)
	)
	(zone
		(layers "In3.Cu" "In5.Cu")
		(hatch none 0.5)
		(connect_pads
			(clearance 0)
		)
		(min_thickness 0.25)
		(keepout
			(tracks not_allowed)
			(vias allowed)
			(pads allowed)
			(copperpour not_allowed)
			(footprints allowed)
		)
		(placement
			(enabled no)
			(sheetname "")
		)
		(fill yes
			(thermal_gap 0.5)
			(thermal_bridge_width 0.5)
			(island_removal_mode 0)
		)
		(polygon
			(pts
				(arc
					(start 387.24205 -439.760614)
					(mid 387.264368 -439.814496)
					(end 387.31825 -439.836814)
				)
				(arc
					(start 388.25805 -439.836814)
					(mid 388.311932 -439.814496)
					(end 388.33425 -439.760614)
				)
				(arc
					(start 388.33425 -437.21909)
					(mid 388.311932 -437.165208)
					(end 388.25805 -437.14289)
				)
				(arc
					(start 387.31825 -437.14289)
					(mid 387.264368 -437.165208)
					(end 387.24205 -437.21909)
				)
				(arc
					(start 387.24205 -437.946546)
					(mid 387.244049 -437.963887)
					(end 387.249924 -437.980328)
				)
				(arc
					(start 387.48335 -438.456578)
					(mid 387.491133 -438.490106)
					(end 387.48335 -438.523634)
				)
				(arc
					(start 387.249924 -438.999884)
					(mid 387.244029 -439.01632)
					(end 387.24205 -439.033666)
				)
			)
		)
	)
	(zone
		(layers "In3.Cu" "In5.Cu")
		(hatch none 0.5)
		(connect_pads
			(clearance 0)
		)
		(min_thickness 0.25)
		(keepout
			(tracks not_allowed)
			(vias allowed)
			(pads allowed)
			(copperpour not_allowed)
			(footprints allowed)
		)
		(placement
			(enabled no)
			(sheetname "")
		)
		(fill yes
			(thermal_gap 0.5)
			(thermal_bridge_width 0.5)
			(island_removal_mode 0)
		)
		(polygon
			(pts
				(arc
					(start 395.242034 -439.760614)
					(mid 395.264352 -439.814496)
					(end 395.318234 -439.836814)
				)
				(arc
					(start 396.258034 -439.836814)
					(mid 396.311916 -439.814496)
					(end 396.334234 -439.760614)
				)
				(arc
					(start 396.334234 -437.21909)
					(mid 396.311916 -437.165208)
					(end 396.258034 -437.14289)
				)
				(arc
					(start 395.318234 -437.14289)
					(mid 395.264352 -437.165208)
					(end 395.242034 -437.21909)
				)
				(arc
					(start 395.242034 -437.946546)
					(mid 395.244033 -437.963887)
					(end 395.249908 -437.980328)
				)
				(arc
					(start 395.483334 -438.456578)
					(mid 395.491117 -438.490106)
					(end 395.483334 -438.523634)
				)
				(arc
					(start 395.249908 -438.999884)
					(mid 395.244013 -439.01632)
					(end 395.242034 -439.033666)
				)
			)
		)
	)
	(zone
		(layers "In3.Cu" "In5.Cu")
		(hatch none 0.5)
		(connect_pads
			(clearance 0)
		)
		(min_thickness 0.25)
		(keepout
			(tracks not_allowed)
			(vias allowed)
			(pads allowed)
			(copperpour not_allowed)
			(footprints allowed)
		)
		(placement
			(enabled no)
			(sheetname "")
		)
		(fill yes
			(thermal_gap 0.5)
			(thermal_bridge_width 0.5)
			(island_removal_mode 0)
		)
		(polygon
			(pts
				(arc
					(start 412.242 -439.760614)
					(mid 412.264318 -439.814496)
					(end 412.3182 -439.836814)
				)
				(arc
					(start 413.258 -439.836814)
					(mid 413.311882 -439.814496)
					(end 413.3342 -439.760614)
				)
				(arc
					(start 413.3342 -437.21909)
					(mid 413.311882 -437.165208)
					(end 413.258 -437.14289)
				)
				(arc
					(start 412.3182 -437.14289)
					(mid 412.264318 -437.165208)
					(end 412.242 -437.21909)
				)
				(arc
					(start 412.242 -437.946546)
					(mid 412.243999 -437.963887)
					(end 412.249874 -437.980328)
				)
				(arc
					(start 412.4833 -438.456578)
					(mid 412.491083 -438.490106)
					(end 412.4833 -438.523634)
				)
				(arc
					(start 412.249874 -438.999884)
					(mid 412.243979 -439.01632)
					(end 412.242 -439.033666)
				)
			)
		)
	)
	(zone
		(layers "In3.Cu" "In5.Cu")
		(hatch none 0.5)
		(connect_pads
			(clearance 0)
		)
		(min_thickness 0.25)
		(keepout
			(tracks not_allowed)
			(vias allowed)
			(pads allowed)
			(copperpour not_allowed)
			(footprints allowed)
		)
		(placement
			(enabled no)
			(sheetname "")
		)
		(fill yes
			(thermal_gap 0.5)
			(thermal_bridge_width 0.5)
			(island_removal_mode 0)
		)
		(polygon
			(pts
				(arc
					(start 326.142096 -435.16042)
					(mid 326.164414 -435.214302)
					(end 326.218296 -435.23662)
				)
				(arc
					(start 327.158096 -435.23662)
					(mid 327.211978 -435.214302)
					(end 327.234296 -435.16042)
				)
				(arc
					(start 327.234296 -432.618896)
					(mid 327.211978 -432.565014)
					(end 327.158096 -432.542696)
				)
				(arc
					(start 326.218296 -432.542696)
					(mid 326.164414 -432.565014)
					(end 326.142096 -432.618896)
				)
				(arc
					(start 326.142096 -433.346352)
					(mid 326.144095 -433.363693)
					(end 326.14997 -433.380134)
				)
				(arc
					(start 326.383396 -433.856384)
					(mid 326.391179 -433.889912)
					(end 326.383396 -433.92344)
				)
				(arc
					(start 326.14997 -434.39969)
					(mid 326.144075 -434.416126)
					(end 326.142096 -434.433472)
				)
			)
		)
	)
	(zone
		(layers "In3.Cu" "In5.Cu")
		(hatch none 0.5)
		(connect_pads
			(clearance 0)
		)
		(min_thickness 0.25)
		(keepout
			(tracks not_allowed)
			(vias allowed)
			(pads allowed)
			(copperpour not_allowed)
			(footprints allowed)
		)
		(placement
			(enabled no)
			(sheetname "")
		)
		(fill yes
			(thermal_gap 0.5)
			(thermal_bridge_width 0.5)
			(island_removal_mode 0)
		)
		(polygon
			(pts
				(arc
					(start 148.24202 -439.760614)
					(mid 148.264338 -439.814496)
					(end 148.31822 -439.836814)
				)
				(arc
					(start 149.25802 -439.836814)
					(mid 149.311902 -439.814496)
					(end 149.33422 -439.760614)
				)
				(arc
					(start 149.33422 -437.21909)
					(mid 149.311902 -437.165208)
					(end 149.25802 -437.14289)
				)
				(arc
					(start 148.31822 -437.14289)
					(mid 148.264338 -437.165208)
					(end 148.24202 -437.21909)
				)
				(arc
					(start 148.24202 -437.946546)
					(mid 148.244019 -437.963887)
					(end 148.249894 -437.980328)
				)
				(arc
					(start 148.48332 -438.456578)
					(mid 148.491103 -438.490106)
					(end 148.48332 -438.523634)
				)
				(arc
					(start 148.249894 -438.999884)
					(mid 148.243999 -439.01632)
					(end 148.24202 -439.033666)
				)
			)
		)
	)
	(zone
		(layers "In3.Cu" "In5.Cu")
		(hatch none 0.5)
		(connect_pads
			(clearance 0)
		)
		(min_thickness 0.25)
		(keepout
			(tracks not_allowed)
			(vias allowed)
			(pads allowed)
			(copperpour not_allowed)
			(footprints allowed)
		)
		(placement
			(enabled no)
			(sheetname "")
		)
		(fill yes
			(thermal_gap 0.5)
			(thermal_bridge_width 0.5)
			(island_removal_mode 0)
		)
		(polygon
			(pts
				(arc
					(start 62.142116 -435.16042)
					(mid 62.164434 -435.214302)
					(end 62.218316 -435.23662)
				)
				(arc
					(start 63.158116 -435.23662)
					(mid 63.211998 -435.214302)
					(end 63.234316 -435.16042)
				)
				(arc
					(start 63.234316 -432.618896)
					(mid 63.211998 -432.565014)
					(end 63.158116 -432.542696)
				)
				(arc
					(start 62.218316 -432.542696)
					(mid 62.164434 -432.565014)
					(end 62.142116 -432.618896)
				)
				(arc
					(start 62.142116 -433.346352)
					(mid 62.144115 -433.363693)
					(end 62.14999 -433.380134)
				)
				(arc
					(start 62.383416 -433.856384)
					(mid 62.391199 -433.889912)
					(end 62.383416 -433.92344)
				)
				(arc
					(start 62.14999 -434.39969)
					(mid 62.144095 -434.416126)
					(end 62.142116 -434.433472)
				)
			)
		)
	)
	(zone
		(layers "In3.Cu" "In5.Cu")
		(hatch none 0.5)
		(connect_pads
			(clearance 0)
		)
		(min_thickness 0.25)
		(keepout
			(tracks not_allowed)
			(vias allowed)
			(pads allowed)
			(copperpour not_allowed)
			(footprints allowed)
		)
		(placement
			(enabled no)
			(sheetname "")
		)
		(fill yes
			(thermal_gap 0.5)
			(thermal_bridge_width 0.5)
			(island_removal_mode 0)
		)
		(polygon
			(pts
				(arc
					(start 328.142092 -436.160418)
					(mid 328.16441 -436.2143)
					(end 328.218292 -436.236618)
				)
				(arc
					(start 329.158092 -436.236618)
					(mid 329.211974 -436.2143)
					(end 329.234292 -436.160418)
				)
				(arc
					(start 329.234292 -433.618894)
					(mid 329.211974 -433.565012)
					(end 329.158092 -433.542694)
				)
				(arc
					(start 328.218292 -433.542694)
					(mid 328.16441 -433.565012)
					(end 328.142092 -433.618894)
				)
				(arc
					(start 328.142092 -434.34635)
					(mid 328.144091 -434.363691)
					(end 328.149966 -434.380132)
				)
				(arc
					(start 328.383392 -434.856382)
					(mid 328.391175 -434.88991)
					(end 328.383392 -434.923438)
				)
				(arc
					(start 328.149966 -435.399688)
					(mid 328.144071 -435.416124)
					(end 328.142092 -435.43347)
				)
			)
		)
	)
	(zone
		(layers "In3.Cu" "In5.Cu")
		(hatch none 0.5)
		(connect_pads
			(clearance 0)
		)
		(min_thickness 0.25)
		(keepout
			(tracks not_allowed)
			(vias allowed)
			(pads allowed)
			(copperpour not_allowed)
			(footprints allowed)
		)
		(placement
			(enabled no)
			(sheetname "")
		)
		(fill yes
			(thermal_gap 0.5)
			(thermal_bridge_width 0.5)
			(island_removal_mode 0)
		)
		(polygon
			(pts
				(arc
					(start 383.242058 -439.760614)
					(mid 383.264376 -439.814496)
					(end 383.318258 -439.836814)
				)
				(arc
					(start 384.258058 -439.836814)
					(mid 384.31194 -439.814496)
					(end 384.334258 -439.760614)
				)
				(arc
					(start 384.334258 -437.21909)
					(mid 384.31194 -437.165208)
					(end 384.258058 -437.14289)
				)
				(arc
					(start 383.318258 -437.14289)
					(mid 383.264376 -437.165208)
					(end 383.242058 -437.21909)
				)
				(arc
					(start 383.242058 -437.946546)
					(mid 383.244057 -437.963887)
					(end 383.249932 -437.980328)
				)
				(arc
					(start 383.483358 -438.456578)
					(mid 383.491141 -438.490106)
					(end 383.483358 -438.523634)
				)
				(arc
					(start 383.249932 -438.999884)
					(mid 383.244037 -439.01632)
					(end 383.242058 -439.033666)
				)
			)
		)
	)
	(zone
		(layers "In3.Cu" "In5.Cu")
		(hatch none 0.5)
		(connect_pads
			(clearance 0)
		)
		(min_thickness 0.25)
		(keepout
			(tracks not_allowed)
			(vias allowed)
			(pads allowed)
			(copperpour not_allowed)
			(footprints allowed)
		)
		(placement
			(enabled no)
			(sheetname "")
		)
		(fill yes
			(thermal_gap 0.5)
			(thermal_bridge_width 0.5)
			(island_removal_mode 0)
		)
		(polygon
			(pts
				(arc
					(start 320.142108 -436.160418)
					(mid 320.164426 -436.2143)
					(end 320.218308 -436.236618)
				)
				(arc
					(start 321.158108 -436.236618)
					(mid 321.21199 -436.2143)
					(end 321.234308 -436.160418)
				)
				(arc
					(start 321.234308 -433.618894)
					(mid 321.21199 -433.565012)
					(end 321.158108 -433.542694)
				)
				(arc
					(start 320.218308 -433.542694)
					(mid 320.164426 -433.565012)
					(end 320.142108 -433.618894)
				)
				(arc
					(start 320.142108 -434.34635)
					(mid 320.144107 -434.363691)
					(end 320.149982 -434.380132)
				)
				(arc
					(start 320.383408 -434.856382)
					(mid 320.391191 -434.88991)
					(end 320.383408 -434.923438)
				)
				(arc
					(start 320.149982 -435.399688)
					(mid 320.144087 -435.416124)
					(end 320.142108 -435.43347)
				)
			)
		)
	)
	(zone
		(layers "In3.Cu" "In5.Cu")
		(hatch none 0.5)
		(connect_pads
			(clearance 0)
		)
		(min_thickness 0.25)
		(keepout
			(tracks not_allowed)
			(vias allowed)
			(pads allowed)
			(copperpour not_allowed)
			(footprints allowed)
		)
		(placement
			(enabled no)
			(sheetname "")
		)
		(fill yes
			(thermal_gap 0.5)
			(thermal_bridge_width 0.5)
			(island_removal_mode 0)
		)
		(polygon
			(pts
				(arc
					(start 400.242024 -439.760614)
					(mid 400.264342 -439.814496)
					(end 400.318224 -439.836814)
				)
				(arc
					(start 401.258024 -439.836814)
					(mid 401.311906 -439.814496)
					(end 401.334224 -439.760614)
				)
				(arc
					(start 401.334224 -437.21909)
					(mid 401.311906 -437.165208)
					(end 401.258024 -437.14289)
				)
				(arc
					(start 400.318224 -437.14289)
					(mid 400.264342 -437.165208)
					(end 400.242024 -437.21909)
				)
				(arc
					(start 400.242024 -437.946546)
					(mid 400.244023 -437.963887)
					(end 400.249898 -437.980328)
				)
				(arc
					(start 400.483324 -438.456578)
					(mid 400.491107 -438.490106)
					(end 400.483324 -438.523634)
				)
				(arc
					(start 400.249898 -438.999884)
					(mid 400.244003 -439.01632)
					(end 400.242024 -439.033666)
				)
			)
		)
	)
	(zone
		(layers "In3.Cu" "In5.Cu")
		(hatch none 0.5)
		(connect_pads
			(clearance 0)
		)
		(min_thickness 0.25)
		(keepout
			(tracks not_allowed)
			(vias allowed)
			(pads allowed)
			(copperpour not_allowed)
			(footprints allowed)
		)
		(placement
			(enabled no)
			(sheetname "")
		)
		(fill yes
			(thermal_gap 0.5)
			(thermal_bridge_width 0.5)
			(island_removal_mode 0)
		)
		(polygon
			(pts
				(arc
					(start 316.142116 -436.160418)
					(mid 316.164434 -436.2143)
					(end 316.218316 -436.236618)
				)
				(arc
					(start 317.158116 -436.236618)
					(mid 317.211998 -436.2143)
					(end 317.234316 -436.160418)
				)
				(arc
					(start 317.234316 -433.618894)
					(mid 317.211998 -433.565012)
					(end 317.158116 -433.542694)
				)
				(arc
					(start 316.218316 -433.542694)
					(mid 316.164434 -433.565012)
					(end 316.142116 -433.618894)
				)
				(arc
					(start 316.142116 -434.34635)
					(mid 316.144115 -434.363691)
					(end 316.14999 -434.380132)
				)
				(arc
					(start 316.383416 -434.856382)
					(mid 316.391199 -434.88991)
					(end 316.383416 -434.923438)
				)
				(arc
					(start 316.14999 -435.399688)
					(mid 316.144095 -435.416124)
					(end 316.142116 -435.43347)
				)
			)
		)
	)
	(zone
		(layers "In3.Cu" "In5.Cu")
		(hatch none 0.5)
		(connect_pads
			(clearance 0)
		)
		(min_thickness 0.25)
		(keepout
			(tracks not_allowed)
			(vias allowed)
			(pads allowed)
			(copperpour not_allowed)
			(footprints allowed)
		)
		(placement
			(enabled no)
			(sheetname "")
		)
		(fill yes
			(thermal_gap 0.5)
			(thermal_bridge_width 0.5)
			(island_removal_mode 0)
		)
		(polygon
			(pts
				(arc
					(start 144.242028 -439.760614)
					(mid 144.264346 -439.814496)
					(end 144.318228 -439.836814)
				)
				(arc
					(start 145.258028 -439.836814)
					(mid 145.31191 -439.814496)
					(end 145.334228 -439.760614)
				)
				(arc
					(start 145.334228 -437.21909)
					(mid 145.31191 -437.165208)
					(end 145.258028 -437.14289)
				)
				(arc
					(start 144.318228 -437.14289)
					(mid 144.264346 -437.165208)
					(end 144.242028 -437.21909)
				)
				(arc
					(start 144.242028 -437.946546)
					(mid 144.244027 -437.963887)
					(end 144.249902 -437.980328)
				)
				(arc
					(start 144.483328 -438.456578)
					(mid 144.491111 -438.490106)
					(end 144.483328 -438.523634)
				)
				(arc
					(start 144.249902 -438.999884)
					(mid 144.244007 -439.01632)
					(end 144.242028 -439.033666)
				)
			)
		)
	)
	(zone
		(layers "In3.Cu" "In5.Cu")
		(hatch none 0.5)
		(connect_pads
			(clearance 0)
		)
		(min_thickness 0.25)
		(keepout
			(tracks not_allowed)
			(vias allowed)
			(pads allowed)
			(copperpour not_allowed)
			(footprints allowed)
		)
		(placement
			(enabled no)
			(sheetname "")
		)
		(fill yes
			(thermal_gap 0.5)
			(thermal_bridge_width 0.5)
			(island_removal_mode 0)
		)
		(polygon
			(pts
				(arc
					(start 85.14207 -436.160418)
					(mid 85.164388 -436.2143)
					(end 85.21827 -436.236618)
				)
				(arc
					(start 86.15807 -436.236618)
					(mid 86.211952 -436.2143)
					(end 86.23427 -436.160418)
				)
				(arc
					(start 86.23427 -433.618894)
					(mid 86.211952 -433.565012)
					(end 86.15807 -433.542694)
				)
				(arc
					(start 85.21827 -433.542694)
					(mid 85.164388 -433.565012)
					(end 85.14207 -433.618894)
				)
				(arc
					(start 85.14207 -434.34635)
					(mid 85.144069 -434.363691)
					(end 85.149944 -434.380132)
				)
				(arc
					(start 85.38337 -434.856382)
					(mid 85.391153 -434.88991)
					(end 85.38337 -434.923438)
				)
				(arc
					(start 85.149944 -435.399688)
					(mid 85.144049 -435.416124)
					(end 85.14207 -435.43347)
				)
			)
		)
	)
	(zone
		(layers "In3.Cu" "In5.Cu")
		(hatch none 0.5)
		(connect_pads
			(clearance 0)
		)
		(min_thickness 0.25)
		(keepout
			(tracks not_allowed)
			(vias allowed)
			(pads allowed)
			(copperpour not_allowed)
			(footprints allowed)
		)
		(placement
			(enabled no)
			(sheetname "")
		)
		(fill yes
			(thermal_gap 0.5)
			(thermal_bridge_width 0.5)
			(island_removal_mode 0)
		)
		(polygon
			(pts
				(arc
					(start 341.142066 -436.160418)
					(mid 341.164384 -436.2143)
					(end 341.218266 -436.236618)
				)
				(arc
					(start 342.158066 -436.236618)
					(mid 342.211948 -436.2143)
					(end 342.234266 -436.160418)
				)
				(arc
					(start 342.234266 -433.618894)
					(mid 342.211948 -433.565012)
					(end 342.158066 -433.542694)
				)
				(arc
					(start 341.218266 -433.542694)
					(mid 341.164384 -433.565012)
					(end 341.142066 -433.618894)
				)
				(arc
					(start 341.142066 -434.34635)
					(mid 341.144065 -434.363691)
					(end 341.14994 -434.380132)
				)
				(arc
					(start 341.383366 -434.856382)
					(mid 341.391149 -434.88991)
					(end 341.383366 -434.923438)
				)
				(arc
					(start 341.14994 -435.399688)
					(mid 341.144045 -435.416124)
					(end 341.142066 -435.43347)
				)
			)
		)
	)
	(zone
		(layers "In3.Cu" "In5.Cu")
		(hatch none 0.5)
		(connect_pads
			(clearance 0)
		)
		(min_thickness 0.25)
		(keepout
			(tracks not_allowed)
			(vias allowed)
			(pads allowed)
			(copperpour not_allowed)
			(footprints allowed)
		)
		(placement
			(enabled no)
			(sheetname "")
		)
		(fill yes
			(thermal_gap 0.5)
			(thermal_bridge_width 0.5)
			(island_removal_mode 0)
		)
		(polygon
			(pts
				(arc
					(start 331.142086 -435.16042)
					(mid 331.164404 -435.214302)
					(end 331.218286 -435.23662)
				)
				(arc
					(start 332.158086 -435.23662)
					(mid 332.211968 -435.214302)
					(end 332.234286 -435.16042)
				)
				(arc
					(start 332.234286 -432.618896)
					(mid 332.211968 -432.565014)
					(end 332.158086 -432.542696)
				)
				(arc
					(start 331.218286 -432.542696)
					(mid 331.164404 -432.565014)
					(end 331.142086 -432.618896)
				)
				(arc
					(start 331.142086 -433.346352)
					(mid 331.144085 -433.363693)
					(end 331.14996 -433.380134)
				)
				(arc
					(start 331.383386 -433.856384)
					(mid 331.391169 -433.889912)
					(end 331.383386 -433.92344)
				)
				(arc
					(start 331.14996 -434.39969)
					(mid 331.144065 -434.416126)
					(end 331.142086 -434.433472)
				)
			)
		)
	)
	(zone
		(layers "In3.Cu" "In5.Cu")
		(hatch none 0.5)
		(connect_pads
			(clearance 0)
		)
		(min_thickness 0.25)
		(keepout
			(tracks not_allowed)
			(vias allowed)
			(pads allowed)
			(copperpour not_allowed)
			(footprints allowed)
		)
		(placement
			(enabled no)
			(sheetname "")
		)
		(fill yes
			(thermal_gap 0.5)
			(thermal_bridge_width 0.5)
			(island_removal_mode 0)
		)
		(polygon
			(pts
				(arc
					(start 129.242058 -438.760616)
					(mid 129.264376 -438.814498)
					(end 129.318258 -438.836816)
				)
				(arc
					(start 130.258058 -438.836816)
					(mid 130.31194 -438.814498)
					(end 130.334258 -438.760616)
				)
				(arc
					(start 130.334258 -436.219092)
					(mid 130.31194 -436.16521)
					(end 130.258058 -436.142892)
				)
				(arc
					(start 129.318258 -436.142892)
					(mid 129.264376 -436.16521)
					(end 129.242058 -436.219092)
				)
				(arc
					(start 129.242058 -436.946548)
					(mid 129.244057 -436.963889)
					(end 129.249932 -436.98033)
				)
				(arc
					(start 129.483358 -437.45658)
					(mid 129.491141 -437.490108)
					(end 129.483358 -437.523636)
				)
				(arc
					(start 129.249932 -437.999886)
					(mid 129.244037 -438.016322)
					(end 129.242058 -438.033668)
				)
			)
		)
	)
	(zone
		(layers "In3.Cu" "In5.Cu")
		(hatch none 0.5)
		(connect_pads
			(clearance 0)
		)
		(min_thickness 0.25)
		(keepout
			(tracks not_allowed)
			(vias allowed)
			(pads allowed)
			(copperpour not_allowed)
			(footprints allowed)
		)
		(placement
			(enabled no)
			(sheetname "")
		)
		(fill yes
			(thermal_gap 0.5)
			(thermal_bridge_width 0.5)
			(island_removal_mode 0)
		)
		(polygon
			(pts
				(arc
					(start 381.242062 -438.760616)
					(mid 381.26438 -438.814498)
					(end 381.318262 -438.836816)
				)
				(arc
					(start 382.258062 -438.836816)
					(mid 382.311944 -438.814498)
					(end 382.334262 -438.760616)
				)
				(arc
					(start 382.334262 -436.219092)
					(mid 382.311944 -436.16521)
					(end 382.258062 -436.142892)
				)
				(arc
					(start 381.318262 -436.142892)
					(mid 381.26438 -436.16521)
					(end 381.242062 -436.219092)
				)
				(arc
					(start 381.242062 -436.946548)
					(mid 381.244061 -436.963889)
					(end 381.249936 -436.98033)
				)
				(arc
					(start 381.483362 -437.45658)
					(mid 381.491145 -437.490108)
					(end 381.483362 -437.523636)
				)
				(arc
					(start 381.249936 -437.999886)
					(mid 381.244041 -438.016322)
					(end 381.242062 -438.033668)
				)
			)
		)
	)
	(zone
		(layers "In3.Cu" "In5.Cu")
		(hatch none 0.5)
		(connect_pads
			(clearance 0)
		)
		(min_thickness 0.25)
		(keepout
			(tracks not_allowed)
			(vias allowed)
			(pads allowed)
			(copperpour not_allowed)
			(footprints allowed)
		)
		(placement
			(enabled no)
			(sheetname "")
		)
		(fill yes
			(thermal_gap 0.5)
			(thermal_bridge_width 0.5)
			(island_removal_mode 0)
		)
		(polygon
			(pts
				(arc
					(start 64.142112 -436.160418)
					(mid 64.16443 -436.2143)
					(end 64.218312 -436.236618)
				)
				(arc
					(start 65.158112 -436.236618)
					(mid 65.211994 -436.2143)
					(end 65.234312 -436.160418)
				)
				(arc
					(start 65.234312 -433.618894)
					(mid 65.211994 -433.565012)
					(end 65.158112 -433.542694)
				)
				(arc
					(start 64.218312 -433.542694)
					(mid 64.16443 -433.565012)
					(end 64.142112 -433.618894)
				)
				(arc
					(start 64.142112 -434.34635)
					(mid 64.144111 -434.363691)
					(end 64.149986 -434.380132)
				)
				(arc
					(start 64.383412 -434.856382)
					(mid 64.391195 -434.88991)
					(end 64.383412 -434.923438)
				)
				(arc
					(start 64.149986 -435.399688)
					(mid 64.144091 -435.416124)
					(end 64.142112 -435.43347)
				)
			)
		)
	)
	(zone
		(layers "In3.Cu" "In5.Cu")
		(hatch none 0.5)
		(connect_pads
			(clearance 0)
		)
		(min_thickness 0.25)
		(keepout
			(tracks not_allowed)
			(vias allowed)
			(pads allowed)
			(copperpour not_allowed)
			(footprints allowed)
		)
		(placement
			(enabled no)
			(sheetname "")
		)
		(fill yes
			(thermal_gap 0.5)
			(thermal_bridge_width 0.5)
			(island_removal_mode 0)
		)
		(polygon
			(pts
				(arc
					(start 150.242016 -438.760616)
					(mid 150.264334 -438.814498)
					(end 150.318216 -438.836816)
				)
				(arc
					(start 151.258016 -438.836816)
					(mid 151.311898 -438.814498)
					(end 151.334216 -438.760616)
				)
				(arc
					(start 151.334216 -436.219092)
					(mid 151.311898 -436.16521)
					(end 151.258016 -436.142892)
				)
				(arc
					(start 150.318216 -436.142892)
					(mid 150.264334 -436.16521)
					(end 150.242016 -436.219092)
				)
				(arc
					(start 150.242016 -436.946548)
					(mid 150.244015 -436.963889)
					(end 150.24989 -436.98033)
				)
				(arc
					(start 150.483316 -437.45658)
					(mid 150.491099 -437.490108)
					(end 150.483316 -437.523636)
				)
				(arc
					(start 150.24989 -437.999886)
					(mid 150.243995 -438.016322)
					(end 150.242016 -438.033668)
				)
			)
		)
	)
	(zone
		(layers "In3.Cu" "In5.Cu")
		(hatch none 0.5)
		(connect_pads
			(clearance 0)
		)
		(min_thickness 0.25)
		(keepout
			(tracks not_allowed)
			(vias allowed)
			(pads allowed)
			(copperpour not_allowed)
			(footprints allowed)
		)
		(placement
			(enabled no)
			(sheetname "")
		)
		(fill yes
			(thermal_gap 0.5)
			(thermal_bridge_width 0.5)
			(island_removal_mode 0)
		)
		(polygon
			(pts
				(arc
					(start 402.24202 -438.760616)
					(mid 402.264338 -438.814498)
					(end 402.31822 -438.836816)
				)
				(arc
					(start 403.25802 -438.836816)
					(mid 403.311902 -438.814498)
					(end 403.33422 -438.760616)
				)
				(arc
					(start 403.33422 -436.219092)
					(mid 403.311902 -436.16521)
					(end 403.25802 -436.142892)
				)
				(arc
					(start 402.31822 -436.142892)
					(mid 402.264338 -436.16521)
					(end 402.24202 -436.219092)
				)
				(arc
					(start 402.24202 -436.946548)
					(mid 402.244019 -436.963889)
					(end 402.249894 -436.98033)
				)
				(arc
					(start 402.48332 -437.45658)
					(mid 402.491103 -437.490108)
					(end 402.48332 -437.523636)
				)
				(arc
					(start 402.249894 -437.999886)
					(mid 402.243999 -438.016322)
					(end 402.24202 -438.033668)
				)
			)
		)
	)
	(zone
		(layers "In3.Cu" "In5.Cu")
		(hatch none 0.5)
		(connect_pads
			(clearance 0)
		)
		(min_thickness 0.25)
		(keepout
			(tracks not_allowed)
			(vias allowed)
			(pads allowed)
			(copperpour not_allowed)
			(footprints allowed)
		)
		(placement
			(enabled no)
			(sheetname "")
		)
		(fill yes
			(thermal_gap 0.5)
			(thermal_bridge_width 0.5)
			(island_removal_mode 0)
		)
		(polygon
			(pts
				(arc
					(start 83.142074 -435.16042)
					(mid 83.164392 -435.214302)
					(end 83.218274 -435.23662)
				)
				(arc
					(start 84.158074 -435.23662)
					(mid 84.211956 -435.214302)
					(end 84.234274 -435.16042)
				)
				(arc
					(start 84.234274 -432.618896)
					(mid 84.211956 -432.565014)
					(end 84.158074 -432.542696)
				)
				(arc
					(start 83.218274 -432.542696)
					(mid 83.164392 -432.565014)
					(end 83.142074 -432.618896)
				)
				(arc
					(start 83.142074 -433.346352)
					(mid 83.144073 -433.363693)
					(end 83.149948 -433.380134)
				)
				(arc
					(start 83.383374 -433.856384)
					(mid 83.391157 -433.889912)
					(end 83.383374 -433.92344)
				)
				(arc
					(start 83.149948 -434.39969)
					(mid 83.144053 -434.416126)
					(end 83.142074 -434.433472)
				)
			)
		)
	)
	(zone
		(layers "In3.Cu" "In5.Cu")
		(hatch none 0.5)
		(connect_pads
			(clearance 0)
		)
		(min_thickness 0.25)
		(keepout
			(tracks not_allowed)
			(vias allowed)
			(pads allowed)
			(copperpour not_allowed)
			(footprints allowed)
		)
		(placement
			(enabled no)
			(sheetname "")
		)
		(fill yes
			(thermal_gap 0.5)
			(thermal_bridge_width 0.5)
			(island_removal_mode 0)
		)
		(polygon
			(pts
				(arc
					(start 385.242054 -438.760616)
					(mid 385.264372 -438.814498)
					(end 385.318254 -438.836816)
				)
				(arc
					(start 386.258054 -438.836816)
					(mid 386.311936 -438.814498)
					(end 386.334254 -438.760616)
				)
				(arc
					(start 386.334254 -436.219092)
					(mid 386.311936 -436.16521)
					(end 386.258054 -436.142892)
				)
				(arc
					(start 385.318254 -436.142892)
					(mid 385.264372 -436.16521)
					(end 385.242054 -436.219092)
				)
				(arc
					(start 385.242054 -436.946548)
					(mid 385.244053 -436.963889)
					(end 385.249928 -436.98033)
				)
				(arc
					(start 385.483354 -437.45658)
					(mid 385.491137 -437.490108)
					(end 385.483354 -437.523636)
				)
				(arc
					(start 385.249928 -437.999886)
					(mid 385.244033 -438.016322)
					(end 385.242054 -438.033668)
				)
			)
		)
	)
	(zone
		(layers "In3.Cu" "In5.Cu")
		(hatch none 0.5)
		(connect_pads
			(clearance 0)
		)
		(min_thickness 0.25)
		(keepout
			(tracks not_allowed)
			(vias allowed)
			(pads allowed)
			(copperpour not_allowed)
			(footprints allowed)
		)
		(placement
			(enabled no)
			(sheetname "")
		)
		(fill yes
			(thermal_gap 0.5)
			(thermal_bridge_width 0.5)
			(island_removal_mode 0)
		)
		(polygon
			(pts
				(arc
					(start 339.14207 -435.16042)
					(mid 339.164388 -435.214302)
					(end 339.21827 -435.23662)
				)
				(arc
					(start 340.15807 -435.23662)
					(mid 340.211952 -435.214302)
					(end 340.23427 -435.16042)
				)
				(arc
					(start 340.23427 -432.618896)
					(mid 340.211952 -432.565014)
					(end 340.15807 -432.542696)
				)
				(arc
					(start 339.21827 -432.542696)
					(mid 339.164388 -432.565014)
					(end 339.14207 -432.618896)
				)
				(arc
					(start 339.14207 -433.346352)
					(mid 339.144069 -433.363693)
					(end 339.149944 -433.380134)
				)
				(arc
					(start 339.38337 -433.856384)
					(mid 339.391153 -433.889912)
					(end 339.38337 -433.92344)
				)
				(arc
					(start 339.149944 -434.39969)
					(mid 339.144049 -434.416126)
					(end 339.14207 -434.433472)
				)
			)
		)
	)
	(zone
		(layers "In3.Cu" "In5.Cu")
		(hatch none 0.5)
		(connect_pads
			(clearance 0)
		)
		(min_thickness 0.25)
		(keepout
			(tracks not_allowed)
			(vias allowed)
			(pads allowed)
			(copperpour not_allowed)
			(footprints allowed)
		)
		(placement
			(enabled no)
			(sheetname "")
		)
		(fill yes
			(thermal_gap 0.5)
			(thermal_bridge_width 0.5)
			(island_removal_mode 0)
		)
		(polygon
			(pts
				(arc
					(start 125.242066 -438.760616)
					(mid 125.264384 -438.814498)
					(end 125.318266 -438.836816)
				)
				(arc
					(start 126.258066 -438.836816)
					(mid 126.311948 -438.814498)
					(end 126.334266 -438.760616)
				)
				(arc
					(start 126.334266 -436.219092)
					(mid 126.311948 -436.16521)
					(end 126.258066 -436.142892)
				)
				(arc
					(start 125.318266 -436.142892)
					(mid 125.264384 -436.16521)
					(end 125.242066 -436.219092)
				)
				(arc
					(start 125.242066 -436.946548)
					(mid 125.244065 -436.963889)
					(end 125.24994 -436.98033)
				)
				(arc
					(start 125.483366 -437.45658)
					(mid 125.491149 -437.490108)
					(end 125.483366 -437.523636)
				)
				(arc
					(start 125.24994 -437.999886)
					(mid 125.244045 -438.016322)
					(end 125.242066 -438.033668)
				)
			)
		)
	)
	(zone
		(layers "In3.Cu" "In5.Cu")
		(hatch none 0.5)
		(connect_pads
			(clearance 0)
		)
		(min_thickness 0.25)
		(keepout
			(tracks not_allowed)
			(vias allowed)
			(pads allowed)
			(copperpour not_allowed)
			(footprints allowed)
		)
		(placement
			(enabled no)
			(sheetname "")
		)
		(fill yes
			(thermal_gap 0.5)
			(thermal_bridge_width 0.5)
			(island_removal_mode 0)
		)
		(polygon
			(pts
				(arc
					(start 154.242008 -438.760616)
					(mid 154.264326 -438.814498)
					(end 154.318208 -438.836816)
				)
				(arc
					(start 155.258008 -438.836816)
					(mid 155.31189 -438.814498)
					(end 155.334208 -438.760616)
				)
				(arc
					(start 155.334208 -436.219092)
					(mid 155.31189 -436.16521)
					(end 155.258008 -436.142892)
				)
				(arc
					(start 154.318208 -436.142892)
					(mid 154.264326 -436.16521)
					(end 154.242008 -436.219092)
				)
				(arc
					(start 154.242008 -436.946548)
					(mid 154.244007 -436.963889)
					(end 154.249882 -436.98033)
				)
				(arc
					(start 154.483308 -437.45658)
					(mid 154.491091 -437.490108)
					(end 154.483308 -437.523636)
				)
				(arc
					(start 154.249882 -437.999886)
					(mid 154.243987 -438.016322)
					(end 154.242008 -438.033668)
				)
			)
		)
	)
	(zone
		(layers "In3.Cu" "In5.Cu")
		(hatch none 0.5)
		(connect_pads
			(clearance 0)
		)
		(min_thickness 0.25)
		(keepout
			(tracks not_allowed)
			(vias allowed)
			(pads allowed)
			(copperpour not_allowed)
			(footprints allowed)
		)
		(placement
			(enabled no)
			(sheetname "")
		)
		(fill yes
			(thermal_gap 0.5)
			(thermal_bridge_width 0.5)
			(island_removal_mode 0)
		)
		(polygon
			(pts
				(arc
					(start 333.142082 -436.160418)
					(mid 333.1644 -436.2143)
					(end 333.218282 -436.236618)
				)
				(arc
					(start 334.158082 -436.236618)
					(mid 334.211964 -436.2143)
					(end 334.234282 -436.160418)
				)
				(arc
					(start 334.234282 -433.618894)
					(mid 334.211964 -433.565012)
					(end 334.158082 -433.542694)
				)
				(arc
					(start 333.218282 -433.542694)
					(mid 333.1644 -433.565012)
					(end 333.142082 -433.618894)
				)
				(arc
					(start 333.142082 -434.34635)
					(mid 333.144081 -434.363691)
					(end 333.149956 -434.380132)
				)
				(arc
					(start 333.383382 -434.856382)
					(mid 333.391165 -434.88991)
					(end 333.383382 -434.923438)
				)
				(arc
					(start 333.149956 -435.399688)
					(mid 333.144061 -435.416124)
					(end 333.142082 -435.43347)
				)
			)
		)
	)
	(zone
		(layers "In3.Cu" "In5.Cu")
		(hatch none 0.5)
		(connect_pads
			(clearance 0)
		)
		(min_thickness 0.25)
		(keepout
			(tracks not_allowed)
			(vias allowed)
			(pads allowed)
			(copperpour not_allowed)
			(footprints allowed)
		)
		(placement
			(enabled no)
			(sheetname "")
		)
		(fill yes
			(thermal_gap 0.5)
			(thermal_bridge_width 0.5)
			(island_removal_mode 0)
		)
		(polygon
			(pts
				(arc
					(start 391.242042 -439.760614)
					(mid 391.26436 -439.814496)
					(end 391.318242 -439.836814)
				)
				(arc
					(start 392.258042 -439.836814)
					(mid 392.311924 -439.814496)
					(end 392.334242 -439.760614)
				)
				(arc
					(start 392.334242 -437.21909)
					(mid 392.311924 -437.165208)
					(end 392.258042 -437.14289)
				)
				(arc
					(start 391.318242 -437.14289)
					(mid 391.26436 -437.165208)
					(end 391.242042 -437.21909)
				)
				(arc
					(start 391.242042 -437.946546)
					(mid 391.244041 -437.963887)
					(end 391.249916 -437.980328)
				)
				(arc
					(start 391.483342 -438.456578)
					(mid 391.491125 -438.490106)
					(end 391.483342 -438.523634)
				)
				(arc
					(start 391.249916 -438.999884)
					(mid 391.244021 -439.01632)
					(end 391.242042 -439.033666)
				)
			)
		)
	)
	(zone
		(layers "In3.Cu" "In5.Cu")
		(hatch none 0.5)
		(connect_pads
			(clearance 0)
		)
		(min_thickness 0.25)
		(keepout
			(tracks not_allowed)
			(vias allowed)
			(pads allowed)
			(copperpour not_allowed)
			(footprints allowed)
		)
		(placement
			(enabled no)
			(sheetname "")
		)
		(fill yes
			(thermal_gap 0.5)
			(thermal_bridge_width 0.5)
			(island_removal_mode 0)
		)
		(polygon
			(pts
				(arc
					(start 89.142062 -436.160418)
					(mid 89.16438 -436.2143)
					(end 89.218262 -436.236618)
				)
				(arc
					(start 90.158062 -436.236618)
					(mid 90.211944 -436.2143)
					(end 90.234262 -436.160418)
				)
				(arc
					(start 90.234262 -433.618894)
					(mid 90.211944 -433.565012)
					(end 90.158062 -433.542694)
				)
				(arc
					(start 89.218262 -433.542694)
					(mid 89.16438 -433.565012)
					(end 89.142062 -433.618894)
				)
				(arc
					(start 89.142062 -434.34635)
					(mid 89.144061 -434.363691)
					(end 89.149936 -434.380132)
				)
				(arc
					(start 89.383362 -434.856382)
					(mid 89.391145 -434.88991)
					(end 89.383362 -434.923438)
				)
				(arc
					(start 89.149936 -435.399688)
					(mid 89.144041 -435.416124)
					(end 89.142062 -435.43347)
				)
			)
		)
	)
	(zone
		(layers "In3.Cu" "In5.Cu")
		(hatch none 0.5)
		(connect_pads
			(clearance 0)
		)
		(min_thickness 0.25)
		(keepout
			(tracks not_allowed)
			(vias allowed)
			(pads allowed)
			(copperpour not_allowed)
			(footprints allowed)
		)
		(placement
			(enabled no)
			(sheetname "")
		)
		(fill yes
			(thermal_gap 0.5)
			(thermal_bridge_width 0.5)
			(island_removal_mode 0)
		)
		(polygon
			(pts
				(arc
					(start 406.242012 -438.760616)
					(mid 406.26433 -438.814498)
					(end 406.318212 -438.836816)
				)
				(arc
					(start 407.258012 -438.836816)
					(mid 407.311894 -438.814498)
					(end 407.334212 -438.760616)
				)
				(arc
					(start 407.334212 -436.219092)
					(mid 407.311894 -436.16521)
					(end 407.258012 -436.142892)
				)
				(arc
					(start 406.318212 -436.142892)
					(mid 406.26433 -436.16521)
					(end 406.242012 -436.219092)
				)
				(arc
					(start 406.242012 -436.946548)
					(mid 406.244011 -436.963889)
					(end 406.249886 -436.98033)
				)
				(arc
					(start 406.483312 -437.45658)
					(mid 406.491095 -437.490108)
					(end 406.483312 -437.523636)
				)
				(arc
					(start 406.249886 -437.999886)
					(mid 406.243991 -438.016322)
					(end 406.242012 -438.033668)
				)
			)
		)
	)
	(zone
		(layers "In3.Cu" "In5.Cu")
		(hatch none 0.5)
		(connect_pads
			(clearance 0)
		)
		(min_thickness 0.25)
		(keepout
			(tracks not_allowed)
			(vias allowed)
			(pads allowed)
			(copperpour not_allowed)
			(footprints allowed)
		)
		(placement
			(enabled no)
			(sheetname "")
		)
		(fill yes
			(thermal_gap 0.5)
			(thermal_bridge_width 0.5)
			(island_removal_mode 0)
		)
		(polygon
			(pts
				(arc
					(start 142.242032 -438.760616)
					(mid 142.26435 -438.814498)
					(end 142.318232 -438.836816)
				)
				(arc
					(start 143.258032 -438.836816)
					(mid 143.311914 -438.814498)
					(end 143.334232 -438.760616)
				)
				(arc
					(start 143.334232 -436.219092)
					(mid 143.311914 -436.16521)
					(end 143.258032 -436.142892)
				)
				(arc
					(start 142.318232 -436.142892)
					(mid 142.26435 -436.16521)
					(end 142.242032 -436.219092)
				)
				(arc
					(start 142.242032 -436.946548)
					(mid 142.244031 -436.963889)
					(end 142.249906 -436.98033)
				)
				(arc
					(start 142.483332 -437.45658)
					(mid 142.491115 -437.490108)
					(end 142.483332 -437.523636)
				)
				(arc
					(start 142.249906 -437.999886)
					(mid 142.244011 -438.016322)
					(end 142.242032 -438.033668)
				)
			)
		)
	)
	(zone
		(layers "In3.Cu" "In5.Cu")
		(hatch none 0.5)
		(connect_pads
			(clearance 0)
		)
		(min_thickness 0.25)
		(keepout
			(tracks not_allowed)
			(vias allowed)
			(pads allowed)
			(copperpour not_allowed)
			(footprints allowed)
		)
		(placement
			(enabled no)
			(sheetname "")
		)
		(fill yes
			(thermal_gap 0.5)
			(thermal_bridge_width 0.5)
			(island_removal_mode 0)
		)
		(polygon
			(pts
				(arc
					(start 156.242004 -439.760614)
					(mid 156.264322 -439.814496)
					(end 156.318204 -439.836814)
				)
				(arc
					(start 157.258004 -439.836814)
					(mid 157.311886 -439.814496)
					(end 157.334204 -439.760614)
				)
				(arc
					(start 157.334204 -437.21909)
					(mid 157.311886 -437.165208)
					(end 157.258004 -437.14289)
				)
				(arc
					(start 156.318204 -437.14289)
					(mid 156.264322 -437.165208)
					(end 156.242004 -437.21909)
				)
				(arc
					(start 156.242004 -437.946546)
					(mid 156.244003 -437.963887)
					(end 156.249878 -437.980328)
				)
				(arc
					(start 156.483304 -438.456578)
					(mid 156.491087 -438.490106)
					(end 156.483304 -438.523634)
				)
				(arc
					(start 156.249878 -438.999884)
					(mid 156.243983 -439.01632)
					(end 156.242004 -439.033666)
				)
			)
		)
	)
	(zone
		(layers "In3.Cu" "In5.Cu")
		(hatch none 0.5)
		(connect_pads
			(clearance 0)
		)
		(min_thickness 0.25)
		(keepout
			(tracks not_allowed)
			(vias allowed)
			(pads allowed)
			(copperpour not_allowed)
			(footprints allowed)
		)
		(placement
			(enabled no)
			(sheetname "")
		)
		(fill yes
			(thermal_gap 0.5)
			(thermal_bridge_width 0.5)
			(island_removal_mode 0)
		)
		(polygon
			(pts
				(arc
					(start 79.142082 -435.16042)
					(mid 79.1644 -435.214302)
					(end 79.218282 -435.23662)
				)
				(arc
					(start 80.158082 -435.23662)
					(mid 80.211964 -435.214302)
					(end 80.234282 -435.16042)
				)
				(arc
					(start 80.234282 -432.618896)
					(mid 80.211964 -432.565014)
					(end 80.158082 -432.542696)
				)
				(arc
					(start 79.218282 -432.542696)
					(mid 79.1644 -432.565014)
					(end 79.142082 -432.618896)
				)
				(arc
					(start 79.142082 -433.346352)
					(mid 79.144081 -433.363693)
					(end 79.149956 -433.380134)
				)
				(arc
					(start 79.383382 -433.856384)
					(mid 79.391165 -433.889912)
					(end 79.383382 -433.92344)
				)
				(arc
					(start 79.149956 -434.39969)
					(mid 79.144061 -434.416126)
					(end 79.142082 -434.433472)
				)
			)
		)
	)
	(zone
		(layers "In3.Cu" "In5.Cu")
		(hatch none 0.5)
		(connect_pads
			(clearance 0)
		)
		(min_thickness 0.25)
		(keepout
			(tracks not_allowed)
			(vias allowed)
			(pads allowed)
			(copperpour not_allowed)
			(footprints allowed)
		)
		(placement
			(enabled no)
			(sheetname "")
		)
		(fill yes
			(thermal_gap 0.5)
			(thermal_bridge_width 0.5)
			(island_removal_mode 0)
		)
		(polygon
			(pts
				(arc
					(start 135.242046 -439.760614)
					(mid 135.264364 -439.814496)
					(end 135.318246 -439.836814)
				)
				(arc
					(start 136.258046 -439.836814)
					(mid 136.311928 -439.814496)
					(end 136.334246 -439.760614)
				)
				(arc
					(start 136.334246 -437.21909)
					(mid 136.311928 -437.165208)
					(end 136.258046 -437.14289)
				)
				(arc
					(start 135.318246 -437.14289)
					(mid 135.264364 -437.165208)
					(end 135.242046 -437.21909)
				)
				(arc
					(start 135.242046 -437.946546)
					(mid 135.244045 -437.963887)
					(end 135.24992 -437.980328)
				)
				(arc
					(start 135.483346 -438.456578)
					(mid 135.491129 -438.490106)
					(end 135.483346 -438.523634)
				)
				(arc
					(start 135.24992 -438.999884)
					(mid 135.244025 -439.01632)
					(end 135.242046 -439.033666)
				)
			)
		)
	)
	(zone
		(layers "In3.Cu" "In5.Cu")
		(hatch none 0.5)
		(connect_pads
			(clearance 0)
		)
		(min_thickness 0.25)
		(keepout
			(tracks not_allowed)
			(vias allowed)
			(pads allowed)
			(copperpour not_allowed)
			(footprints allowed)
		)
		(placement
			(enabled no)
			(sheetname "")
		)
		(fill yes
			(thermal_gap 0.5)
			(thermal_bridge_width 0.5)
			(island_removal_mode 0)
		)
		(polygon
			(pts
				(arc
					(start 389.242046 -438.760616)
					(mid 389.264364 -438.814498)
					(end 389.318246 -438.836816)
				)
				(arc
					(start 390.258046 -438.836816)
					(mid 390.311928 -438.814498)
					(end 390.334246 -438.760616)
				)
				(arc
					(start 390.334246 -436.219092)
					(mid 390.311928 -436.16521)
					(end 390.258046 -436.142892)
				)
				(arc
					(start 389.318246 -436.142892)
					(mid 389.264364 -436.16521)
					(end 389.242046 -436.219092)
				)
				(arc
					(start 389.242046 -436.946548)
					(mid 389.244045 -436.963889)
					(end 389.24992 -436.98033)
				)
				(arc
					(start 389.483346 -437.45658)
					(mid 389.491129 -437.490108)
					(end 389.483346 -437.523636)
				)
				(arc
					(start 389.24992 -437.999886)
					(mid 389.244025 -438.016322)
					(end 389.242046 -438.033668)
				)
			)
		)
	)
	(zone
		(layers "In3.Cu" "In5.Cu")
		(hatch none 0.5)
		(connect_pads
			(clearance 0)
		)
		(min_thickness 0.25)
		(keepout
			(tracks not_allowed)
			(vias allowed)
			(pads allowed)
			(copperpour not_allowed)
			(footprints allowed)
		)
		(placement
			(enabled no)
			(sheetname "")
		)
		(fill yes
			(thermal_gap 0.5)
			(thermal_bridge_width 0.5)
			(island_removal_mode 0)
		)
		(polygon
			(pts
				(arc
					(start 60.14212 -436.160418)
					(mid 60.164438 -436.2143)
					(end 60.21832 -436.236618)
				)
				(arc
					(start 61.15812 -436.236618)
					(mid 61.212002 -436.2143)
					(end 61.23432 -436.160418)
				)
				(arc
					(start 61.23432 -433.618894)
					(mid 61.212002 -433.565012)
					(end 61.15812 -433.542694)
				)
				(arc
					(start 60.21832 -433.542694)
					(mid 60.164438 -433.565012)
					(end 60.14212 -433.618894)
				)
				(arc
					(start 60.14212 -434.34635)
					(mid 60.144119 -434.363691)
					(end 60.149994 -434.380132)
				)
				(arc
					(start 60.38342 -434.856382)
					(mid 60.391203 -434.88991)
					(end 60.38342 -434.923438)
				)
				(arc
					(start 60.149994 -435.399688)
					(mid 60.144099 -435.416124)
					(end 60.14212 -435.43347)
				)
			)
		)
	)
	(zone
		(layers "In3.Cu" "In5.Cu")
		(hatch none 0.5)
		(connect_pads
			(clearance 0)
		)
		(min_thickness 0.25)
		(keepout
			(tracks not_allowed)
			(vias allowed)
			(pads allowed)
			(copperpour not_allowed)
			(footprints allowed)
		)
		(placement
			(enabled no)
			(sheetname "")
		)
		(fill yes
			(thermal_gap 0.5)
			(thermal_bridge_width 0.5)
			(island_removal_mode 0)
		)
		(polygon
			(pts
				(arc
					(start 75.14209 -435.16042)
					(mid 75.164408 -435.214302)
					(end 75.21829 -435.23662)
				)
				(arc
					(start 76.15809 -435.23662)
					(mid 76.211972 -435.214302)
					(end 76.23429 -435.16042)
				)
				(arc
					(start 76.23429 -432.618896)
					(mid 76.211972 -432.565014)
					(end 76.15809 -432.542696)
				)
				(arc
					(start 75.21829 -432.542696)
					(mid 75.164408 -432.565014)
					(end 75.14209 -432.618896)
				)
				(arc
					(start 75.14209 -433.346352)
					(mid 75.144089 -433.363693)
					(end 75.149964 -433.380134)
				)
				(arc
					(start 75.38339 -433.856384)
					(mid 75.391173 -433.889912)
					(end 75.38339 -433.92344)
				)
				(arc
					(start 75.149964 -434.39969)
					(mid 75.144069 -434.416126)
					(end 75.14209 -434.433472)
				)
			)
		)
	)
	(zone
		(layers "In3.Cu" "In5.Cu")
		(hatch none 0.5)
		(connect_pads
			(clearance 0)
		)
		(min_thickness 0.25)
		(keepout
			(tracks not_allowed)
			(vias allowed)
			(pads allowed)
			(copperpour not_allowed)
			(footprints allowed)
		)
		(placement
			(enabled no)
			(sheetname "")
		)
		(fill yes
			(thermal_gap 0.5)
			(thermal_bridge_width 0.5)
			(island_removal_mode 0)
		)
		(polygon
			(pts
				(arc
					(start 337.142074 -436.160418)
					(mid 337.164392 -436.2143)
					(end 337.218274 -436.236618)
				)
				(arc
					(start 338.158074 -436.236618)
					(mid 338.211956 -436.2143)
					(end 338.234274 -436.160418)
				)
				(arc
					(start 338.234274 -433.618894)
					(mid 338.211956 -433.565012)
					(end 338.158074 -433.542694)
				)
				(arc
					(start 337.218274 -433.542694)
					(mid 337.164392 -433.565012)
					(end 337.142074 -433.618894)
				)
				(arc
					(start 337.142074 -434.34635)
					(mid 337.144073 -434.363691)
					(end 337.149948 -434.380132)
				)
				(arc
					(start 337.383374 -434.856382)
					(mid 337.391157 -434.88991)
					(end 337.383374 -434.923438)
				)
				(arc
					(start 337.149948 -435.399688)
					(mid 337.144053 -435.416124)
					(end 337.142074 -435.43347)
				)
			)
		)
	)
	(zone
		(layers "In3.Cu" "In5.Cu")
		(hatch none 0.5)
		(connect_pads
			(clearance 0)
		)
		(min_thickness 0.25)
		(keepout
			(tracks not_allowed)
			(vias allowed)
			(pads allowed)
			(copperpour not_allowed)
			(footprints allowed)
		)
		(placement
			(enabled no)
			(sheetname "")
		)
		(fill yes
			(thermal_gap 0.5)
			(thermal_bridge_width 0.5)
			(island_removal_mode 0)
		)
		(polygon
			(pts
				(arc
					(start 133.24205 -438.760616)
					(mid 133.264368 -438.814498)
					(end 133.31825 -438.836816)
				)
				(arc
					(start 134.25805 -438.836816)
					(mid 134.311932 -438.814498)
					(end 134.33425 -438.760616)
				)
				(arc
					(start 134.33425 -436.219092)
					(mid 134.311932 -436.16521)
					(end 134.25805 -436.142892)
				)
				(arc
					(start 133.31825 -436.142892)
					(mid 133.264368 -436.16521)
					(end 133.24205 -436.219092)
				)
				(arc
					(start 133.24205 -436.946548)
					(mid 133.244049 -436.963889)
					(end 133.249924 -436.98033)
				)
				(arc
					(start 133.48335 -437.45658)
					(mid 133.491133 -437.490108)
					(end 133.48335 -437.523636)
				)
				(arc
					(start 133.249924 -437.999886)
					(mid 133.244029 -438.016322)
					(end 133.24205 -438.033668)
				)
			)
		)
	)
	(zone
		(layers "In3.Cu" "In5.Cu")
		(hatch none 0.5)
		(connect_pads
			(clearance 0)
		)
		(min_thickness 0.25)
		(keepout
			(tracks not_allowed)
			(vias allowed)
			(pads allowed)
			(copperpour not_allowed)
			(footprints allowed)
		)
		(placement
			(enabled no)
			(sheetname "")
		)
		(fill yes
			(thermal_gap 0.5)
			(thermal_bridge_width 0.5)
			(island_removal_mode 0)
		)
		(polygon
			(pts
				(arc
					(start 127.242062 -439.760614)
					(mid 127.26438 -439.814496)
					(end 127.318262 -439.836814)
				)
				(arc
					(start 128.258062 -439.836814)
					(mid 128.311944 -439.814496)
					(end 128.334262 -439.760614)
				)
				(arc
					(start 128.334262 -437.21909)
					(mid 128.311944 -437.165208)
					(end 128.258062 -437.14289)
				)
				(arc
					(start 127.318262 -437.14289)
					(mid 127.26438 -437.165208)
					(end 127.242062 -437.21909)
				)
				(arc
					(start 127.242062 -437.946546)
					(mid 127.244061 -437.963887)
					(end 127.249936 -437.980328)
				)
				(arc
					(start 127.483362 -438.456578)
					(mid 127.491145 -438.490106)
					(end 127.483362 -438.523634)
				)
				(arc
					(start 127.249936 -438.999884)
					(mid 127.244041 -439.01632)
					(end 127.242062 -439.033666)
				)
			)
		)
	)
	(zone
		(layers "In3.Cu" "In5.Cu")
		(hatch none 0.5)
		(connect_pads
			(clearance 0)
		)
		(min_thickness 0.25)
		(keepout
			(tracks not_allowed)
			(vias allowed)
			(pads allowed)
			(copperpour not_allowed)
			(footprints allowed)
		)
		(placement
			(enabled no)
			(sheetname "")
		)
		(fill yes
			(thermal_gap 0.5)
			(thermal_bridge_width 0.5)
			(island_removal_mode 0)
		)
		(polygon
			(pts
				(arc
					(start 77.142086 -436.160418)
					(mid 77.164404 -436.2143)
					(end 77.218286 -436.236618)
				)
				(arc
					(start 78.158086 -436.236618)
					(mid 78.211968 -436.2143)
					(end 78.234286 -436.160418)
				)
				(arc
					(start 78.234286 -433.618894)
					(mid 78.211968 -433.565012)
					(end 78.158086 -433.542694)
				)
				(arc
					(start 77.218286 -433.542694)
					(mid 77.164404 -433.565012)
					(end 77.142086 -433.618894)
				)
				(arc
					(start 77.142086 -434.34635)
					(mid 77.144085 -434.363691)
					(end 77.14996 -434.380132)
				)
				(arc
					(start 77.383386 -434.856382)
					(mid 77.391169 -434.88991)
					(end 77.383386 -434.923438)
				)
				(arc
					(start 77.14996 -435.399688)
					(mid 77.144065 -435.416124)
					(end 77.142086 -435.43347)
				)
			)
		)
	)
	(zone
		(layers "In3.Cu" "In5.Cu")
		(hatch none 0.5)
		(connect_pads
			(clearance 0)
		)
		(min_thickness 0.25)
		(keepout
			(tracks not_allowed)
			(vias allowed)
			(pads allowed)
			(copperpour not_allowed)
			(footprints allowed)
		)
		(placement
			(enabled no)
			(sheetname "")
		)
		(fill yes
			(thermal_gap 0.5)
			(thermal_bridge_width 0.5)
			(island_removal_mode 0)
		)
		(polygon
			(pts
				(arc
					(start 58.142124 -435.16042)
					(mid 58.164442 -435.214302)
					(end 58.218324 -435.23662)
				)
				(arc
					(start 59.158124 -435.23662)
					(mid 59.212006 -435.214302)
					(end 59.234324 -435.16042)
				)
				(arc
					(start 59.234324 -432.618896)
					(mid 59.212006 -432.565014)
					(end 59.158124 -432.542696)
				)
				(arc
					(start 58.218324 -432.542696)
					(mid 58.164442 -432.565014)
					(end 58.142124 -432.618896)
				)
				(arc
					(start 58.142124 -433.346352)
					(mid 58.144123 -433.363693)
					(end 58.149998 -433.380134)
				)
				(arc
					(start 58.383424 -433.856384)
					(mid 58.391207 -433.889912)
					(end 58.383424 -433.92344)
				)
				(arc
					(start 58.149998 -434.39969)
					(mid 58.144103 -434.416126)
					(end 58.142124 -434.433472)
				)
			)
		)
	)
	(zone
		(layer "In4.Cu")
		(hatch none 0.5)
		(connect_pads
			(clearance 0)
		)
		(min_thickness 0.25)
		(keepout
			(tracks allowed)
			(vias allowed)
			(pads allowed)
			(copperpour allowed)
			(footprints allowed)
		)
		(placement
			(enabled no)
			(sheetname "")
		)
		(fill
			(thermal_gap 0.5)
			(thermal_bridge_width 0.5)
			(island_removal_mode 0)
		)
		(polygon
			(pts
				(xy 50.858674 -305.237134) (xy 50.858674 -303.882298) (xy 51.33594 -303.882298) (xy 51.33594 -305.237134)
			)
		)
	)
	(zone
		(layer "In4.Cu")
		(hatch none 0.5)
		(connect_pads
			(clearance 0)
		)
		(min_thickness 0.25)
		(keepout
			(tracks allowed)
			(vias allowed)
			(pads allowed)
			(copperpour allowed)
			(footprints allowed)
		)
		(placement
			(enabled no)
			(sheetname "")
		)
		(fill
			(thermal_gap 0.5)
			(thermal_bridge_width 0.5)
			(island_removal_mode 0)
		)
		(polygon
			(pts
				(xy 435.58841 -263.851644) (xy 435.58841 -262.496808) (xy 436.065676 -262.496808) (xy 436.065676 -263.851644)
			)
		)
	)
	(zone
		(layer "In4.Cu")
		(hatch none 0.5)
		(connect_pads
			(clearance 0)
		)
		(min_thickness 0.25)
		(keepout
			(tracks allowed)
			(vias allowed)
			(pads allowed)
			(copperpour allowed)
			(footprints allowed)
		)
		(placement
			(enabled no)
			(sheetname "")
		)
		(fill
			(thermal_gap 0.5)
			(thermal_bridge_width 0.5)
			(island_removal_mode 0)
		)
		(polygon
			(pts
				(xy 177.118264 -287.152842) (xy 177.118264 -288.507678) (xy 176.640998 -288.507678) (xy 176.473612 -288.507678)
				(xy 175.98136 -288.507678) (xy 175.98136 -286.81934) (xy 177.118264 -286.81934)
			)
		)
	)
	(zone
		(layer "In4.Cu")
		(hatch none 0.5)
		(connect_pads
			(clearance 0)
		)
		(min_thickness 0.25)
		(keepout
			(tracks allowed)
			(vias allowed)
			(pads allowed)
			(copperpour allowed)
			(footprints allowed)
		)
		(placement
			(enabled no)
			(sheetname "")
		)
		(fill
			(thermal_gap 0.5)
			(thermal_bridge_width 0.5)
			(island_removal_mode 0)
		)
		(polygon
			(pts
				(xy 391.832592 -241.683794) (xy 394.042392 -243.893594) (xy 393.331192 -244.604794) (xy 388.36092 -244.605048)
				(xy 388.36092 -241.927888) (xy 391.588752 -241.927634)
			)
		)
	)
	(zone
		(layer "In4.Cu")
		(hatch none 0.5)
		(connect_pads
			(clearance 0)
		)
		(min_thickness 0.25)
		(keepout
			(tracks allowed)
			(vias allowed)
			(pads allowed)
			(copperpour allowed)
			(footprints allowed)
		)
		(placement
			(enabled no)
			(sheetname "")
		)
		(fill
			(thermal_gap 0.5)
			(thermal_bridge_width 0.5)
			(island_removal_mode 0)
		)
		(polygon
			(pts
				(xy 31.616142 -244.321076) (xy 31.616142 -242.96624) (xy 32.093408 -242.96624) (xy 32.093408 -244.321076)
			)
		)
	)
	(zone
		(layer "In4.Cu")
		(hatch none 0.5)
		(connect_pads
			(clearance 0)
		)
		(min_thickness 0.25)
		(keepout
			(tracks allowed)
			(vias allowed)
			(pads allowed)
			(copperpour allowed)
			(footprints allowed)
		)
		(placement
			(enabled no)
			(sheetname "")
		)
		(fill
			(thermal_gap 0.5)
			(thermal_bridge_width 0.5)
			(island_removal_mode 0)
		)
		(polygon
			(pts
				(xy 35.725862 -295.570656) (xy 35.725862 -294.21582) (xy 36.203128 -294.21582) (xy 36.203128 -295.570656)
			)
		)
	)
	(zone
		(layer "In4.Cu")
		(hatch none 0.5)
		(connect_pads
			(clearance 0)
		)
		(min_thickness 0.25)
		(keepout
			(tracks allowed)
			(vias allowed)
			(pads allowed)
			(copperpour allowed)
			(footprints allowed)
		)
		(placement
			(enabled no)
			(sheetname "")
		)
		(fill
			(thermal_gap 0.5)
			(thermal_bridge_width 0.5)
			(island_removal_mode 0)
		)
		(polygon
			(pts
				(xy 43.273472 -242.559078) (xy 43.273472 -241.377978) (xy 43.728132 -241.377978) (xy 43.728132 -242.559078)
			)
		)
	)
	(zone
		(layer "In4.Cu")
		(hatch none 0.5)
		(connect_pads
			(clearance 0)
		)
		(min_thickness 0.25)
		(keepout
			(tracks allowed)
			(vias allowed)
			(pads allowed)
			(copperpour allowed)
			(footprints allowed)
		)
		(placement
			(enabled no)
			(sheetname "")
		)
		(fill
			(thermal_gap 0.5)
			(thermal_bridge_width 0.5)
			(island_removal_mode 0)
		)
		(polygon
			(pts
				(xy 187.62853 -267.25753) (xy 187.62853 -265.902694) (xy 188.105796 -265.902694) (xy 188.105796 -267.25753)
			)
		)
	)
	(zone
		(layer "In4.Cu")
		(hatch none 0.5)
		(connect_pads
			(clearance 0)
		)
		(min_thickness 0.25)
		(keepout
			(tracks allowed)
			(vias allowed)
			(pads allowed)
			(copperpour allowed)
			(footprints allowed)
		)
		(placement
			(enabled no)
			(sheetname "")
		)
		(fill
			(thermal_gap 0.5)
			(thermal_bridge_width 0.5)
			(island_removal_mode 0)
		)
		(polygon
			(pts
				(xy 187.638436 -314.96508) (xy 187.638436 -313.610244) (xy 188.115702 -313.610244) (xy 188.115702 -314.96508)
			)
		)
	)
	(zone
		(layer "In4.Cu")
		(hatch none 0.5)
		(connect_pads
			(clearance 0)
		)
		(min_thickness 0.25)
		(keepout
			(tracks allowed)
			(vias allowed)
			(pads allowed)
			(copperpour allowed)
			(footprints allowed)
		)
		(placement
			(enabled no)
			(sheetname "")
		)
		(fill
			(thermal_gap 0.5)
			(thermal_bridge_width 0.5)
			(island_removal_mode 0)
		)
		(polygon
			(pts
				(xy 50.826162 -308.151276) (xy 50.826162 -306.79644) (xy 51.303428 -306.79644) (xy 51.303428 -308.151276)
			)
		)
	)
	(zone
		(layer "In4.Cu")
		(hatch none 0.5)
		(connect_pads
			(clearance 0)
		)
		(min_thickness 0.25)
		(keepout
			(tracks allowed)
			(vias allowed)
			(pads allowed)
			(copperpour allowed)
			(footprints allowed)
		)
		(placement
			(enabled no)
			(sheetname "")
		)
		(fill
			(thermal_gap 0.5)
			(thermal_bridge_width 0.5)
			(island_removal_mode 0)
		)
		(polygon
			(pts
				(xy 61.789564 -245.100856) (xy 61.789564 -242.924076) (xy 62.411864 -242.924076) (xy 62.411864 -245.100856)
			)
		)
	)
	(zone
		(layer "In4.Cu")
		(hatch none 0.5)
		(connect_pads
			(clearance 0)
		)
		(min_thickness 0.25)
		(keepout
			(tracks allowed)
			(vias allowed)
			(pads allowed)
			(copperpour allowed)
			(footprints allowed)
		)
		(placement
			(enabled no)
			(sheetname "")
		)
		(fill
			(thermal_gap 0.5)
			(thermal_bridge_width 0.5)
			(island_removal_mode 0)
		)
		(polygon
			(pts
				(xy 298.786042 -308.145434) (xy 298.786042 -306.790598) (xy 299.263308 -306.790598) (xy 299.263308 -308.145434)
			)
		)
	)
	(zone
		(layer "In4.Cu")
		(hatch none 0.5)
		(connect_pads
			(clearance 0)
		)
		(min_thickness 0.25)
		(keepout
			(tracks allowed)
			(vias allowed)
			(pads allowed)
			(copperpour allowed)
			(footprints allowed)
		)
		(placement
			(enabled no)
			(sheetname "")
		)
		(fill
			(thermal_gap 0.5)
			(thermal_bridge_width 0.5)
			(island_removal_mode 0)
		)
		(polygon
			(pts
				(xy 313.73572 -232.404158) (xy 313.73572 -223.412558) (xy 314.3377 -223.412558) (xy 314.3377 -232.404158)
			)
		)
	)
	(zone
		(layer "In4.Cu")
		(hatch none 0.5)
		(connect_pads
			(clearance 0)
		)
		(min_thickness 0.25)
		(keepout
			(tracks allowed)
			(vias allowed)
			(pads allowed)
			(copperpour allowed)
			(footprints allowed)
		)
		(placement
			(enabled no)
			(sheetname "")
		)
		(fill
			(thermal_gap 0.5)
			(thermal_bridge_width 0.5)
			(island_removal_mode 0)
		)
		(polygon
			(pts
				(xy 61.805312 -305.543458) (xy 61.805312 -301.598838) (xy 62.328552 -301.598838) (xy 62.328552 -305.543458)
			)
		)
	)
	(zone
		(layer "In4.Cu")
		(hatch none 0.5)
		(connect_pads
			(clearance 0)
		)
		(min_thickness 0.25)
		(keepout
			(tracks allowed)
			(vias allowed)
			(pads allowed)
			(copperpour allowed)
			(footprints allowed)
		)
		(placement
			(enabled no)
			(sheetname "")
		)
		(fill
			(thermal_gap 0.5)
			(thermal_bridge_width 0.5)
			(island_removal_mode 0)
		)
		(polygon
			(pts
				(xy 435.58841 -206.901542) (xy 435.58841 -205.546706) (xy 436.065676 -205.546706) (xy 436.065676 -206.901542)
			)
		)
	)
	(zone
		(layer "In4.Cu")
		(hatch none 0.5)
		(connect_pads
			(clearance 0)
		)
		(min_thickness 0.25)
		(keepout
			(tracks allowed)
			(vias allowed)
			(pads allowed)
			(copperpour allowed)
			(footprints allowed)
		)
		(placement
			(enabled no)
			(sheetname "")
		)
		(fill
			(thermal_gap 0.5)
			(thermal_bridge_width 0.5)
			(island_removal_mode 0)
		)
		(polygon
			(pts
				(xy 172.560742 -272.351754) (xy 172.560742 -270.996918) (xy 173.038008 -270.996918) (xy 173.038008 -272.351754)
			)
		)
	)
	(zone
		(layer "In4.Cu")
		(hatch none 0.5)
		(connect_pads
			(clearance 0)
		)
		(min_thickness 0.25)
		(keepout
			(tracks allowed)
			(vias allowed)
			(pads allowed)
			(copperpour allowed)
			(footprints allowed)
		)
		(placement
			(enabled no)
			(sheetname "")
		)
		(fill
			(thermal_gap 0.5)
			(thermal_bridge_width 0.5)
			(island_removal_mode 0)
		)
		(polygon
			(pts
				(xy 61.749432 -301.205138) (xy 61.749432 -298.065698) (xy 62.196472 -298.065698) (xy 62.196472 -301.205138)
			)
		)
	)
	(zone
		(layer "In4.Cu")
		(hatch none 0.5)
		(connect_pads
			(clearance 0)
		)
		(min_thickness 0.25)
		(keepout
			(tracks allowed)
			(vias allowed)
			(pads allowed)
			(copperpour allowed)
			(footprints allowed)
		)
		(placement
			(enabled no)
			(sheetname "")
		)
		(fill
			(thermal_gap 0.5)
			(thermal_bridge_width 0.5)
			(island_removal_mode 0)
		)
		(polygon
			(pts
				(xy 61.858144 -233.165396) (xy 61.858144 -223.343216) (xy 62.335664 -223.343216) (xy 62.335664 -233.165396)
			)
		)
	)
	(zone
		(layer "In4.Cu")
		(hatch none 0.5)
		(connect_pads
			(clearance 0)
		)
		(min_thickness 0.25)
		(keepout
			(tracks allowed)
			(vias allowed)
			(pads allowed)
			(copperpour allowed)
			(footprints allowed)
		)
		(placement
			(enabled no)
			(sheetname "")
		)
		(fill
			(thermal_gap 0.5)
			(thermal_bridge_width 0.5)
			(island_removal_mode 0)
		)
		(polygon
			(pts
				(xy 187.648342 -237.491778) (xy 187.648342 -235.29671) (xy 188.125608 -235.29671) (xy 188.125608 -237.491778)
			)
		)
	)
	(zone
		(layer "In4.Cu")
		(hatch none 0.5)
		(connect_pads
			(clearance 0)
		)
		(min_thickness 0.25)
		(keepout
			(tracks allowed)
			(vias allowed)
			(pads allowed)
			(copperpour allowed)
			(footprints allowed)
		)
		(placement
			(enabled no)
			(sheetname "")
		)
		(fill
			(thermal_gap 0.5)
			(thermal_bridge_width 0.5)
			(island_removal_mode 0)
		)
		(polygon
			(pts
				(xy 435.58841 -293.623238) (xy 435.58841 -291.396928) (xy 436.065676 -291.396928) (xy 436.065676 -293.623238)
			)
		)
	)
	(zone
		(layer "In4.Cu")
		(hatch none 0.5)
		(connect_pads
			(clearance 0)
		)
		(min_thickness 0.25)
		(keepout
			(tracks allowed)
			(vias allowed)
			(pads allowed)
			(copperpour allowed)
			(footprints allowed)
		)
		(placement
			(enabled no)
			(sheetname "")
		)
		(fill
			(thermal_gap 0.5)
			(thermal_bridge_width 0.5)
			(island_removal_mode 0)
		)
		(polygon
			(pts
				(xy 187.648342 -291.051742) (xy 187.648342 -289.696906) (xy 188.125608 -289.696906) (xy 188.125608 -291.051742)
			)
		)
	)
	(zone
		(layer "In4.Cu")
		(hatch none 0.5)
		(connect_pads
			(clearance 0)
		)
		(min_thickness 0.25)
		(keepout
			(tracks allowed)
			(vias allowed)
			(pads allowed)
			(copperpour allowed)
			(footprints allowed)
		)
		(placement
			(enabled no)
			(sheetname "")
		)
		(fill
			(thermal_gap 0.5)
			(thermal_bridge_width 0.5)
			(island_removal_mode 0)
		)
		(polygon
			(pts
				(xy 35.745674 -294.142414) (xy 35.745674 -292.787578) (xy 36.22294 -292.787578) (xy 36.22294 -294.142414)
			)
		)
	)
	(zone
		(layer "In4.Cu")
		(hatch none 0.5)
		(connect_pads
			(clearance 0)
		)
		(min_thickness 0.25)
		(keepout
			(tracks allowed)
			(vias allowed)
			(pads allowed)
			(copperpour allowed)
			(footprints allowed)
		)
		(placement
			(enabled no)
			(sheetname "")
		)
		(fill
			(thermal_gap 0.5)
			(thermal_bridge_width 0.5)
			(island_removal_mode 0)
		)
		(polygon
			(pts
				(xy 291.279072 -261.227316) (xy 291.279072 -258.273296) (xy 291.634672 -258.273296) (xy 291.634672 -261.227316)
			)
		)
	)
	(zone
		(layer "In4.Cu")
		(hatch none 0.5)
		(connect_pads
			(clearance 0)
		)
		(min_thickness 0.25)
		(keepout
			(tracks allowed)
			(vias allowed)
			(pads allowed)
			(copperpour allowed)
			(footprints allowed)
		)
		(placement
			(enabled no)
			(sheetname "")
		)
		(fill
			(thermal_gap 0.5)
			(thermal_bridge_width 0.5)
			(island_removal_mode 0)
		)
		(polygon
			(pts
				(xy 59.603132 -318.210438) (xy 59.603132 -316.912498) (xy 60.108592 -316.912498) (xy 60.108592 -318.210438)
			)
		)
	)
	(zone
		(layer "In4.Cu")
		(hatch none 0.5)
		(connect_pads
			(clearance 0)
		)
		(min_thickness 0.25)
		(keepout
			(tracks allowed)
			(vias allowed)
			(pads allowed)
			(copperpour allowed)
			(footprints allowed)
		)
		(placement
			(enabled no)
			(sheetname "")
		)
		(fill
			(thermal_gap 0.5)
			(thermal_bridge_width 0.5)
			(island_removal_mode 0)
		)
		(polygon
			(pts
				(xy 35.745674 -234.076494) (xy 35.745674 -232.721658) (xy 36.22294 -232.721658) (xy 36.22294 -234.076494)
			)
		)
	)
	(zone
		(layer "In4.Cu")
		(hatch none 0.5)
		(connect_pads
			(clearance 0)
		)
		(min_thickness 0.25)
		(keepout
			(tracks allowed)
			(vias allowed)
			(pads allowed)
			(copperpour allowed)
			(footprints allowed)
		)
		(placement
			(enabled no)
			(sheetname "")
		)
		(fill
			(thermal_gap 0.5)
			(thermal_bridge_width 0.5)
			(island_removal_mode 0)
		)
		(polygon
			(pts
				(xy 391.11936 -263.319514) (xy 391.329164 -263.109964) (xy 394.522452 -259.916168) (xy 394.522452 -259.851906)
				(xy 395.101572 -259.272786) (xy 395.101572 -258.863084) (xy 396.86484 -257.099816) (xy 397.083534 -256.881122)
				(xy 397.083534 -252.348492) (xy 396.379954 -251.644912) (xy 396.377414 -251.644912) (xy 396.377414 -251.05106)
				(xy 395.73454 -250.408186) (xy 395.722094 -250.408186) (xy 394.95857 -249.644662) (xy 394.95857 -249.50801)
				(xy 396.03299 -248.43359) (xy 396.383256 -248.43359) (xy 398.369282 -246.447564) (xy 398.141952 -246.220234)
				(xy 398.027652 -246.220234) (xy 397.799052 -245.991634) (xy 396.694152 -245.991634) (xy 395.017752 -244.315234)
				(xy 394.452602 -244.315234) (xy 393.85621 -244.911626) (xy 388.391654 -244.911626) (xy 388.216648 -245.086632)
				(xy 385.996942 -245.086632) (xy 385.894834 -245.18874) (xy 385.894834 -249.521472) (xy 385.43865 -249.977656)
				(xy 377.792996 -249.977656) (xy 377.494546 -250.276106) (xy 377.150376 -250.276106) (xy 377.085606 -250.211336)
				(xy 377.085606 -250.055888) (xy 377.085606 -249.903488) (xy 377.087892 -249.903488) (xy 377.113292 -249.878088)
				(xy 377.113292 -249.65025) (xy 376.986038 -249.522996) (xy 376.982736 -249.526298) (xy 376.15114 -249.526298)
				(xy 375.989596 -249.364754) (xy 375.714006 -249.364754) (xy 375.714006 -250.386088) (xy 375.841006 -250.513088)
				(xy 375.841006 -251.579888) (xy 375.383806 -252.037088) (xy 374.789954 -252.63094) (xy 374.789954 -252.924818)
				(xy 378.463556 -252.924818) (xy 378.762006 -252.924818) (xy 378.821188 -252.924818) (xy 378.892308 -252.995938)
				(xy 378.892308 -253.935738) (xy 379.041914 -254.085344) (xy 384.928364 -254.085344) (xy 385.01574 -254.17272)
				(xy 385.01574 -254.935228) (xy 385.01574 -255.00203) (xy 385.04622 -255.03251) (xy 386.684012 -255.03251)
				(xy 386.788914 -255.137412) (xy 387.652006 -255.137412) (xy 387.754368 -255.239774) (xy 387.754368 -256.09931)
				(xy 387.702298 -256.15138) (xy 385.369054 -256.15138) (xy 385.32943 -256.191004) (xy 385.32943 -257.21564)
				(xy 385.357878 -257.244088) (xy 386.849112 -257.244088) (xy 386.866638 -257.261614) (xy 386.866638 -257.908806)
				(xy 386.984494 -258.026662) (xy 387.505702 -258.026662) (xy 387.58114 -258.1021) (xy 387.58114 -259.754116)
				(xy 387.533388 -259.801868) (xy 387.474206 -259.801868) (xy 386.893054 -259.801868) (xy 386.879338 -259.815584)
				(xy 386.879338 -261.91083) (xy 386.902198 -261.93369) (xy 388.332218 -261.93369) (xy 388.509256 -262.110728)
				(xy 388.509256 -263.319768)
			)
		)
	)
	(zone
		(layer "In4.Cu")
		(hatch none 0.5)
		(connect_pads
			(clearance 0)
		)
		(min_thickness 0.25)
		(keepout
			(tracks allowed)
			(vias allowed)
			(pads allowed)
			(copperpour allowed)
			(footprints allowed)
		)
		(placement
			(enabled no)
			(sheetname "")
		)
		(fill
			(thermal_gap 0.5)
			(thermal_bridge_width 0.5)
			(island_removal_mode 0)
		)
		(polygon
			(pts
				(xy 172.560742 -202.651614) (xy 172.560742 -200.410318) (xy 173.038008 -200.410318) (xy 173.038008 -202.651614)
			)
		)
	)
	(zone
		(layer "In4.Cu")
		(hatch none 0.5)
		(connect_pads
			(clearance 0)
		)
		(min_thickness 0.25)
		(keepout
			(tracks allowed)
			(vias allowed)
			(pads allowed)
			(copperpour allowed)
			(footprints allowed)
		)
		(placement
			(enabled no)
			(sheetname "")
		)
		(fill
			(thermal_gap 0.5)
			(thermal_bridge_width 0.5)
			(island_removal_mode 0)
		)
		(polygon
			(pts
				(xy 35.741102 -262.603996) (xy 35.741102 -261.24916) (xy 36.218368 -261.24916) (xy 36.218368 -262.603996)
			)
		)
	)
	(zone
		(layer "In4.Cu")
		(hatch none 0.5)
		(connect_pads
			(clearance 0)
		)
		(min_thickness 0.25)
		(keepout
			(tracks allowed)
			(vias allowed)
			(pads allowed)
			(copperpour allowed)
			(footprints allowed)
		)
		(placement
			(enabled no)
			(sheetname "")
		)
		(fill
			(thermal_gap 0.5)
			(thermal_bridge_width 0.5)
			(island_removal_mode 0)
		)
		(polygon
			(pts
				(xy 420.50081 -206.051658) (xy 420.50081 -204.696822) (xy 420.978076 -204.696822) (xy 420.978076 -206.051658)
				(xy 420.978076 -206.54137) (xy 420.50081 -206.54137)
			)
		)
	)
	(zone
		(layer "In4.Cu")
		(hatch none 0.5)
		(connect_pads
			(clearance 0)
		)
		(min_thickness 0.25)
		(keepout
			(tracks allowed)
			(vias allowed)
			(pads allowed)
			(copperpour allowed)
			(footprints allowed)
		)
		(placement
			(enabled no)
			(sheetname "")
		)
		(fill
			(thermal_gap 0.5)
			(thermal_bridge_width 0.5)
			(island_removal_mode 0)
		)
		(polygon
			(pts
				(xy 300.000162 -318.943736) (xy 300.000162 -317.5889) (xy 300.477428 -317.5889) (xy 300.477428 -318.943736)
			)
		)
	)
	(zone
		(layer "In4.Cu")
		(hatch none 0.5)
		(connect_pads
			(clearance 0)
		)
		(min_thickness 0.25)
		(keepout
			(tracks allowed)
			(vias allowed)
			(pads allowed)
			(copperpour allowed)
			(footprints allowed)
		)
		(placement
			(enabled no)
			(sheetname "")
		)
		(fill
			(thermal_gap 0.5)
			(thermal_bridge_width 0.5)
			(island_removal_mode 0)
		)
		(polygon
			(pts
				(xy 43.257724 -317.297816) (xy 43.257724 -316.177676) (xy 43.819064 -316.177676) (xy 43.819064 -317.297816)
			)
		)
	)
	(zone
		(layer "In4.Cu")
		(hatch none 0.5)
		(connect_pads
			(clearance 0)
		)
		(min_thickness 0.25)
		(keepout
			(tracks allowed)
			(vias allowed)
			(pads allowed)
			(copperpour allowed)
			(footprints allowed)
		)
		(placement
			(enabled no)
			(sheetname "")
		)
		(fill
			(thermal_gap 0.5)
			(thermal_bridge_width 0.5)
			(island_removal_mode 0)
		)
		(polygon
			(pts
				(xy 291.21354 -242.559078) (xy 291.21354 -241.377978) (xy 291.6682 -241.377978) (xy 291.6682 -242.559078)
			)
		)
	)
	(zone
		(layer "In4.Cu")
		(hatch none 0.5)
		(connect_pads
			(clearance 0)
		)
		(min_thickness 0.25)
		(keepout
			(tracks allowed)
			(vias allowed)
			(pads allowed)
			(copperpour allowed)
			(footprints allowed)
		)
		(placement
			(enabled no)
			(sheetname "")
		)
		(fill
			(thermal_gap 0.5)
			(thermal_bridge_width 0.5)
			(island_removal_mode 0)
		)
		(polygon
			(pts
				(xy 298.77893 -303.863756) (xy 298.77893 -302.50892) (xy 299.256196 -302.50892) (xy 299.256196 -303.863756)
			)
		)
	)
	(zone
		(layer "In4.Cu")
		(hatch none 0.5)
		(connect_pads
			(clearance 0)
		)
		(min_thickness 0.25)
		(keepout
			(tracks allowed)
			(vias allowed)
			(pads allowed)
			(copperpour allowed)
			(footprints allowed)
		)
		(placement
			(enabled no)
			(sheetname "")
		)
		(fill
			(thermal_gap 0.5)
			(thermal_bridge_width 0.5)
			(island_removal_mode 0)
		)
		(polygon
			(pts
				(xy 35.753294 -212.829394) (xy 35.753294 -211.474558) (xy 36.23056 -211.474558) (xy 36.23056 -212.829394)
			)
		)
	)
	(zone
		(layer "In4.Cu")
		(hatch none 0.5)
		(connect_pads
			(clearance 0)
		)
		(min_thickness 0.25)
		(keepout
			(tracks allowed)
			(vias allowed)
			(pads allowed)
			(copperpour allowed)
			(footprints allowed)
		)
		(placement
			(enabled no)
			(sheetname "")
		)
		(fill
			(thermal_gap 0.5)
			(thermal_bridge_width 0.5)
			(island_removal_mode 0)
		)
		(polygon
			(pts
				(xy 291.233352 -242.553236) (xy 291.233352 -241.372136) (xy 291.688012 -241.372136) (xy 291.688012 -242.553236)
			)
		)
	)
	(zone
		(layer "In4.Cu")
		(hatch none 0.5)
		(connect_pads
			(clearance 0)
		)
		(min_thickness 0.25)
		(keepout
			(tracks allowed)
			(vias allowed)
			(pads allowed)
			(copperpour allowed)
			(footprints allowed)
		)
		(placement
			(enabled no)
			(sheetname "")
		)
		(fill
			(thermal_gap 0.5)
			(thermal_bridge_width 0.5)
			(island_removal_mode 0)
		)
		(polygon
			(pts
				(xy 409.437332 -306.741322) (xy 409.437332 -305.386486) (xy 409.914598 -305.386486) (xy 409.914598 -306.741322)
			)
		)
	)
	(zone
		(layer "In4.Cu")
		(hatch none 0.5)
		(connect_pads
			(clearance 0)
		)
		(min_thickness 0.25)
		(keepout
			(tracks allowed)
			(vias allowed)
			(pads allowed)
			(copperpour allowed)
			(footprints allowed)
		)
		(placement
			(enabled no)
			(sheetname "")
		)
		(fill
			(thermal_gap 0.5)
			(thermal_bridge_width 0.5)
			(island_removal_mode 0)
		)
		(polygon
			(pts
				(xy 435.568598 -291.057584) (xy 435.568598 -289.702748) (xy 436.045864 -289.702748) (xy 436.045864 -291.057584)
			)
		)
	)
	(zone
		(layer "In4.Cu")
		(hatch none 0.5)
		(connect_pads
			(clearance 0)
		)
		(min_thickness 0.25)
		(keepout
			(tracks allowed)
			(vias allowed)
			(pads allowed)
			(copperpour allowed)
			(footprints allowed)
		)
		(placement
			(enabled no)
			(sheetname "")
		)
		(fill
			(thermal_gap 0.5)
			(thermal_bridge_width 0.5)
			(island_removal_mode 0)
		)
		(polygon
			(pts
				(xy 243.91112 -43.08348) (xy 243.91112 -41.79316) (xy 244.9957 -41.79316) (xy 244.9957 -43.08348)
			)
		)
	)
	(zone
		(layer "In4.Cu")
		(hatch none 0.5)
		(connect_pads
			(clearance 0)
		)
		(min_thickness 0.25)
		(keepout
			(tracks allowed)
			(vias allowed)
			(pads allowed)
			(copperpour allowed)
			(footprints allowed)
		)
		(placement
			(enabled no)
			(sheetname "")
		)
		(fill
			(thermal_gap 0.5)
			(thermal_bridge_width 0.5)
			(island_removal_mode 0)
		)
		(polygon
			(pts
				(xy 302.2092 -245.066058) (xy 302.2092 -242.909598) (xy 302.74768 -242.909598) (xy 302.74768 -245.066058)
			)
		)
	)
	(zone
		(layer "In4.Cu")
		(hatch none 0.5)
		(connect_pads
			(clearance 0)
		)
		(min_thickness 0.25)
		(keepout
			(tracks allowed)
			(vias allowed)
			(pads allowed)
			(copperpour allowed)
			(footprints allowed)
		)
		(placement
			(enabled no)
			(sheetname "")
		)
		(fill
			(thermal_gap 0.5)
			(thermal_bridge_width 0.5)
			(island_removal_mode 0)
		)
		(polygon
			(pts
				(xy 50.856134 -229.011734) (xy 50.856134 -227.656898) (xy 51.3334 -227.656898) (xy 51.3334 -229.011734)
				(xy 51.3334 -231.929432) (xy 50.856134 -231.929432)
			)
		)
	)
	(zone
		(layer "In4.Cu")
		(hatch none 0.5)
		(connect_pads
			(clearance 0)
		)
		(min_thickness 0.25)
		(keepout
			(tracks allowed)
			(vias allowed)
			(pads allowed)
			(copperpour allowed)
			(footprints allowed)
		)
		(placement
			(enabled no)
			(sheetname "")
		)
		(fill
			(thermal_gap 0.5)
			(thermal_bridge_width 0.5)
			(island_removal_mode 0)
		)
		(polygon
			(pts
				(xy 313.755532 -232.398316) (xy 313.755532 -223.406716) (xy 314.357512 -223.406716) (xy 314.357512 -232.398316)
			)
		)
	)
	(zone
		(layer "In4.Cu")
		(hatch none 0.5)
		(connect_pads
			(clearance 0)
		)
		(min_thickness 0.25)
		(keepout
			(tracks allowed)
			(vias allowed)
			(pads allowed)
			(copperpour allowed)
			(footprints allowed)
		)
		(placement
			(enabled no)
			(sheetname "")
		)
		(fill
			(thermal_gap 0.5)
			(thermal_bridge_width 0.5)
			(island_removal_mode 0)
		)
		(polygon
			(pts
				(xy 283.66593 -294.148256) (xy 283.66593 -292.79342) (xy 284.143196 -292.79342) (xy 284.143196 -294.148256)
			)
		)
	)
	(zone
		(layer "In4.Cu")
		(hatch none 0.5)
		(connect_pads
			(clearance 0)
		)
		(min_thickness 0.25)
		(keepout
			(tracks allowed)
			(vias allowed)
			(pads allowed)
			(copperpour allowed)
			(footprints allowed)
		)
		(placement
			(enabled no)
			(sheetname "")
		)
		(fill
			(thermal_gap 0.5)
			(thermal_bridge_width 0.5)
			(island_removal_mode 0)
		)
		(polygon
			(pts
				(xy 299.950632 -195.763896) (xy 299.950632 -194.552316) (xy 300.509432 -194.552316) (xy 300.509432 -195.763896)
			)
		)
	)
	(zone
		(layer "In4.Cu")
		(hatch none 0.5)
		(connect_pads
			(clearance 0)
		)
		(min_thickness 0.25)
		(keepout
			(tracks allowed)
			(vias allowed)
			(pads allowed)
			(copperpour allowed)
			(footprints allowed)
		)
		(placement
			(enabled no)
			(sheetname "")
		)
		(fill
			(thermal_gap 0.5)
			(thermal_bridge_width 0.5)
			(island_removal_mode 0)
		)
		(polygon
			(pts
				(xy 187.62853 -237.49762) (xy 187.62853 -235.302552) (xy 188.105796 -235.302552) (xy 188.105796 -237.49762)
			)
		)
	)
	(zone
		(layer "In4.Cu")
		(hatch none 0.5)
		(connect_pads
			(clearance 0)
		)
		(min_thickness 0.25)
		(keepout
			(tracks allowed)
			(vias allowed)
			(pads allowed)
			(copperpour allowed)
			(footprints allowed)
		)
		(placement
			(enabled no)
			(sheetname "")
		)
		(fill
			(thermal_gap 0.5)
			(thermal_bridge_width 0.5)
			(island_removal_mode 0)
		)
		(polygon
			(pts
				(xy 357.814626 -355.594412) (xy 359.259886 -355.594412) (xy 359.567226 -355.901752) (xy 359.567226 -356.358952)
				(xy 359.445306 -356.480872) (xy 359.107486 -356.480872) (xy 358.977946 -356.351332) (xy 358.124506 -356.351332)
				(xy 357.786686 -356.689152) (xy 357.786686 -362.231432) (xy 357.255826 -362.762292) (xy 357.255826 -365.444532)
				(xy 356.600506 -366.099852) (xy 356.600506 -366.574832) (xy 356.760526 -366.734852) (xy 356.760526 -367.021872)
				(xy 356.676706 -367.105692) (xy 355.518466 -367.105692) (xy 355.409246 -366.996472) (xy 355.409246 -366.765332)
				(xy 355.729286 -366.445292) (xy 355.729286 -365.899192) (xy 356.498906 -365.129572) (xy 356.498906 -362.487972)
				(xy 357.050086 -361.936792) (xy 357.050086 -356.358952)
			)
		)
	)
	(zone
		(layer "In4.Cu")
		(hatch none 0.5)
		(connect_pads
			(clearance 0)
		)
		(min_thickness 0.25)
		(keepout
			(tracks allowed)
			(vias allowed)
			(pads allowed)
			(copperpour allowed)
			(footprints allowed)
		)
		(placement
			(enabled no)
			(sheetname "")
		)
		(fill
			(thermal_gap 0.5)
			(thermal_bridge_width 0.5)
			(island_removal_mode 0)
		)
		(polygon
			(pts
				(xy 420.480998 -307.207412) (xy 420.480998 -305.852576) (xy 420.958264 -305.852576) (xy 420.958264 -307.207412)
			)
		)
	)
	(zone
		(layer "In4.Cu")
		(hatch none 0.5)
		(connect_pads
			(clearance 0)
		)
		(min_thickness 0.25)
		(keepout
			(tracks allowed)
			(vias allowed)
			(pads allowed)
			(copperpour allowed)
			(footprints allowed)
		)
		(placement
			(enabled no)
			(sheetname "")
		)
		(fill
			(thermal_gap 0.5)
			(thermal_bridge_width 0.5)
			(island_removal_mode 0)
		)
		(polygon
			(pts
				(xy 351.78746 -352.422968) (xy 351.78746 -351.183448) (xy 353.74834 -351.183448) (xy 353.74834 -352.422968)
			)
		)
	)
	(zone
		(layer "In4.Cu")
		(hatch none 0.5)
		(connect_pads
			(clearance 0)
		)
		(min_thickness 0.25)
		(keepout
			(tracks allowed)
			(vias allowed)
			(pads allowed)
			(copperpour allowed)
			(footprints allowed)
		)
		(placement
			(enabled no)
			(sheetname "")
		)
		(fill
			(thermal_gap 0.5)
			(thermal_bridge_width 0.5)
			(island_removal_mode 0)
		)
		(polygon
			(pts
				(xy 405.367998 -244.30736) (xy 405.367998 -242.952524) (xy 405.845264 -242.952524) (xy 405.845264 -244.30736)
			)
		)
	)
	(zone
		(layer "In4.Cu")
		(hatch none 0.5)
		(connect_pads
			(clearance 0)
		)
		(min_thickness 0.25)
		(keepout
			(tracks allowed)
			(vias allowed)
			(pads allowed)
			(copperpour allowed)
			(footprints allowed)
		)
		(placement
			(enabled no)
			(sheetname "")
		)
		(fill
			(thermal_gap 0.5)
			(thermal_bridge_width 0.5)
			(island_removal_mode 0)
		)
		(polygon
			(pts
				(xy 187.62853 -240.057432) (xy 187.62853 -238.702596) (xy 188.105796 -238.702596) (xy 188.105796 -240.057432)
			)
		)
	)
	(zone
		(layer "In4.Cu")
		(hatch none 0.5)
		(connect_pads
			(clearance 0)
		)
		(min_thickness 0.25)
		(keepout
			(tracks allowed)
			(vias allowed)
			(pads allowed)
			(copperpour allowed)
			(footprints allowed)
		)
		(placement
			(enabled no)
			(sheetname "")
		)
		(fill
			(thermal_gap 0.5)
			(thermal_bridge_width 0.5)
			(island_removal_mode 0)
		)
		(polygon
			(pts
				(xy 50.833782 -285.118556) (xy 50.833782 -283.76372) (xy 51.311048 -283.76372) (xy 51.311048 -285.118556)
			)
		)
	)
	(zone
		(layer "In4.Cu")
		(hatch none 0.5)
		(connect_pads
			(clearance 0)
		)
		(min_thickness 0.25)
		(keepout
			(tracks allowed)
			(vias allowed)
			(pads allowed)
			(copperpour allowed)
			(footprints allowed)
		)
		(placement
			(enabled no)
			(sheetname "")
		)
		(fill
			(thermal_gap 0.5)
			(thermal_bridge_width 0.5)
			(island_removal_mode 0)
		)
		(polygon
			(pts
				(xy 50.845974 -302.234854) (xy 50.845974 -300.880018) (xy 51.32324 -300.880018) (xy 51.32324 -302.234854)
			)
		)
	)
	(zone
		(layer "In4.Cu")
		(hatch none 0.5)
		(connect_pads
			(clearance 0)
		)
		(min_thickness 0.25)
		(keepout
			(tracks allowed)
			(vias allowed)
			(pads allowed)
			(copperpour allowed)
			(footprints allowed)
		)
		(placement
			(enabled no)
			(sheetname "")
		)
		(fill
			(thermal_gap 0.5)
			(thermal_bridge_width 0.5)
			(island_removal_mode 0)
		)
		(polygon
			(pts
				(xy 342.6841 -47.219108) (xy 342.6841 -46.380908) (xy 344.05062 -46.380908) (xy 344.05062 -47.219108)
			)
		)
	)
	(zone
		(layer "In4.Cu")
		(hatch none 0.5)
		(connect_pads
			(clearance 0)
		)
		(min_thickness 0.25)
		(keepout
			(tracks allowed)
			(vias allowed)
			(pads allowed)
			(copperpour allowed)
			(footprints allowed)
		)
		(placement
			(enabled no)
			(sheetname "")
		)
		(fill
			(thermal_gap 0.5)
			(thermal_bridge_width 0.5)
			(island_removal_mode 0)
		)
		(polygon
			(pts
				(xy 187.62853 -246.007382) (xy 187.62853 -244.652546) (xy 188.105796 -244.652546) (xy 188.105796 -246.007382)
			)
		)
	)
	(zone
		(layer "In4.Cu")
		(hatch none 0.5)
		(connect_pads
			(clearance 0)
		)
		(min_thickness 0.25)
		(keepout
			(tracks allowed)
			(vias allowed)
			(pads allowed)
			(copperpour allowed)
			(footprints allowed)
		)
		(placement
			(enabled no)
			(sheetname "")
		)
		(fill
			(thermal_gap 0.5)
			(thermal_bridge_width 0.5)
			(island_removal_mode 0)
		)
		(polygon
			(pts
				(xy 420.50081 -231.551734) (xy 420.50081 -230.196898) (xy 420.978076 -230.196898) (xy 420.978076 -231.551734)
				(xy 420.978076 -232.495852) (xy 420.180516 -232.495852) (xy 420.180516 -231.551734)
			)
		)
	)
	(zone
		(layer "In4.Cu")
		(hatch none 0.5)
		(connect_pads
			(clearance 0)
		)
		(min_thickness 0.25)
		(keepout
			(tracks allowed)
			(vias allowed)
			(pads allowed)
			(copperpour allowed)
			(footprints allowed)
		)
		(placement
			(enabled no)
			(sheetname "")
		)
		(fill
			(thermal_gap 0.5)
			(thermal_bridge_width 0.5)
			(island_removal_mode 0)
		)
		(polygon
			(pts
				(xy 187.62853 -241.757454) (xy 187.62853 -240.402618) (xy 188.105796 -240.402618) (xy 188.105796 -241.757454)
			)
		)
	)
	(zone
		(layer "In4.Cu")
		(hatch none 0.5)
		(connect_pads
			(clearance 0)
		)
		(min_thickness 0.25)
		(keepout
			(tracks allowed)
			(vias allowed)
			(pads allowed)
			(copperpour allowed)
			(footprints allowed)
		)
		(placement
			(enabled no)
			(sheetname "")
		)
		(fill
			(thermal_gap 0.5)
			(thermal_bridge_width 0.5)
			(island_removal_mode 0)
		)
		(polygon
			(pts
				(xy 307.430932 -195.796916) (xy 307.430932 -194.521836) (xy 308.083712 -194.521836) (xy 308.083712 -195.796916)
			)
		)
	)
	(zone
		(layer "In4.Cu")
		(hatch none 0.5)
		(connect_pads
			(clearance 0)
		)
		(min_thickness 0.25)
		(keepout
			(tracks allowed)
			(vias allowed)
			(pads allowed)
			(copperpour allowed)
			(footprints allowed)
		)
		(placement
			(enabled no)
			(sheetname "")
		)
		(fill
			(thermal_gap 0.5)
			(thermal_bridge_width 0.5)
			(island_removal_mode 0)
		)
		(polygon
			(pts
				(xy 298.77893 -288.478976) (xy 298.77893 -287.12414) (xy 299.256196 -287.12414) (xy 299.256196 -288.478976)
			)
		)
	)
	(zone
		(layer "In4.Cu")
		(hatch none 0.5)
		(connect_pads
			(clearance 0)
		)
		(min_thickness 0.25)
		(keepout
			(tracks allowed)
			(vias allowed)
			(pads allowed)
			(copperpour allowed)
			(footprints allowed)
		)
		(placement
			(enabled no)
			(sheetname "")
		)
		(fill
			(thermal_gap 0.5)
			(thermal_bridge_width 0.5)
			(island_removal_mode 0)
		)
		(polygon
			(pts
				(xy 61.769752 -245.106698) (xy 61.769752 -242.929918) (xy 62.392052 -242.929918) (xy 62.392052 -245.106698)
			)
		)
	)
	(zone
		(layer "In4.Cu")
		(hatch none 0.5)
		(connect_pads
			(clearance 0)
		)
		(min_thickness 0.25)
		(keepout
			(tracks allowed)
			(vias allowed)
			(pads allowed)
			(copperpour allowed)
			(footprints allowed)
		)
		(placement
			(enabled no)
			(sheetname "")
		)
		(fill
			(thermal_gap 0.5)
			(thermal_bridge_width 0.5)
			(island_removal_mode 0)
		)
		(polygon
			(pts
				(xy 35.760914 -262.598154) (xy 35.760914 -261.243318) (xy 36.23818 -261.243318) (xy 36.23818 -262.598154)
			)
		)
	)
	(zone
		(layer "In4.Cu")
		(hatch none 0.5)
		(connect_pads
			(clearance 0)
		)
		(min_thickness 0.25)
		(keepout
			(tracks allowed)
			(vias allowed)
			(pads allowed)
			(copperpour allowed)
			(footprints allowed)
		)
		(placement
			(enabled no)
			(sheetname "")
		)
		(fill
			(thermal_gap 0.5)
			(thermal_bridge_width 0.5)
			(island_removal_mode 0)
		)
		(polygon
			(pts
				(xy 50.845974 -306.626514) (xy 50.845974 -305.271678) (xy 51.32324 -305.271678) (xy 51.32324 -306.626514)
			)
		)
	)
	(zone
		(layer "In4.Cu")
		(hatch none 0.5)
		(connect_pads
			(clearance 0)
		)
		(min_thickness 0.25)
		(keepout
			(tracks allowed)
			(vias allowed)
			(pads allowed)
			(copperpour allowed)
			(footprints allowed)
		)
		(placement
			(enabled no)
			(sheetname "")
		)
		(fill
			(thermal_gap 0.5)
			(thermal_bridge_width 0.5)
			(island_removal_mode 0)
		)
		(polygon
			(pts
				(xy 299.92066 -287.636458) (xy 299.92066 -285.439358) (xy 300.52772 -285.439358) (xy 300.52772 -287.636458)
			)
		)
	)
	(zone
		(layer "In4.Cu")
		(hatch none 0.5)
		(connect_pads
			(clearance 0)
		)
		(min_thickness 0.25)
		(keepout
			(tracks allowed)
			(vias allowed)
			(pads allowed)
			(copperpour allowed)
			(footprints allowed)
		)
		(placement
			(enabled no)
			(sheetname "")
		)
		(fill
			(thermal_gap 0.5)
			(thermal_bridge_width 0.5)
			(island_removal_mode 0)
		)
		(polygon
			(pts
				(xy 420.50081 -225.60153) (xy 420.50081 -224.246694) (xy 420.978076 -224.246694) (xy 420.978076 -225.60153)
			)
		)
	)
	(zone
		(layer "In4.Cu")
		(hatch none 0.5)
		(connect_pads
			(clearance 0)
		)
		(min_thickness 0.25)
		(keepout
			(tracks allowed)
			(vias allowed)
			(pads allowed)
			(copperpour allowed)
			(footprints allowed)
		)
		(placement
			(enabled no)
			(sheetname "")
		)
		(fill
			(thermal_gap 0.5)
			(thermal_bridge_width 0.5)
			(island_removal_mode 0)
		)
		(polygon
			(pts
				(xy 109.875066 -355.589332) (xy 111.246666 -355.589332) (xy 111.665766 -356.008432) (xy 111.665766 -356.264972)
				(xy 111.378746 -356.551992) (xy 110.177326 -356.551992) (xy 109.875066 -356.854252) (xy 109.875066 -362.239052)
				(xy 109.285786 -362.828332) (xy 109.285786 -365.497872) (xy 108.841286 -365.942372) (xy 108.841286 -367.072672)
				(xy 108.660946 -367.253012) (xy 107.581446 -367.253012) (xy 107.411266 -367.082832) (xy 107.411266 -366.287812)
				(xy 108.564426 -365.134652) (xy 108.564426 -362.480352) (xy 109.082586 -361.962192) (xy 109.082586 -356.407212)
				(xy 109.069886 -356.394512)
			)
		)
	)
	(zone
		(layer "In4.Cu")
		(hatch none 0.5)
		(connect_pads
			(clearance 0)
		)
		(min_thickness 0.25)
		(keepout
			(tracks allowed)
			(vias allowed)
			(pads allowed)
			(copperpour allowed)
			(footprints allowed)
		)
		(placement
			(enabled no)
			(sheetname "")
		)
		(fill
			(thermal_gap 0.5)
			(thermal_bridge_width 0.5)
			(island_removal_mode 0)
		)
		(polygon
			(pts
				(xy 65.815464 -232.398316) (xy 65.815464 -223.406716) (xy 66.417444 -223.406716) (xy 66.417444 -232.398316)
			)
		)
	)
	(zone
		(layer "In4.Cu")
		(hatch none 0.5)
		(connect_pads
			(clearance 0)
		)
		(min_thickness 0.25)
		(keepout
			(tracks allowed)
			(vias allowed)
			(pads allowed)
			(copperpour allowed)
			(footprints allowed)
		)
		(placement
			(enabled no)
			(sheetname "")
		)
		(fill
			(thermal_gap 0.5)
			(thermal_bridge_width 0.5)
			(island_removal_mode 0)
		)
		(polygon
			(pts
				(xy 420.50081 -272.351754) (xy 420.50081 -270.996918) (xy 420.978076 -270.996918) (xy 420.978076 -272.351754)
			)
		)
	)
	(zone
		(layer "In4.Cu")
		(hatch none 0.5)
		(connect_pads
			(clearance 0)
		)
		(min_thickness 0.25)
		(keepout
			(tracks allowed)
			(vias allowed)
			(pads allowed)
			(copperpour allowed)
			(footprints allowed)
		)
		(placement
			(enabled no)
			(sheetname "")
		)
		(fill
			(thermal_gap 0.5)
			(thermal_bridge_width 0.5)
			(island_removal_mode 0)
		)
		(polygon
			(pts
				(xy 284.895036 -319.101978) (xy 284.895036 -317.747142) (xy 285.372302 -317.747142) (xy 285.372302 -319.101978)
			)
		)
	)
	(zone
		(layer "In4.Cu")
		(hatch none 0.5)
		(connect_pads
			(clearance 0)
		)
		(min_thickness 0.25)
		(keepout
			(tracks allowed)
			(vias allowed)
			(pads allowed)
			(copperpour allowed)
			(footprints allowed)
		)
		(placement
			(enabled no)
			(sheetname "")
		)
		(fill
			(thermal_gap 0.5)
			(thermal_bridge_width 0.5)
			(island_removal_mode 0)
		)
		(polygon
			(pts
				(xy 172.54093 -305.50739) (xy 172.54093 -304.152554) (xy 173.018196 -304.152554) (xy 173.018196 -305.50739)
			)
		)
	)
	(zone
		(layer "In4.Cu")
		(hatch none 0.5)
		(connect_pads
			(clearance 0)
		)
		(min_thickness 0.25)
		(keepout
			(tracks allowed)
			(vias allowed)
			(pads allowed)
			(copperpour allowed)
			(footprints allowed)
		)
		(placement
			(enabled no)
			(sheetname "")
		)
		(fill
			(thermal_gap 0.5)
			(thermal_bridge_width 0.5)
			(island_removal_mode 0)
		)
		(polygon
			(pts
				(xy 283.63291 -291.882576) (xy 283.63291 -290.52774) (xy 284.110176 -290.52774) (xy 284.110176 -291.882576)
			)
		)
	)
	(zone
		(layer "In4.Cu")
		(hatch none 0.5)
		(connect_pads
			(clearance 0)
		)
		(min_thickness 0.25)
		(keepout
			(tracks allowed)
			(vias allowed)
			(pads allowed)
			(copperpour allowed)
			(footprints allowed)
		)
		(placement
			(enabled no)
			(sheetname "")
		)
		(fill
			(thermal_gap 0.5)
			(thermal_bridge_width 0.5)
			(island_removal_mode 0)
		)
		(polygon
			(pts
				(xy 435.568598 -206.907384) (xy 435.568598 -205.552548) (xy 436.045864 -205.552548) (xy 436.045864 -206.907384)
			)
		)
	)
	(zone
		(layer "In4.Cu")
		(hatch none 0.5)
		(connect_pads
			(clearance 0)
		)
		(min_thickness 0.25)
		(keepout
			(tracks allowed)
			(vias allowed)
			(pads allowed)
			(copperpour allowed)
			(footprints allowed)
		)
		(placement
			(enabled no)
			(sheetname "")
		)
		(fill
			(thermal_gap 0.5)
			(thermal_bridge_width 0.5)
			(island_removal_mode 0)
		)
		(polygon
			(pts
				(xy 283.66339 -251.534676) (xy 283.66339 -250.17984) (xy 284.140656 -250.17984) (xy 284.140656 -251.534676)
			)
		)
	)
	(zone
		(layer "In4.Cu")
		(hatch none 0.5)
		(connect_pads
			(clearance 0)
		)
		(min_thickness 0.25)
		(keepout
			(tracks allowed)
			(vias allowed)
			(pads allowed)
			(copperpour allowed)
			(footprints allowed)
		)
		(placement
			(enabled no)
			(sheetname "")
		)
		(fill
			(thermal_gap 0.5)
			(thermal_bridge_width 0.5)
			(island_removal_mode 0)
		)
		(polygon
			(pts
				(xy 187.62853 -265.557508) (xy 187.62853 -264.202672) (xy 188.105796 -264.202672) (xy 188.105796 -265.557508)
			)
		)
	)
	(zone
		(layer "In4.Cu")
		(hatch none 0.5)
		(connect_pads
			(clearance 0)
		)
		(min_thickness 0.25)
		(keepout
			(tracks allowed)
			(vias allowed)
			(pads allowed)
			(copperpour allowed)
			(footprints allowed)
		)
		(placement
			(enabled no)
			(sheetname "")
		)
		(fill
			(thermal_gap 0.5)
			(thermal_bridge_width 0.5)
			(island_removal_mode 0)
		)
		(polygon
			(pts
				(xy 35.713162 -248.642378) (xy 35.713162 -248.017792) (xy 36.190428 -248.017792) (xy 36.496498 -248.017792)
				(xy 36.56838 -248.089674) (xy 36.56838 -248.55678) (xy 36.482782 -248.642378) (xy 36.190428 -248.642378)
			)
		)
	)
	(zone
		(layer "In4.Cu")
		(hatch none 0.5)
		(connect_pads
			(clearance 0)
		)
		(min_thickness 0.25)
		(keepout
			(tracks allowed)
			(vias allowed)
			(pads allowed)
			(copperpour allowed)
			(footprints allowed)
		)
		(placement
			(enabled no)
			(sheetname "")
		)
		(fill
			(thermal_gap 0.5)
			(thermal_bridge_width 0.5)
			(island_removal_mode 0)
		)
		(polygon
			(pts
				(xy 435.538372 -213.711282) (xy 435.538372 -212.356446) (xy 436.015638 -212.356446) (xy 436.015638 -213.711282)
			)
		)
	)
	(zone
		(layer "In4.Cu")
		(hatch none 0.5)
		(connect_pads
			(clearance 0)
		)
		(min_thickness 0.25)
		(keepout
			(tracks allowed)
			(vias allowed)
			(pads allowed)
			(copperpour allowed)
			(footprints allowed)
		)
		(placement
			(enabled no)
			(sheetname "")
		)
		(fill
			(thermal_gap 0.5)
			(thermal_bridge_width 0.5)
			(island_removal_mode 0)
		)
		(polygon
			(pts
				(xy 20.34032 -383.96164) (xy 20.34032 -383.23012) (xy 22.62378 -383.23012) (xy 22.62378 -383.96164)
			)
		)
	)
	(zone
		(layer "In4.Cu")
		(hatch none 0.5)
		(connect_pads
			(clearance 0)
		)
		(min_thickness 0.25)
		(keepout
			(tracks allowed)
			(vias allowed)
			(pads allowed)
			(copperpour allowed)
			(footprints allowed)
		)
		(placement
			(enabled no)
			(sheetname "")
		)
		(fill
			(thermal_gap 0.5)
			(thermal_bridge_width 0.5)
			(island_removal_mode 0)
		)
		(polygon
			(pts
				(xy 157.42793 -244.30736) (xy 157.42793 -242.952524) (xy 157.905196 -242.952524) (xy 157.905196 -244.30736)
			)
		)
	)
	(zone
		(layer "In4.Cu")
		(hatch none 0.5)
		(connect_pads
			(clearance 0)
		)
		(min_thickness 0.25)
		(keepout
			(tracks allowed)
			(vias allowed)
			(pads allowed)
			(copperpour allowed)
			(footprints allowed)
		)
		(placement
			(enabled no)
			(sheetname "")
		)
		(fill
			(thermal_gap 0.5)
			(thermal_bridge_width 0.5)
			(island_removal_mode 0)
		)
		(polygon
			(pts
				(xy 283.66593 -314.574936) (xy 283.66593 -313.2201) (xy 284.143196 -313.2201) (xy 284.143196 -314.574936)
			)
		)
	)
	(zone
		(layer "In4.Cu")
		(hatch none 0.5)
		(connect_pads
			(clearance 0)
		)
		(min_thickness 0.25)
		(keepout
			(tracks allowed)
			(vias allowed)
			(pads allowed)
			(copperpour allowed)
			(footprints allowed)
		)
		(placement
			(enabled no)
			(sheetname "")
		)
		(fill
			(thermal_gap 0.5)
			(thermal_bridge_width 0.5)
			(island_removal_mode 0)
		)
		(polygon
			(pts
				(xy 435.578504 -308.00802) (xy 435.578504 -306.653184) (xy 436.05577 -306.653184) (xy 436.05577 -308.00802)
			)
		)
	)
	(zone
		(layer "In4.Cu")
		(hatch none 0.5)
		(connect_pads
			(clearance 0)
		)
		(min_thickness 0.25)
		(keepout
			(tracks allowed)
			(vias allowed)
			(pads allowed)
			(copperpour allowed)
			(footprints allowed)
		)
		(placement
			(enabled no)
			(sheetname "")
		)
		(fill
			(thermal_gap 0.5)
			(thermal_bridge_width 0.5)
			(island_removal_mode 0)
		)
		(polygon
			(pts
				(xy 187.62853 -296.157396) (xy 187.62853 -294.80256) (xy 188.105796 -294.80256) (xy 188.105796 -296.157396)
			)
		)
	)
	(zone
		(layer "In4.Cu")
		(hatch none 0.5)
		(connect_pads
			(clearance 0)
		)
		(min_thickness 0.25)
		(keepout
			(tracks allowed)
			(vias allowed)
			(pads allowed)
			(copperpour allowed)
			(footprints allowed)
		)
		(placement
			(enabled no)
			(sheetname "")
		)
		(fill
			(thermal_gap 0.5)
			(thermal_bridge_width 0.5)
			(island_removal_mode 0)
		)
		(polygon
			(pts
				(xy 35.765994 -208.597754) (xy 35.765994 -207.242918) (xy 36.24326 -207.242918) (xy 36.24326 -208.597754)
			)
		)
	)
	(zone
		(layer "In4.Cu")
		(hatch none 0.5)
		(connect_pads
			(clearance 0)
		)
		(min_thickness 0.25)
		(keepout
			(tracks allowed)
			(vias allowed)
			(pads allowed)
			(copperpour allowed)
			(footprints allowed)
		)
		(placement
			(enabled no)
			(sheetname "")
		)
		(fill
			(thermal_gap 0.5)
			(thermal_bridge_width 0.5)
			(island_removal_mode 0)
		)
		(polygon
			(pts
				(xy 61.838332 -233.171238) (xy 61.838332 -223.349058) (xy 62.315852 -223.349058) (xy 62.315852 -233.171238)
			)
		)
	)
	(zone
		(layer "In4.Cu")
		(hatch none 0.5)
		(connect_pads
			(clearance 0)
		)
		(min_thickness 0.25)
		(keepout
			(tracks allowed)
			(vias allowed)
			(pads allowed)
			(copperpour allowed)
			(footprints allowed)
		)
		(placement
			(enabled no)
			(sheetname "")
		)
		(fill
			(thermal_gap 0.5)
			(thermal_bridge_width 0.5)
			(island_removal_mode 0)
		)
		(polygon
			(pts
				(xy 283.64815 -240.922556) (xy 283.64815 -239.56772) (xy 284.125416 -239.56772) (xy 284.125416 -240.922556)
			)
		)
	)
	(zone
		(layer "In4.Cu")
		(hatch none 0.5)
		(connect_pads
			(clearance 0)
		)
		(min_thickness 0.25)
		(keepout
			(tracks allowed)
			(vias allowed)
			(pads allowed)
			(copperpour allowed)
			(footprints allowed)
		)
		(placement
			(enabled no)
			(sheetname "")
		)
		(fill
			(thermal_gap 0.5)
			(thermal_bridge_width 0.5)
			(island_removal_mode 0)
		)
		(polygon
			(pts
				(xy 279.56637 -246.048276) (xy 279.56637 -244.69344) (xy 280.043636 -244.69344) (xy 280.043636 -246.048276)
			)
		)
	)
	(zone
		(layer "In4.Cu")
		(hatch none 0.5)
		(connect_pads
			(clearance 0)
		)
		(min_thickness 0.25)
		(keepout
			(tracks allowed)
			(vias allowed)
			(pads allowed)
			(copperpour allowed)
			(footprints allowed)
		)
		(placement
			(enabled no)
			(sheetname "")
		)
		(fill
			(thermal_gap 0.5)
			(thermal_bridge_width 0.5)
			(island_removal_mode 0)
		)
		(polygon
			(pts
				(xy 35.712654 -291.876734) (xy 35.712654 -290.521898) (xy 36.18992 -290.521898) (xy 36.18992 -291.876734)
			)
		)
	)
	(zone
		(layer "In4.Cu")
		(hatch none 0.5)
		(connect_pads
			(clearance 0)
		)
		(min_thickness 0.25)
		(keepout
			(tracks allowed)
			(vias allowed)
			(pads allowed)
			(copperpour allowed)
			(footprints allowed)
		)
		(placement
			(enabled no)
			(sheetname "")
		)
		(fill
			(thermal_gap 0.5)
			(thermal_bridge_width 0.5)
			(island_removal_mode 0)
		)
		(polygon
			(pts
				(xy 172.54093 -199.257412) (xy 172.54093 -197.902576) (xy 173.018196 -197.902576) (xy 173.018196 -199.257412)
			)
		)
	)
	(zone
		(layer "In4.Cu")
		(hatch none 0.5)
		(connect_pads
			(clearance 0)
		)
		(min_thickness 0.25)
		(keepout
			(tracks allowed)
			(vias allowed)
			(pads allowed)
			(copperpour allowed)
			(footprints allowed)
		)
		(placement
			(enabled no)
			(sheetname "")
		)
		(fill
			(thermal_gap 0.5)
			(thermal_bridge_width 0.5)
			(island_removal_mode 0)
		)
		(polygon
			(pts
				(xy 187.62853 -293.62908) (xy 187.62853 -291.40277) (xy 188.105796 -291.40277) (xy 188.105796 -293.62908)
			)
		)
	)
	(zone
		(layer "In4.Cu")
		(hatch none 0.5)
		(connect_pads
			(clearance 0)
		)
		(min_thickness 0.25)
		(keepout
			(tracks allowed)
			(vias allowed)
			(pads allowed)
			(copperpour allowed)
			(footprints allowed)
		)
		(placement
			(enabled no)
			(sheetname "")
		)
		(fill
			(thermal_gap 0.5)
			(thermal_bridge_width 0.5)
			(island_removal_mode 0)
		)
		(polygon
			(pts
				(xy 172.560742 -302.951642) (xy 172.560742 -301.743872) (xy 171.614338 -301.743872) (xy 171.614338 -300.737778)
				(xy 172.560742 -300.737778) (xy 173.038008 -300.737778) (xy 173.038008 -302.951642)
			)
		)
	)
	(zone
		(layer "In4.Cu")
		(hatch none 0.5)
		(connect_pads
			(clearance 0)
		)
		(min_thickness 0.25)
		(keepout
			(tracks allowed)
			(vias allowed)
			(pads allowed)
			(copperpour allowed)
			(footprints allowed)
		)
		(placement
			(enabled no)
			(sheetname "")
		)
		(fill
			(thermal_gap 0.5)
			(thermal_bridge_width 0.5)
			(island_removal_mode 0)
		)
		(polygon
			(pts
				(xy 187.648342 -289.35172) (xy 187.648342 -287.996884) (xy 188.125608 -287.996884) (xy 188.125608 -289.35172)
			)
		)
	)
	(zone
		(layer "In4.Cu")
		(hatch none 0.5)
		(connect_pads
			(clearance 0)
		)
		(min_thickness 0.25)
		(keepout
			(tracks allowed)
			(vias allowed)
			(pads allowed)
			(copperpour allowed)
			(footprints allowed)
		)
		(placement
			(enabled no)
			(sheetname "")
		)
		(fill
			(thermal_gap 0.5)
			(thermal_bridge_width 0.5)
			(island_removal_mode 0)
		)
		(polygon
			(pts
				(xy 298.786042 -302.234854) (xy 298.786042 -300.880018) (xy 299.263308 -300.880018) (xy 299.263308 -302.234854)
			)
		)
	)
	(zone
		(layer "In4.Cu")
		(hatch none 0.5)
		(connect_pads
			(clearance 0)
		)
		(min_thickness 0.25)
		(keepout
			(tracks allowed)
			(vias allowed)
			(pads allowed)
			(copperpour allowed)
			(footprints allowed)
		)
		(placement
			(enabled no)
			(sheetname "")
		)
		(fill
			(thermal_gap 0.5)
			(thermal_bridge_width 0.5)
			(island_removal_mode 0)
		)
		(polygon
			(pts
				(xy 144.074896 -281.669744) (xy 141.297406 -284.447234) (xy 140.677646 -284.447234) (xy 138.798046 -282.567888)
				(xy 138.798046 -281.940508) (xy 139.074906 -281.663648) (xy 139.074906 -281.44343) (xy 139.820396 -280.69794)
				(xy 139.820396 -280.625804) (xy 139.403836 -280.209244) (xy 139.403328 -280.209244) (xy 139.403328 -280.186384)
				(xy 140.319506 -279.269952) (xy 140.860526 -278.728932) (xy 140.860526 -278.657304) (xy 140.857478 -278.657304)
				(xy 140.834364 -278.63419) (xy 140.835888 -278.632666) (xy 139.566904 -277.363682) (xy 139.566904 -277.346156)
				(xy 139.968986 -276.944074) (xy 139.968986 -276.91461) (xy 139.24788 -276.193504) (xy 139.24788 -276.14753)
				(xy 139.848082 -275.547328) (xy 139.946126 -275.645372) (xy 140.944346 -276.643592) (xy 141.045946 -276.745192)
				(xy 145.003266 -280.702512) (xy 145.003266 -280.741374)
			)
		)
	)
	(zone
		(layer "In4.Cu")
		(hatch none 0.5)
		(connect_pads
			(clearance 0)
		)
		(min_thickness 0.25)
		(keepout
			(tracks allowed)
			(vias allowed)
			(pads allowed)
			(copperpour allowed)
			(footprints allowed)
		)
		(placement
			(enabled no)
			(sheetname "")
		)
		(fill
			(thermal_gap 0.5)
			(thermal_bridge_width 0.5)
			(island_removal_mode 0)
		)
		(polygon
			(pts
				(xy 283.68117 -262.603996) (xy 283.68117 -261.24916) (xy 284.158436 -261.24916) (xy 284.158436 -262.603996)
			)
		)
	)
	(zone
		(layer "In4.Cu")
		(hatch none 0.5)
		(connect_pads
			(clearance 0)
		)
		(min_thickness 0.25)
		(keepout
			(tracks allowed)
			(vias allowed)
			(pads allowed)
			(copperpour allowed)
			(footprints allowed)
		)
		(placement
			(enabled no)
			(sheetname "")
		)
		(fill
			(thermal_gap 0.5)
			(thermal_bridge_width 0.5)
			(island_removal_mode 0)
		)
		(polygon
			(pts
				(xy 435.58841 -251.101606) (xy 435.58841 -249.74677) (xy 436.065676 -249.74677) (xy 436.065676 -251.101606)
			)
		)
	)
	(zone
		(layer "In4.Cu")
		(hatch none 0.5)
		(connect_pads
			(clearance 0)
		)
		(min_thickness 0.25)
		(keepout
			(tracks allowed)
			(vias allowed)
			(pads allowed)
			(copperpour allowed)
			(footprints allowed)
		)
		(placement
			(enabled no)
			(sheetname "")
		)
		(fill
			(thermal_gap 0.5)
			(thermal_bridge_width 0.5)
			(island_removal_mode 0)
		)
		(polygon
			(pts
				(xy 420.480998 -272.357596) (xy 420.480998 -271.00276) (xy 420.958264 -271.00276) (xy 420.958264 -272.357596)
			)
		)
	)
	(zone
		(layer "In4.Cu")
		(hatch none 0.5)
		(connect_pads
			(clearance 0)
		)
		(min_thickness 0.25)
		(keepout
			(tracks allowed)
			(vias allowed)
			(pads allowed)
			(copperpour allowed)
			(footprints allowed)
		)
		(placement
			(enabled no)
			(sheetname "")
		)
		(fill
			(thermal_gap 0.5)
			(thermal_bridge_width 0.5)
			(island_removal_mode 0)
		)
		(polygon
			(pts
				(xy 50.762662 -197.582536) (xy 50.762662 -196.2277) (xy 51.239928 -196.2277) (xy 51.239928 -197.582536)
			)
		)
	)
	(zone
		(layer "In4.Cu")
		(hatch none 0.5)
		(connect_pads
			(clearance 0)
		)
		(min_thickness 0.25)
		(keepout
			(tracks allowed)
			(vias allowed)
			(pads allowed)
			(copperpour allowed)
			(footprints allowed)
		)
		(placement
			(enabled no)
			(sheetname "")
		)
		(fill
			(thermal_gap 0.5)
			(thermal_bridge_width 0.5)
			(island_removal_mode 0)
		)
		(polygon
			(pts
				(xy 296.519092 -268.077696) (xy 296.519092 -265.946636) (xy 297.032172 -265.946636) (xy 297.032172 -268.077696)
			)
		)
	)
	(zone
		(layer "In4.Cu")
		(hatch none 0.5)
		(connect_pads
			(clearance 0)
		)
		(min_thickness 0.25)
		(keepout
			(tracks allowed)
			(vias allowed)
			(pads allowed)
			(copperpour allowed)
			(footprints allowed)
		)
		(placement
			(enabled no)
			(sheetname "")
		)
		(fill
			(thermal_gap 0.5)
			(thermal_bridge_width 0.5)
			(island_removal_mode 0)
		)
		(polygon
			(pts
				(xy 31.621222 -269.832836) (xy 31.621222 -268.478) (xy 32.098488 -268.478) (xy 32.098488 -269.832836)
			)
		)
	)
	(zone
		(layer "In4.Cu")
		(hatch none 0.5)
		(connect_pads
			(clearance 0)
		)
		(min_thickness 0.25)
		(keepout
			(tracks allowed)
			(vias allowed)
			(pads allowed)
			(copperpour allowed)
			(footprints allowed)
		)
		(placement
			(enabled no)
			(sheetname "")
		)
		(fill
			(thermal_gap 0.5)
			(thermal_bridge_width 0.5)
			(island_removal_mode 0)
		)
		(polygon
			(pts
				(xy 96.32188 -335.521808) (xy 96.32188 -334.068928) (xy 98.01098 -334.068928) (xy 98.01098 -335.521808)
			)
		)
	)
	(zone
		(layer "In4.Cu")
		(hatch none 0.5)
		(connect_pads
			(clearance 0)
		)
		(min_thickness 0.25)
		(keepout
			(tracks allowed)
			(vias allowed)
			(pads allowed)
			(copperpour allowed)
			(footprints allowed)
		)
		(placement
			(enabled no)
			(sheetname "")
		)
		(fill
			(thermal_gap 0.5)
			(thermal_bridge_width 0.5)
			(island_removal_mode 0)
		)
		(polygon
			(pts
				(xy 298.75607 -300.625256) (xy 298.75607 -299.27042) (xy 299.233336 -299.27042) (xy 299.233336 -300.625256)
			)
		)
	)
	(zone
		(layer "In4.Cu")
		(hatch none 0.5)
		(connect_pads
			(clearance 0)
		)
		(min_thickness 0.25)
		(keepout
			(tracks allowed)
			(vias allowed)
			(pads allowed)
			(copperpour allowed)
			(footprints allowed)
		)
		(placement
			(enabled no)
			(sheetname "")
		)
		(fill
			(thermal_gap 0.5)
			(thermal_bridge_width 0.5)
			(island_removal_mode 0)
		)
		(polygon
			(pts
				(xy 283.667962 -240.916714) (xy 283.667962 -239.561878) (xy 284.145228 -239.561878) (xy 284.145228 -240.916714)
			)
		)
	)
	(zone
		(layer "In4.Cu")
		(hatch none 0.5)
		(connect_pads
			(clearance 0)
		)
		(min_thickness 0.25)
		(keepout
			(tracks allowed)
			(vias allowed)
			(pads allowed)
			(copperpour allowed)
			(footprints allowed)
		)
		(placement
			(enabled no)
			(sheetname "")
		)
		(fill
			(thermal_gap 0.5)
			(thermal_bridge_width 0.5)
			(island_removal_mode 0)
		)
		(polygon
			(pts
				(xy 218.45778 -15.96898) (xy 218.45778 -14.89456) (xy 220.0656 -14.89456) (xy 220.0656 -15.96898)
			)
		)
	)
	(zone
		(layer "In4.Cu")
		(hatch none 0.5)
		(connect_pads
			(clearance 0)
		)
		(min_thickness 0.25)
		(keepout
			(tracks allowed)
			(vias allowed)
			(pads allowed)
			(copperpour allowed)
			(footprints allowed)
		)
		(placement
			(enabled no)
			(sheetname "")
		)
		(fill
			(thermal_gap 0.5)
			(thermal_bridge_width 0.5)
			(island_removal_mode 0)
		)
		(polygon
			(pts
				(xy 50.858674 -303.857914) (xy 50.858674 -302.503078) (xy 51.33594 -302.503078) (xy 51.33594 -303.857914)
			)
		)
	)
	(zone
		(layer "In4.Cu")
		(hatch none 0.5)
		(connect_pads
			(clearance 0)
		)
		(min_thickness 0.25)
		(keepout
			(tracks allowed)
			(vias allowed)
			(pads allowed)
			(copperpour allowed)
			(footprints allowed)
		)
		(placement
			(enabled no)
			(sheetname "")
		)
		(fill
			(thermal_gap 0.5)
			(thermal_bridge_width 0.5)
			(island_removal_mode 0)
		)
		(polygon
			(pts
				(xy 173.018196 -300.407578) (xy 172.54093 -300.407578) (xy 172.134784 -300.407578) (xy 172.134784 -299.82033)
				(xy 170.913806 -299.82033) (xy 170.913806 -298.327318) (xy 170.913806 -297.958764) (xy 171.025312 -297.847258)
				(xy 171.97705 -297.847258) (xy 173.245018 -297.847258) (xy 173.245018 -298.194476) (xy 173.245018 -298.684188)
				(xy 173.245018 -300.407578)
			)
		)
	)
	(zone
		(layer "In4.Cu")
		(hatch none 0.5)
		(connect_pads
			(clearance 0)
		)
		(min_thickness 0.25)
		(keepout
			(tracks allowed)
			(vias allowed)
			(pads allowed)
			(copperpour allowed)
			(footprints allowed)
		)
		(placement
			(enabled no)
			(sheetname "")
		)
		(fill
			(thermal_gap 0.5)
			(thermal_bridge_width 0.5)
			(island_removal_mode 0)
		)
		(polygon
			(pts
				(xy 381.381 -347.802708) (xy 381.381 -343.708228) (xy 386.74548 -343.708228) (xy 386.74548 -347.802708)
			)
		)
	)
	(zone
		(layer "In4.Cu")
		(hatch none 0.5)
		(connect_pads
			(clearance 0)
		)
		(min_thickness 0.25)
		(keepout
			(tracks allowed)
			(vias allowed)
			(pads allowed)
			(copperpour allowed)
			(footprints allowed)
		)
		(placement
			(enabled no)
			(sheetname "")
		)
		(fill
			(thermal_gap 0.5)
			(thermal_bridge_width 0.5)
			(island_removal_mode 0)
		)
		(polygon
			(pts
				(xy 126.02718 -342.438228) (xy 126.02718 -339.329268) (xy 133.69798 -339.329268) (xy 133.69798 -342.438228)
			)
		)
	)
	(zone
		(layer "In4.Cu")
		(hatch none 0.5)
		(connect_pads
			(clearance 0)
		)
		(min_thickness 0.25)
		(keepout
			(tracks allowed)
			(vias allowed)
			(pads allowed)
			(copperpour allowed)
			(footprints allowed)
		)
		(placement
			(enabled no)
			(sheetname "")
		)
		(fill
			(thermal_gap 0.5)
			(thermal_bridge_width 0.5)
			(island_removal_mode 0)
		)
		(polygon
			(pts
				(xy 420.50081 -287.651698) (xy 420.50081 -286.296862) (xy 420.978076 -286.296862) (xy 420.978076 -287.651698)
				(xy 421.265858 -287.651698) (xy 421.265858 -289.019742) (xy 420.977822 -289.019742) (xy 420.096442 -289.019742)
				(xy 420.096442 -287.651698) (xy 420.34333 -287.651698)
			)
		)
	)
	(zone
		(layer "In4.Cu")
		(hatch none 0.5)
		(connect_pads
			(clearance 0)
		)
		(min_thickness 0.25)
		(keepout
			(tracks allowed)
			(vias allowed)
			(pads allowed)
			(copperpour allowed)
			(footprints allowed)
		)
		(placement
			(enabled no)
			(sheetname "")
		)
		(fill
			(thermal_gap 0.5)
			(thermal_bridge_width 0.5)
			(island_removal_mode 0)
		)
		(polygon
			(pts
				(xy 352.23704 -335.415128) (xy 352.23704 -333.860648) (xy 353.72548 -333.860648) (xy 353.72548 -335.415128)
			)
		)
	)
	(zone
		(layer "In4.Cu")
		(hatch none 0.5)
		(connect_pads
			(clearance 0)
		)
		(min_thickness 0.25)
		(keepout
			(tracks allowed)
			(vias allowed)
			(pads allowed)
			(copperpour allowed)
			(footprints allowed)
		)
		(placement
			(enabled no)
			(sheetname "")
		)
		(fill
			(thermal_gap 0.5)
			(thermal_bridge_width 0.5)
			(island_removal_mode 0)
		)
		(polygon
			(pts
				(xy 294.64762 -259.577078) (xy 294.64762 -258.322318) (xy 295.12514 -258.322318) (xy 295.12514 -259.577078)
			)
		)
	)
	(zone
		(layer "In4.Cu")
		(hatch none 0.5)
		(connect_pads
			(clearance 0)
		)
		(min_thickness 0.25)
		(keepout
			(tracks allowed)
			(vias allowed)
			(pads allowed)
			(copperpour allowed)
			(footprints allowed)
		)
		(placement
			(enabled no)
			(sheetname "")
		)
		(fill
			(thermal_gap 0.5)
			(thermal_bridge_width 0.5)
			(island_removal_mode 0)
		)
		(polygon
			(pts
				(xy 35.746182 -309.764176) (xy 35.746182 -308.40934) (xy 36.223448 -308.40934) (xy 36.223448 -309.764176)
			)
		)
	)
	(zone
		(layer "In4.Cu")
		(hatch none 0.5)
		(connect_pads
			(clearance 0)
		)
		(min_thickness 0.25)
		(keepout
			(tracks allowed)
			(vias allowed)
			(pads allowed)
			(copperpour allowed)
			(footprints allowed)
		)
		(placement
			(enabled no)
			(sheetname "")
		)
		(fill
			(thermal_gap 0.5)
			(thermal_bridge_width 0.5)
			(island_removal_mode 0)
		)
		(polygon
			(pts
				(xy 50.845974 -280.848054) (xy 50.845974 -279.493218) (xy 51.32324 -279.493218) (xy 51.32324 -280.848054)
			)
		)
	)
	(zone
		(layer "In4.Cu")
		(hatch none 0.5)
		(connect_pads
			(clearance 0)
		)
		(min_thickness 0.25)
		(keepout
			(tracks allowed)
			(vias allowed)
			(pads allowed)
			(copperpour allowed)
			(footprints allowed)
		)
		(placement
			(enabled no)
			(sheetname "")
		)
		(fill
			(thermal_gap 0.5)
			(thermal_bridge_width 0.5)
			(island_removal_mode 0)
		)
		(polygon
			(pts
				(xy 195.192142 -245.151656) (xy 195.192142 -243.79682) (xy 195.669408 -243.79682) (xy 195.669408 -245.151656)
			)
		)
	)
	(zone
		(layer "In4.Cu")
		(hatch none 0.5)
		(connect_pads
			(clearance 0)
		)
		(min_thickness 0.25)
		(keepout
			(tracks allowed)
			(vias allowed)
			(pads allowed)
			(copperpour allowed)
			(footprints allowed)
		)
		(placement
			(enabled no)
			(sheetname "")
		)
		(fill
			(thermal_gap 0.5)
			(thermal_bridge_width 0.5)
			(island_removal_mode 0)
		)
		(polygon
			(pts
				(xy 15.13586 -21.93544) (xy 15.13586 -20.84324) (xy 16.8783 -20.84324) (xy 16.8783 -21.93544)
			)
		)
	)
	(zone
		(layer "In4.Cu")
		(hatch none 0.5)
		(connect_pads
			(clearance 0)
		)
		(min_thickness 0.25)
		(keepout
			(tracks allowed)
			(vias allowed)
			(pads allowed)
			(copperpour allowed)
			(footprints allowed)
		)
		(placement
			(enabled no)
			(sheetname "")
		)
		(fill
			(thermal_gap 0.5)
			(thermal_bridge_width 0.5)
			(island_removal_mode 0)
		)
		(polygon
			(pts
				(xy 296.61866 -261.258558) (xy 296.61866 -258.304538) (xy 296.97426 -258.304538) (xy 296.97426 -261.258558)
			)
		)
	)
	(zone
		(layer "In4.Cu")
		(hatch none 0.5)
		(connect_pads
			(clearance 0)
		)
		(min_thickness 0.25)
		(keepout
			(tracks allowed)
			(vias allowed)
			(pads allowed)
			(copperpour allowed)
			(footprints allowed)
		)
		(placement
			(enabled no)
			(sheetname "")
		)
		(fill
			(thermal_gap 0.5)
			(thermal_bridge_width 0.5)
			(island_removal_mode 0)
		)
		(polygon
			(pts
				(xy 50.471578 -172.804328) (xy 50.471578 -171.678346) (xy 52.215542 -171.678346) (xy 52.215542 -172.804328)
			)
		)
	)
	(zone
		(layer "In4.Cu")
		(hatch none 0.5)
		(connect_pads
			(clearance 0)
		)
		(min_thickness 0.25)
		(keepout
			(tracks allowed)
			(vias allowed)
			(pads allowed)
			(copperpour allowed)
			(footprints allowed)
		)
		(placement
			(enabled no)
			(sheetname "")
		)
		(fill
			(thermal_gap 0.5)
			(thermal_bridge_width 0.5)
			(island_removal_mode 0)
		)
		(polygon
			(pts
				(xy 298.786042 -306.626514) (xy 298.786042 -305.271678) (xy 299.263308 -305.271678) (xy 299.263308 -306.626514)
			)
		)
	)
	(zone
		(layer "In4.Cu")
		(hatch none 0.5)
		(connect_pads
			(clearance 0)
		)
		(min_thickness 0.25)
		(keepout
			(tracks allowed)
			(vias allowed)
			(pads allowed)
			(copperpour allowed)
			(footprints allowed)
		)
		(placement
			(enabled no)
			(sheetname "")
		)
		(fill
			(thermal_gap 0.5)
			(thermal_bridge_width 0.5)
			(island_removal_mode 0)
		)
		(polygon
			(pts
				(xy 283.684726 -317.256414) (xy 283.684726 -316.00521) (xy 284.30982 -316.00521) (xy 284.30982 -317.256414)
			)
		)
	)
	(zone
		(layer "In4.Cu")
		(hatch none 0.5)
		(connect_pads
			(clearance 0)
		)
		(min_thickness 0.25)
		(keepout
			(tracks allowed)
			(vias allowed)
			(pads allowed)
			(copperpour allowed)
			(footprints allowed)
		)
		(placement
			(enabled no)
			(sheetname "")
		)
		(fill
			(thermal_gap 0.5)
			(thermal_bridge_width 0.5)
			(island_removal_mode 0)
		)
		(polygon
			(pts
				(xy 283.66593 -246.901716) (xy 283.66593 -245.54688) (xy 284.143196 -245.54688) (xy 284.143196 -246.901716)
			)
		)
	)
	(zone
		(layer "In4.Cu")
		(hatch none 0.5)
		(connect_pads
			(clearance 0)
		)
		(min_thickness 0.25)
		(keepout
			(tracks allowed)
			(vias allowed)
			(pads allowed)
			(copperpour allowed)
			(footprints allowed)
		)
		(placement
			(enabled no)
			(sheetname "")
		)
		(fill
			(thermal_gap 0.5)
			(thermal_bridge_width 0.5)
			(island_removal_mode 0)
		)
		(polygon
			(pts
				(xy 172.54093 -284.257496) (xy 172.54093 -282.0924) (xy 173.018196 -282.0924) (xy 173.018196 -284.257496)
			)
		)
	)
	(zone
		(layer "In4.Cu")
		(hatch none 0.5)
		(connect_pads
			(clearance 0)
		)
		(min_thickness 0.25)
		(keepout
			(tracks allowed)
			(vias allowed)
			(pads allowed)
			(copperpour allowed)
			(footprints allowed)
		)
		(placement
			(enabled no)
			(sheetname "")
		)
		(fill
			(thermal_gap 0.5)
			(thermal_bridge_width 0.5)
			(island_removal_mode 0)
		)
		(polygon
			(pts
				(xy 298.793662 -282.557474) (xy 298.793662 -281.202638) (xy 299.270928 -281.202638) (xy 299.270928 -282.557474)
			)
		)
	)
	(zone
		(layer "In4.Cu")
		(hatch none 0.5)
		(connect_pads
			(clearance 0)
		)
		(min_thickness 0.25)
		(keepout
			(tracks allowed)
			(vias allowed)
			(pads allowed)
			(copperpour allowed)
			(footprints allowed)
		)
		(placement
			(enabled no)
			(sheetname "")
		)
		(fill
			(thermal_gap 0.5)
			(thermal_bridge_width 0.5)
			(island_removal_mode 0)
		)
		(polygon
			(pts
				(xy 48.559212 -268.083538) (xy 48.559212 -265.952478) (xy 49.072292 -265.952478) (xy 49.072292 -268.083538)
			)
		)
	)
	(zone
		(layer "In4.Cu")
		(hatch none 0.5)
		(connect_pads
			(clearance 0)
		)
		(min_thickness 0.25)
		(keepout
			(tracks allowed)
			(vias allowed)
			(pads allowed)
			(copperpour allowed)
			(footprints allowed)
		)
		(placement
			(enabled no)
			(sheetname "")
		)
		(fill
			(thermal_gap 0.5)
			(thermal_bridge_width 0.5)
			(island_removal_mode 0)
		)
		(polygon
			(pts
				(xy 420.50081 -199.25157) (xy 420.50081 -197.896734) (xy 420.978076 -197.896734) (xy 420.978076 -199.25157)
			)
		)
	)
	(zone
		(layer "In4.Cu")
		(hatch none 0.5)
		(connect_pads
			(clearance 0)
		)
		(min_thickness 0.25)
		(keepout
			(tracks allowed)
			(vias allowed)
			(pads allowed)
			(copperpour allowed)
			(footprints allowed)
		)
		(placement
			(enabled no)
			(sheetname "")
		)
		(fill
			(thermal_gap 0.5)
			(thermal_bridge_width 0.5)
			(island_removal_mode 0)
		)
		(polygon
			(pts
				(xy 298.77385 -282.563316) (xy 298.77385 -281.20848) (xy 299.251116 -281.20848) (xy 299.251116 -282.563316)
			)
		)
	)
	(zone
		(layer "In4.Cu")
		(hatch none 0.5)
		(connect_pads
			(clearance 0)
		)
		(min_thickness 0.25)
		(keepout
			(tracks allowed)
			(vias allowed)
			(pads allowed)
			(copperpour allowed)
			(footprints allowed)
		)
		(placement
			(enabled no)
			(sheetname "")
		)
		(fill
			(thermal_gap 0.5)
			(thermal_bridge_width 0.5)
			(island_removal_mode 0)
		)
		(polygon
			(pts
				(xy 289.020504 -319.101978) (xy 289.020504 -317.747142) (xy 289.49777 -317.747142) (xy 289.49777 -319.101978)
			)
		)
	)
	(zone
		(layer "In4.Cu")
		(hatch none 0.5)
		(connect_pads
			(clearance 0)
		)
		(min_thickness 0.25)
		(keepout
			(tracks allowed)
			(vias allowed)
			(pads allowed)
			(copperpour allowed)
			(footprints allowed)
		)
		(placement
			(enabled no)
			(sheetname "")
		)
		(fill
			(thermal_gap 0.5)
			(thermal_bridge_width 0.5)
			(island_removal_mode 0)
		)
		(polygon
			(pts
				(xy 104.06126 -351.721928) (xy 104.06126 -351.114868) (xy 105.4227 -351.114868) (xy 105.4227 -351.721928)
			)
		)
	)
	(zone
		(layer "In4.Cu")
		(hatch none 0.5)
		(connect_pads
			(clearance 0)
		)
		(min_thickness 0.25)
		(keepout
			(tracks allowed)
			(vias allowed)
			(pads allowed)
			(copperpour allowed)
			(footprints allowed)
		)
		(placement
			(enabled no)
			(sheetname "")
		)
		(fill
			(thermal_gap 0.5)
			(thermal_bridge_width 0.5)
			(island_removal_mode 0)
		)
		(polygon
			(pts
				(xy 157.445456 -307.65496) (xy 157.445456 -306.300124) (xy 157.922722 -306.300124) (xy 157.922722 -307.65496)
			)
		)
	)
	(zone
		(layer "In4.Cu")
		(hatch none 0.5)
		(connect_pads
			(clearance 0)
		)
		(min_thickness 0.25)
		(keepout
			(tracks allowed)
			(vias allowed)
			(pads allowed)
			(copperpour allowed)
			(footprints allowed)
		)
		(placement
			(enabled no)
			(sheetname "")
		)
		(fill
			(thermal_gap 0.5)
			(thermal_bridge_width 0.5)
			(island_removal_mode 0)
		)
		(polygon
			(pts
				(xy 51.990752 -195.769738) (xy 51.990752 -194.558158) (xy 52.549552 -194.558158) (xy 52.549552 -195.769738)
			)
		)
	)
	(zone
		(layer "In4.Cu")
		(hatch none 0.5)
		(connect_pads
			(clearance 0)
		)
		(min_thickness 0.25)
		(keepout
			(tracks allowed)
			(vias allowed)
			(pads allowed)
			(copperpour allowed)
			(footprints allowed)
		)
		(placement
			(enabled no)
			(sheetname "")
		)
		(fill
			(thermal_gap 0.5)
			(thermal_bridge_width 0.5)
			(island_removal_mode 0)
		)
		(polygon
			(pts
				(xy 283.642562 -290.210494) (xy 283.642562 -288.855658) (xy 284.119828 -288.855658) (xy 284.119828 -290.210494)
			)
		)
	)
	(zone
		(layer "In4.Cu")
		(hatch none 0.5)
		(connect_pads
			(clearance 0)
		)
		(min_thickness 0.25)
		(keepout
			(tracks allowed)
			(vias allowed)
			(pads allowed)
			(copperpour allowed)
			(footprints allowed)
		)
		(placement
			(enabled no)
			(sheetname "")
		)
		(fill
			(thermal_gap 0.5)
			(thermal_bridge_width 0.5)
			(island_removal_mode 0)
		)
		(polygon
			(pts
				(xy 187.62853 -205.207362) (xy 187.62853 -203.852526) (xy 188.105796 -203.852526) (xy 188.105796 -205.207362)
			)
		)
	)
	(zone
		(layer "In4.Cu")
		(hatch none 0.5)
		(connect_pads
			(clearance 0)
		)
		(min_thickness 0.25)
		(keepout
			(tracks allowed)
			(vias allowed)
			(pads allowed)
			(copperpour allowed)
			(footprints allowed)
		)
		(placement
			(enabled no)
			(sheetname "")
		)
		(fill
			(thermal_gap 0.5)
			(thermal_bridge_width 0.5)
			(island_removal_mode 0)
		)
		(polygon
			(pts
				(xy 283.65323 -239.340136) (xy 283.65323 -237.9853) (xy 284.130496 -237.9853) (xy 284.130496 -239.340136)
			)
		)
	)
	(zone
		(layer "In4.Cu")
		(hatch none 0.5)
		(connect_pads
			(clearance 0)
		)
		(min_thickness 0.25)
		(keepout
			(tracks allowed)
			(vias allowed)
			(pads allowed)
			(copperpour allowed)
			(footprints allowed)
		)
		(placement
			(enabled no)
			(sheetname "")
		)
		(fill
			(thermal_gap 0.5)
			(thermal_bridge_width 0.5)
			(island_removal_mode 0)
		)
		(polygon
			(pts
				(xy 50.836322 -229.017576) (xy 50.836322 -227.66274) (xy 51.313588 -227.66274) (xy 51.313588 -229.017576)
				(xy 51.313588 -231.935274) (xy 50.836322 -231.935274)
			)
		)
	)
	(zone
		(layer "In4.Cu")
		(hatch none 0.5)
		(connect_pads
			(clearance 0)
		)
		(min_thickness 0.25)
		(keepout
			(tracks allowed)
			(vias allowed)
			(pads allowed)
			(copperpour allowed)
			(footprints allowed)
		)
		(placement
			(enabled no)
			(sheetname "")
		)
		(fill
			(thermal_gap 0.5)
			(thermal_bridge_width 0.5)
			(island_removal_mode 0)
		)
		(polygon
			(pts
				(xy 49.58588 -288.369248) (xy 49.58588 -285.961328) (xy 52.8066 -285.961328) (xy 52.8066 -288.369248)
			)
		)
	)
	(zone
		(layer "In4.Cu")
		(hatch none 0.5)
		(connect_pads
			(clearance 0)
		)
		(min_thickness 0.25)
		(keepout
			(tracks allowed)
			(vias allowed)
			(pads allowed)
			(copperpour allowed)
			(footprints allowed)
		)
		(placement
			(enabled no)
			(sheetname "")
		)
		(fill
			(thermal_gap 0.5)
			(thermal_bridge_width 0.5)
			(island_removal_mode 0)
		)
		(polygon
			(pts
				(xy 61.787024 -307.163216) (xy 61.787024 -305.743356) (xy 62.274704 -305.743356) (xy 62.274704 -307.163216)
			)
		)
	)
	(zone
		(layer "In4.Cu")
		(hatch none 0.5)
		(connect_pads
			(clearance 0)
		)
		(min_thickness 0.25)
		(keepout
			(tracks allowed)
			(vias allowed)
			(pads allowed)
			(copperpour allowed)
			(footprints allowed)
		)
		(placement
			(enabled no)
			(sheetname "")
		)
		(fill
			(thermal_gap 0.5)
			(thermal_bridge_width 0.5)
			(island_removal_mode 0)
		)
		(polygon
			(pts
				(xy 50.812954 -203.540614) (xy 50.812954 -202.982068) (xy 51.29022 -202.982068) (xy 51.703478 -202.982068)
				(xy 51.773074 -203.051664) (xy 51.773074 -203.467716) (xy 51.700176 -203.540614) (xy 51.29022 -203.540614)
			)
		)
	)
	(zone
		(layer "In4.Cu")
		(hatch none 0.5)
		(connect_pads
			(clearance 0)
		)
		(min_thickness 0.25)
		(keepout
			(tracks allowed)
			(vias allowed)
			(pads allowed)
			(copperpour allowed)
			(footprints allowed)
		)
		(placement
			(enabled no)
			(sheetname "")
		)
		(fill
			(thermal_gap 0.5)
			(thermal_bridge_width 0.5)
			(island_removal_mode 0)
		)
		(polygon
			(pts
				(xy 283.673042 -239.334294) (xy 283.673042 -237.979458) (xy 284.150308 -237.979458) (xy 284.150308 -239.334294)
			)
		)
	)
	(zone
		(layer "In4.Cu")
		(hatch none 0.5)
		(connect_pads
			(clearance 0)
		)
		(min_thickness 0.25)
		(keepout
			(tracks allowed)
			(vias allowed)
			(pads allowed)
			(copperpour allowed)
			(footprints allowed)
		)
		(placement
			(enabled no)
			(sheetname "")
		)
		(fill
			(thermal_gap 0.5)
			(thermal_bridge_width 0.5)
			(island_removal_mode 0)
		)
		(polygon
			(pts
				(xy 283.685742 -297.040554) (xy 283.685742 -295.685718) (xy 284.163008 -295.685718) (xy 284.163008 -297.040554)
			)
		)
	)
	(zone
		(layer "In4.Cu")
		(hatch none 0.5)
		(connect_pads
			(clearance 0)
		)
		(min_thickness 0.25)
		(keepout
			(tracks allowed)
			(vias allowed)
			(pads allowed)
			(copperpour allowed)
			(footprints allowed)
		)
		(placement
			(enabled no)
			(sheetname "")
		)
		(fill
			(thermal_gap 0.5)
			(thermal_bridge_width 0.5)
			(island_removal_mode 0)
		)
		(polygon
			(pts
				(xy 172.54093 -206.0575) (xy 172.54093 -204.702664) (xy 173.018196 -204.702664) (xy 173.018196 -206.0575)
				(xy 173.018196 -206.547212) (xy 172.54093 -206.547212)
			)
		)
	)
	(zone
		(layer "In4.Cu")
		(hatch none 0.5)
		(connect_pads
			(clearance 0)
		)
		(min_thickness 0.25)
		(keepout
			(tracks allowed)
			(vias allowed)
			(pads allowed)
			(copperpour allowed)
			(footprints allowed)
		)
		(placement
			(enabled no)
			(sheetname "")
		)
		(fill
			(thermal_gap 0.5)
			(thermal_bridge_width 0.5)
			(island_removal_mode 0)
		)
		(polygon
			(pts
				(xy 296.557192 -244.333776) (xy 296.557192 -242.924076) (xy 297.095672 -242.924076) (xy 297.095672 -244.333776)
			)
		)
	)
	(zone
		(layer "In4.Cu")
		(hatch none 0.5)
		(connect_pads
			(clearance 0)
		)
		(min_thickness 0.25)
		(keepout
			(tracks allowed)
			(vias allowed)
			(pads allowed)
			(copperpour allowed)
			(footprints allowed)
		)
		(placement
			(enabled no)
			(sheetname "")
		)
		(fill
			(thermal_gap 0.5)
			(thermal_bridge_width 0.5)
			(island_removal_mode 0)
		)
		(polygon
			(pts
				(xy 172.54093 -287.65754) (xy 172.54093 -286.302704) (xy 173.018196 -286.302704) (xy 173.018196 -287.65754)
				(xy 173.305978 -287.65754) (xy 173.305978 -289.025584) (xy 173.017942 -289.025584) (xy 172.136562 -289.025584)
				(xy 172.136562 -287.65754) (xy 172.38345 -287.65754)
			)
		)
	)
	(zone
		(layer "In4.Cu")
		(hatch none 0.5)
		(connect_pads
			(clearance 0)
		)
		(min_thickness 0.25)
		(keepout
			(tracks allowed)
			(vias allowed)
			(pads allowed)
			(copperpour allowed)
			(footprints allowed)
		)
		(placement
			(enabled no)
			(sheetname "")
		)
		(fill
			(thermal_gap 0.5)
			(thermal_bridge_width 0.5)
			(island_removal_mode 0)
		)
		(polygon
			(pts
				(xy 187.671964 -312.375042) (xy 187.671964 -311.020206) (xy 188.14923 -311.020206) (xy 188.14923 -312.375042)
			)
		)
	)
	(zone
		(layer "In4.Cu")
		(hatch none 0.5)
		(connect_pads
			(clearance 0)
		)
		(min_thickness 0.25)
		(keepout
			(tracks allowed)
			(vias allowed)
			(pads allowed)
			(copperpour allowed)
			(footprints allowed)
		)
		(placement
			(enabled no)
			(sheetname "")
		)
		(fill
			(thermal_gap 0.5)
			(thermal_bridge_width 0.5)
			(island_removal_mode 0)
		)
		(polygon
			(pts
				(xy 187.598304 -213.711282) (xy 187.598304 -212.356446) (xy 188.07557 -212.356446) (xy 188.07557 -213.711282)
			)
		)
	)
	(zone
		(layer "In4.Cu")
		(hatch none 0.5)
		(connect_pads
			(clearance 0)
		)
		(min_thickness 0.25)
		(keepout
			(tracks allowed)
			(vias allowed)
			(pads allowed)
			(copperpour allowed)
			(footprints allowed)
		)
		(placement
			(enabled no)
			(sheetname "")
		)
		(fill
			(thermal_gap 0.5)
			(thermal_bridge_width 0.5)
			(island_removal_mode 0)
		)
		(polygon
			(pts
				(xy 435.568598 -209.457544) (xy 435.568598 -207.29702) (xy 436.045864 -207.29702) (xy 436.045864 -209.457544)
			)
		)
	)
	(zone
		(layer "In4.Cu")
		(hatch none 0.5)
		(connect_pads
			(clearance 0)
		)
		(min_thickness 0.25)
		(keepout
			(tracks allowed)
			(vias allowed)
			(pads allowed)
			(copperpour allowed)
			(footprints allowed)
		)
		(placement
			(enabled no)
			(sheetname "")
		)
		(fill
			(thermal_gap 0.5)
			(thermal_bridge_width 0.5)
			(island_removal_mode 0)
		)
		(polygon
			(pts
				(xy 187.618116 -213.70544) (xy 187.618116 -212.350604) (xy 188.095382 -212.350604) (xy 188.095382 -213.70544)
			)
		)
	)
	(zone
		(layer "In4.Cu")
		(hatch none 0.5)
		(connect_pads
			(clearance 0)
		)
		(min_thickness 0.25)
		(keepout
			(tracks allowed)
			(vias allowed)
			(pads allowed)
			(copperpour allowed)
			(footprints allowed)
		)
		(placement
			(enabled no)
			(sheetname "")
		)
		(fill
			(thermal_gap 0.5)
			(thermal_bridge_width 0.5)
			(island_removal_mode 0)
		)
		(polygon
			(pts
				(xy 35.725862 -234.082336) (xy 35.725862 -232.7275) (xy 36.203128 -232.7275) (xy 36.203128 -234.082336)
			)
		)
	)
	(zone
		(layer "In4.Cu")
		(hatch none 0.5)
		(connect_pads
			(clearance 0)
		)
		(min_thickness 0.25)
		(keepout
			(tracks allowed)
			(vias allowed)
			(pads allowed)
			(copperpour allowed)
			(footprints allowed)
		)
		(placement
			(enabled no)
			(sheetname "")
		)
		(fill
			(thermal_gap 0.5)
			(thermal_bridge_width 0.5)
			(island_removal_mode 0)
		)
		(polygon
			(pts
				(xy 299.98035 -318.949578) (xy 299.98035 -317.594742) (xy 300.457616 -317.594742) (xy 300.457616 -318.949578)
			)
		)
	)
	(zone
		(layer "In4.Cu")
		(hatch none 0.5)
		(connect_pads
			(clearance 0)
		)
		(min_thickness 0.25)
		(keepout
			(tracks allowed)
			(vias allowed)
			(pads allowed)
			(copperpour allowed)
			(footprints allowed)
		)
		(placement
			(enabled no)
			(sheetname "")
		)
		(fill
			(thermal_gap 0.5)
			(thermal_bridge_width 0.5)
			(island_removal_mode 0)
		)
		(polygon
			(pts
				(xy 420.50081 -243.451634) (xy 420.50081 -242.955318) (xy 420.104824 -242.955318) (xy 420.104824 -242.096798)
				(xy 420.50081 -242.096798) (xy 420.978076 -242.096798) (xy 421.26154 -242.096798) (xy 421.26154 -242.972082)
				(xy 420.978076 -242.972082) (xy 420.978076 -243.451634)
			)
		)
	)
	(zone
		(layer "In4.Cu")
		(hatch none 0.5)
		(connect_pads
			(clearance 0)
		)
		(min_thickness 0.25)
		(keepout
			(tracks allowed)
			(vias allowed)
			(pads allowed)
			(copperpour allowed)
			(footprints allowed)
		)
		(placement
			(enabled no)
			(sheetname "")
		)
		(fill
			(thermal_gap 0.5)
			(thermal_bridge_width 0.5)
			(island_removal_mode 0)
		)
		(polygon
			(pts
				(xy 435.58841 -241.751612) (xy 435.58841 -240.396776) (xy 436.065676 -240.396776) (xy 436.065676 -241.751612)
			)
		)
	)
	(zone
		(layer "In4.Cu")
		(hatch none 0.5)
		(connect_pads
			(clearance 0)
		)
		(min_thickness 0.25)
		(keepout
			(tracks allowed)
			(vias allowed)
			(pads allowed)
			(copperpour allowed)
			(footprints allowed)
		)
		(placement
			(enabled no)
			(sheetname "")
		)
		(fill
			(thermal_gap 0.5)
			(thermal_bridge_width 0.5)
			(island_removal_mode 0)
		)
		(polygon
			(pts
				(xy 424.60926 -367.109248) (xy 424.60926 -365.697008) (xy 426.21708 -365.697008) (xy 426.21708 -367.109248)
			)
		)
	)
	(zone
		(layer "In4.Cu")
		(hatch none 0.5)
		(connect_pads
			(clearance 0)
		)
		(min_thickness 0.25)
		(keepout
			(tracks allowed)
			(vias allowed)
			(pads allowed)
			(copperpour allowed)
			(footprints allowed)
		)
		(placement
			(enabled no)
			(sheetname "")
		)
		(fill
			(thermal_gap 0.5)
			(thermal_bridge_width 0.5)
			(island_removal_mode 0)
		)
		(polygon
			(pts
				(xy 283.64307 -311.443116) (xy 283.64307 -310.08828) (xy 284.120336 -310.08828) (xy 284.120336 -311.443116)
			)
		)
	)
	(zone
		(layer "In4.Cu")
		(hatch none 0.5)
		(connect_pads
			(clearance 0)
		)
		(min_thickness 0.25)
		(keepout
			(tracks allowed)
			(vias allowed)
			(pads allowed)
			(copperpour allowed)
			(footprints allowed)
		)
		(placement
			(enabled no)
			(sheetname "")
		)
		(fill
			(thermal_gap 0.5)
			(thermal_bridge_width 0.5)
			(island_removal_mode 0)
		)
		(polygon
			(pts
				(xy 43.293284 -242.553236) (xy 43.293284 -241.372136) (xy 43.747944 -241.372136) (xy 43.747944 -242.553236)
			)
		)
	)
	(zone
		(layer "In4.Cu")
		(hatch none 0.5)
		(connect_pads
			(clearance 0)
		)
		(min_thickness 0.25)
		(keepout
			(tracks allowed)
			(vias allowed)
			(pads allowed)
			(copperpour allowed)
			(footprints allowed)
		)
		(placement
			(enabled no)
			(sheetname "")
		)
		(fill
			(thermal_gap 0.5)
			(thermal_bridge_width 0.5)
			(island_removal_mode 0)
		)
		(polygon
			(pts
				(xy 435.58841 -233.251756) (xy 435.58841 -231.89692) (xy 436.065676 -231.89692) (xy 436.065676 -233.251756)
			)
		)
	)
	(zone
		(layer "In4.Cu")
		(hatch none 0.5)
		(connect_pads
			(clearance 0)
		)
		(min_thickness 0.25)
		(keepout
			(tracks allowed)
			(vias allowed)
			(pads allowed)
			(copperpour allowed)
			(footprints allowed)
		)
		(placement
			(enabled no)
			(sheetname "")
		)
		(fill
			(thermal_gap 0.5)
			(thermal_bridge_width 0.5)
			(island_removal_mode 0)
		)
		(polygon
			(pts
				(xy 172.560742 -229.851712) (xy 172.560742 -228.496876) (xy 173.038008 -228.496876) (xy 173.038008 -229.851712)
			)
		)
	)
	(zone
		(layer "In4.Cu")
		(hatch none 0.5)
		(connect_pads
			(clearance 0)
		)
		(min_thickness 0.25)
		(keepout
			(tracks allowed)
			(vias allowed)
			(pads allowed)
			(copperpour allowed)
			(footprints allowed)
		)
		(placement
			(enabled no)
			(sheetname "")
		)
		(fill
			(thermal_gap 0.5)
			(thermal_bridge_width 0.5)
			(island_removal_mode 0)
		)
		(polygon
			(pts
				(xy 435.58841 -269.800578) (xy 435.58841 -268.92504) (xy 435.164738 -268.92504) (xy 435.164738 -267.596874)
				(xy 435.58841 -267.596874) (xy 436.065676 -267.596874) (xy 436.065676 -269.800578)
			)
		)
	)
	(zone
		(layer "In4.Cu")
		(hatch none 0.5)
		(connect_pads
			(clearance 0)
		)
		(min_thickness 0.25)
		(keepout
			(tracks allowed)
			(vias allowed)
			(pads allowed)
			(copperpour allowed)
			(footprints allowed)
		)
		(placement
			(enabled no)
			(sheetname "")
		)
		(fill
			(thermal_gap 0.5)
			(thermal_bridge_width 0.5)
			(island_removal_mode 0)
		)
		(polygon
			(pts
				(xy 35.732974 -315.988954) (xy 35.732974 -314.634118) (xy 36.21024 -314.634118) (xy 36.21024 -315.988954)
			)
		)
	)
	(zone
		(layer "In4.Cu")
		(hatch none 0.5)
		(connect_pads
			(clearance 0)
		)
		(min_thickness 0.25)
		(keepout
			(tracks allowed)
			(vias allowed)
			(pads allowed)
			(copperpour allowed)
			(footprints allowed)
		)
		(placement
			(enabled no)
			(sheetname "")
		)
		(fill
			(thermal_gap 0.5)
			(thermal_bridge_width 0.5)
			(island_removal_mode 0)
		)
		(polygon
			(pts
				(xy 188.89726 -15.09268) (xy 188.89726 -13.67536) (xy 190.54064 -13.67536) (xy 190.54064 -15.09268)
			)
		)
	)
	(zone
		(layer "In4.Cu")
		(hatch none 0.5)
		(connect_pads
			(clearance 0)
		)
		(min_thickness 0.25)
		(keepout
			(tracks allowed)
			(vias allowed)
			(pads allowed)
			(copperpour allowed)
			(footprints allowed)
		)
		(placement
			(enabled no)
			(sheetname "")
		)
		(fill
			(thermal_gap 0.5)
			(thermal_bridge_width 0.5)
			(island_removal_mode 0)
		)
		(polygon
			(pts
				(xy 187.648342 -240.05159) (xy 187.648342 -238.696754) (xy 188.125608 -238.696754) (xy 188.125608 -240.05159)
			)
		)
	)
	(zone
		(layer "In4.Cu")
		(hatch none 0.5)
		(connect_pads
			(clearance 0)
		)
		(min_thickness 0.25)
		(keepout
			(tracks allowed)
			(vias allowed)
			(pads allowed)
			(copperpour allowed)
			(footprints allowed)
		)
		(placement
			(enabled no)
			(sheetname "")
		)
		(fill
			(thermal_gap 0.5)
			(thermal_bridge_width 0.5)
			(island_removal_mode 0)
		)
		(polygon
			(pts
				(xy 19.42338 -386.10794) (xy 19.42338 -384.58648) (xy 20.3708 -384.58648) (xy 20.3708 -386.10794)
			)
		)
	)
	(zone
		(layer "In4.Cu")
		(hatch none 0.5)
		(connect_pads
			(clearance 0)
		)
		(min_thickness 0.25)
		(keepout
			(tracks allowed)
			(vias allowed)
			(pads allowed)
			(copperpour allowed)
			(footprints allowed)
		)
		(placement
			(enabled no)
			(sheetname "")
		)
		(fill
			(thermal_gap 0.5)
			(thermal_bridge_width 0.5)
			(island_removal_mode 0)
		)
		(polygon
			(pts
				(xy 187.648342 -209.451702) (xy 187.648342 -207.291178) (xy 188.125608 -207.291178) (xy 188.125608 -209.451702)
			)
		)
	)
	(zone
		(layer "In4.Cu")
		(hatch none 0.5)
		(connect_pads
			(clearance 0)
		)
		(min_thickness 0.25)
		(keepout
			(tracks allowed)
			(vias allowed)
			(pads allowed)
			(copperpour allowed)
			(footprints allowed)
		)
		(placement
			(enabled no)
			(sheetname "")
		)
		(fill
			(thermal_gap 0.5)
			(thermal_bridge_width 0.5)
			(island_removal_mode 0)
		)
		(polygon
			(pts
				(xy 46.707552 -259.577078) (xy 46.707552 -258.322318) (xy 47.185072 -258.322318) (xy 47.185072 -259.577078)
			)
		)
	)
	(zone
		(layer "In4.Cu")
		(hatch none 0.5)
		(connect_pads
			(clearance 0)
		)
		(min_thickness 0.25)
		(keepout
			(tracks allowed)
			(vias allowed)
			(pads allowed)
			(copperpour allowed)
			(footprints allowed)
		)
		(placement
			(enabled no)
			(sheetname "")
		)
		(fill
			(thermal_gap 0.5)
			(thermal_bridge_width 0.5)
			(island_removal_mode 0)
		)
		(polygon
			(pts
				(xy 313.85764 -303.823878) (xy 313.85764 -298.251118) (xy 314.30722 -298.251118) (xy 314.30722 -303.823878)
			)
		)
	)
	(zone
		(layer "In4.Cu")
		(hatch none 0.5)
		(connect_pads
			(clearance 0)
		)
		(min_thickness 0.25)
		(keepout
			(tracks allowed)
			(vias allowed)
			(pads allowed)
			(copperpour allowed)
			(footprints allowed)
		)
		(placement
			(enabled no)
			(sheetname "")
		)
		(fill
			(thermal_gap 0.5)
			(thermal_bridge_width 0.5)
			(island_removal_mode 0)
		)
		(polygon
			(pts
				(xy 435.568598 -265.557508) (xy 435.568598 -264.202672) (xy 436.045864 -264.202672) (xy 436.045864 -265.557508)
			)
		)
	)
	(zone
		(layer "In4.Cu")
		(hatch none 0.5)
		(connect_pads
			(clearance 0)
		)
		(min_thickness 0.25)
		(keepout
			(tracks allowed)
			(vias allowed)
			(pads allowed)
			(copperpour allowed)
			(footprints allowed)
		)
		(placement
			(enabled no)
			(sheetname "")
		)
		(fill
			(thermal_gap 0.5)
			(thermal_bridge_width 0.5)
			(island_removal_mode 0)
		)
		(polygon
			(pts
				(xy 172.54093 -302.957484) (xy 172.54093 -301.749714) (xy 171.594526 -301.749714) (xy 171.594526 -300.74362)
				(xy 172.54093 -300.74362) (xy 173.018196 -300.74362) (xy 173.018196 -302.957484)
			)
		)
	)
	(zone
		(layer "In4.Cu")
		(hatch none 0.5)
		(connect_pads
			(clearance 0)
		)
		(min_thickness 0.25)
		(keepout
			(tracks allowed)
			(vias allowed)
			(pads allowed)
			(copperpour allowed)
			(footprints allowed)
		)
		(placement
			(enabled no)
			(sheetname "")
		)
		(fill
			(thermal_gap 0.5)
			(thermal_bridge_width 0.5)
			(island_removal_mode 0)
		)
		(polygon
			(pts
				(xy 172.560742 -206.051658) (xy 172.560742 -204.696822) (xy 173.038008 -204.696822) (xy 173.038008 -206.051658)
				(xy 173.038008 -206.54137) (xy 172.560742 -206.54137)
			)
		)
	)
	(zone
		(layer "In4.Cu")
		(hatch none 0.5)
		(connect_pads
			(clearance 0)
		)
		(min_thickness 0.25)
		(keepout
			(tracks allowed)
			(vias allowed)
			(pads allowed)
			(copperpour allowed)
			(footprints allowed)
		)
		(placement
			(enabled no)
			(sheetname "")
		)
		(fill
			(thermal_gap 0.5)
			(thermal_bridge_width 0.5)
			(island_removal_mode 0)
		)
		(polygon
			(pts
				(xy 443.112398 -245.157498) (xy 443.112398 -243.802662) (xy 443.589664 -243.802662) (xy 443.589664 -245.157498)
			)
		)
	)
	(zone
		(layer "In4.Cu")
		(hatch none 0.5)
		(connect_pads
			(clearance 0)
		)
		(min_thickness 0.25)
		(keepout
			(tracks allowed)
			(vias allowed)
			(pads allowed)
			(copperpour allowed)
			(footprints allowed)
		)
		(placement
			(enabled no)
			(sheetname "")
		)
		(fill
			(thermal_gap 0.5)
			(thermal_bridge_width 0.5)
			(island_removal_mode 0)
		)
		(polygon
			(pts
				(xy 187.648342 -211.151724) (xy 187.648342 -209.796888) (xy 188.125608 -209.796888) (xy 188.125608 -211.151724)
			)
		)
	)
	(zone
		(layer "In4.Cu")
		(hatch none 0.5)
		(connect_pads
			(clearance 0)
		)
		(min_thickness 0.25)
		(keepout
			(tracks allowed)
			(vias allowed)
			(pads allowed)
			(copperpour allowed)
			(footprints allowed)
		)
		(placement
			(enabled no)
			(sheetname "")
		)
		(fill
			(thermal_gap 0.5)
			(thermal_bridge_width 0.5)
			(island_removal_mode 0)
		)
		(polygon
			(pts
				(xy 76.6191 -350.751648) (xy 76.6191 -349.217488) (xy 77.41666 -349.217488) (xy 77.41666 -350.751648)
			)
		)
	)
	(zone
		(layer "In4.Cu")
		(hatch none 0.5)
		(connect_pads
			(clearance 0)
		)
		(min_thickness 0.25)
		(keepout
			(tracks allowed)
			(vias allowed)
			(pads allowed)
			(copperpour allowed)
			(footprints allowed)
		)
		(placement
			(enabled no)
			(sheetname "")
		)
		(fill
			(thermal_gap 0.5)
			(thermal_bridge_width 0.5)
			(island_removal_mode 0)
		)
		(polygon
			(pts
				(xy 35.727894 -235.813854) (xy 35.727894 -234.459018) (xy 36.20516 -234.459018) (xy 36.20516 -235.813854)
			)
		)
	)
	(zone
		(layer "In4.Cu")
		(hatch none 0.5)
		(connect_pads
			(clearance 0)
		)
		(min_thickness 0.25)
		(keepout
			(tracks allowed)
			(vias allowed)
			(pads allowed)
			(copperpour allowed)
			(footprints allowed)
		)
		(placement
			(enabled no)
			(sheetname "")
		)
		(fill
			(thermal_gap 0.5)
			(thermal_bridge_width 0.5)
			(island_removal_mode 0)
		)
		(polygon
			(pts
				(xy 298.76623 -302.240696) (xy 298.76623 -300.88586) (xy 299.243496 -300.88586) (xy 299.243496 -302.240696)
			)
		)
	)
	(zone
		(layer "In4.Cu")
		(hatch none 0.5)
		(connect_pads
			(clearance 0)
		)
		(min_thickness 0.25)
		(keepout
			(tracks allowed)
			(vias allowed)
			(pads allowed)
			(copperpour allowed)
			(footprints allowed)
		)
		(placement
			(enabled no)
			(sheetname "")
		)
		(fill
			(thermal_gap 0.5)
			(thermal_bridge_width 0.5)
			(island_removal_mode 0)
		)
		(polygon
			(pts
				(xy 420.50081 -302.951642) (xy 420.50081 -301.743872) (xy 419.554406 -301.743872) (xy 419.554406 -300.737778)
				(xy 420.50081 -300.737778) (xy 420.978076 -300.737778) (xy 420.978076 -302.951642)
			)
		)
	)
	(zone
		(layer "In4.Cu")
		(hatch none 0.5)
		(connect_pads
			(clearance 0)
		)
		(min_thickness 0.25)
		(keepout
			(tracks allowed)
			(vias allowed)
			(pads allowed)
			(copperpour allowed)
			(footprints allowed)
		)
		(placement
			(enabled no)
			(sheetname "")
		)
		(fill
			(thermal_gap 0.5)
			(thermal_bridge_width 0.5)
			(island_removal_mode 0)
		)
		(polygon
			(pts
				(xy 298.798742 -195.836794) (xy 298.798742 -194.481958) (xy 299.276008 -194.481958) (xy 299.276008 -195.836794)
			)
		)
	)
	(zone
		(layer "In4.Cu")
		(hatch none 0.5)
		(connect_pads
			(clearance 0)
		)
		(min_thickness 0.25)
		(keepout
			(tracks allowed)
			(vias allowed)
			(pads allowed)
			(copperpour allowed)
			(footprints allowed)
		)
		(placement
			(enabled no)
			(sheetname "")
		)
		(fill
			(thermal_gap 0.5)
			(thermal_bridge_width 0.5)
			(island_removal_mode 0)
		)
		(polygon
			(pts
				(xy 309.709312 -301.199296) (xy 309.709312 -298.059856) (xy 310.156352 -298.059856) (xy 310.156352 -301.199296)
			)
		)
	)
	(zone
		(layer "In4.Cu")
		(hatch none 0.5)
		(connect_pads
			(clearance 0)
		)
		(min_thickness 0.25)
		(keepout
			(tracks allowed)
			(vias allowed)
			(pads allowed)
			(copperpour allowed)
			(footprints allowed)
		)
		(placement
			(enabled no)
			(sheetname "")
		)
		(fill
			(thermal_gap 0.5)
			(thermal_bridge_width 0.5)
			(island_removal_mode 0)
		)
		(polygon
			(pts
				(xy 420.978076 -300.401736) (xy 420.50081 -300.401736) (xy 420.094664 -300.401736) (xy 420.094664 -299.814488)
				(xy 418.873686 -299.814488) (xy 418.873686 -298.321476) (xy 418.873686 -297.952922) (xy 418.985192 -297.841416)
				(xy 419.93693 -297.841416) (xy 421.204898 -297.841416) (xy 421.204898 -298.188634) (xy 421.204898 -298.678346)
				(xy 421.204898 -300.401736)
			)
		)
	)
	(zone
		(layer "In4.Cu")
		(hatch none 0.5)
		(connect_pads
			(clearance 0)
		)
		(min_thickness 0.25)
		(keepout
			(tracks allowed)
			(vias allowed)
			(pads allowed)
			(copperpour allowed)
			(footprints allowed)
		)
		(placement
			(enabled no)
			(sheetname "")
		)
		(fill
			(thermal_gap 0.5)
			(thermal_bridge_width 0.5)
			(island_removal_mode 0)
		)
		(polygon
			(pts
				(xy 435.58841 -211.151724) (xy 435.58841 -209.796888) (xy 436.065676 -209.796888) (xy 436.065676 -211.151724)
			)
		)
	)
	(zone
		(layer "In4.Cu")
		(hatch none 0.5)
		(connect_pads
			(clearance 0)
		)
		(min_thickness 0.25)
		(keepout
			(tracks allowed)
			(vias allowed)
			(pads allowed)
			(copperpour allowed)
			(footprints allowed)
		)
		(placement
			(enabled no)
			(sheetname "")
		)
		(fill
			(thermal_gap 0.5)
			(thermal_bridge_width 0.5)
			(island_removal_mode 0)
		)
		(polygon
			(pts
				(xy 165.25748 -8.79348) (xy 165.25748 -7.63016) (xy 165.99916 -7.63016) (xy 165.99916 -8.79348)
			)
		)
	)
	(zone
		(layer "In4.Cu")
		(hatch none 0.5)
		(connect_pads
			(clearance 0)
		)
		(min_thickness 0.25)
		(keepout
			(tracks allowed)
			(vias allowed)
			(pads allowed)
			(copperpour allowed)
			(footprints allowed)
		)
		(placement
			(enabled no)
			(sheetname "")
		)
		(fill
			(thermal_gap 0.5)
			(thermal_bridge_width 0.5)
			(island_removal_mode 0)
		)
		(polygon
			(pts
				(xy 299.940472 -287.630616) (xy 299.940472 -285.433516) (xy 300.547532 -285.433516) (xy 300.547532 -287.630616)
			)
		)
	)
	(zone
		(layer "In4.Cu")
		(hatch none 0.5)
		(connect_pads
			(clearance 0)
		)
		(min_thickness 0.25)
		(keepout
			(tracks allowed)
			(vias allowed)
			(pads allowed)
			(copperpour allowed)
			(footprints allowed)
		)
		(placement
			(enabled no)
			(sheetname "")
		)
		(fill
			(thermal_gap 0.5)
			(thermal_bridge_width 0.5)
			(island_removal_mode 0)
		)
		(polygon
			(pts
				(xy 35.744658 -317.256414) (xy 35.744658 -316.00521) (xy 36.369752 -316.00521) (xy 36.369752 -317.256414)
			)
		)
	)
	(zone
		(layer "In4.Cu")
		(hatch none 0.5)
		(connect_pads
			(clearance 0)
		)
		(min_thickness 0.25)
		(keepout
			(tracks allowed)
			(vias allowed)
			(pads allowed)
			(copperpour allowed)
			(footprints allowed)
		)
		(placement
			(enabled no)
			(sheetname "")
		)
		(fill
			(thermal_gap 0.5)
			(thermal_bridge_width 0.5)
			(island_removal_mode 0)
		)
		(polygon
			(pts
				(xy 54.288944 -245.060216) (xy 54.288944 -242.903756) (xy 54.827424 -242.903756) (xy 54.827424 -245.060216)
			)
		)
	)
	(zone
		(layer "In4.Cu")
		(hatch none 0.5)
		(connect_pads
			(clearance 0)
		)
		(min_thickness 0.25)
		(keepout
			(tracks allowed)
			(vias allowed)
			(pads allowed)
			(copperpour allowed)
			(footprints allowed)
		)
		(placement
			(enabled no)
			(sheetname "")
		)
		(fill
			(thermal_gap 0.5)
			(thermal_bridge_width 0.5)
			(island_removal_mode 0)
		)
		(polygon
			(pts
				(xy 50.708052 -317.425578) (xy 50.708052 -316.117478) (xy 51.307492 -316.117478) (xy 51.307492 -317.425578)
			)
		)
	)
	(zone
		(layer "In4.Cu")
		(hatch none 0.5)
		(connect_pads
			(clearance 0)
		)
		(min_thickness 0.25)
		(keepout
			(tracks allowed)
			(vias allowed)
			(pads allowed)
			(copperpour allowed)
			(footprints allowed)
		)
		(placement
			(enabled no)
			(sheetname "")
		)
		(fill
			(thermal_gap 0.5)
			(thermal_bridge_width 0.5)
			(island_removal_mode 0)
		)
		(polygon
			(pts
				(xy 65.957704 -306.695856) (xy 65.957704 -304.996596) (xy 66.341244 -304.996596) (xy 66.341244 -306.695856)
			)
		)
	)
	(zone
		(layer "In4.Cu")
		(hatch none 0.5)
		(connect_pads
			(clearance 0)
		)
		(min_thickness 0.25)
		(keepout
			(tracks allowed)
			(vias allowed)
			(pads allowed)
			(copperpour allowed)
			(footprints allowed)
		)
		(placement
			(enabled no)
			(sheetname "")
		)
		(fill
			(thermal_gap 0.5)
			(thermal_bridge_width 0.5)
			(island_removal_mode 0)
		)
		(polygon
			(pts
				(xy 187.648342 -244.301518) (xy 187.648342 -242.946682) (xy 188.125608 -242.946682) (xy 188.125608 -244.301518)
			)
		)
	)
	(zone
		(layer "In4.Cu")
		(hatch none 0.5)
		(connect_pads
			(clearance 0)
		)
		(min_thickness 0.25)
		(keepout
			(tracks allowed)
			(vias allowed)
			(pads allowed)
			(copperpour allowed)
			(footprints allowed)
		)
		(placement
			(enabled no)
			(sheetname "")
		)
		(fill
			(thermal_gap 0.5)
			(thermal_bridge_width 0.5)
			(island_removal_mode 0)
		)
		(polygon
			(pts
				(xy 435.568598 -240.057432) (xy 435.568598 -238.702596) (xy 436.045864 -238.702596) (xy 436.045864 -240.057432)
			)
		)
	)
	(zone
		(layer "In4.Cu")
		(hatch none 0.5)
		(connect_pads
			(clearance 0)
		)
		(min_thickness 0.25)
		(keepout
			(tracks allowed)
			(vias allowed)
			(pads allowed)
			(copperpour allowed)
			(footprints allowed)
		)
		(placement
			(enabled no)
			(sheetname "")
		)
		(fill
			(thermal_gap 0.5)
			(thermal_bridge_width 0.5)
			(island_removal_mode 0)
		)
		(polygon
			(pts
				(xy 172.54093 -223.90735) (xy 172.54093 -222.552514) (xy 173.018196 -222.552514) (xy 173.018196 -223.90735)
			)
		)
	)
	(zone
		(layer "In4.Cu")
		(hatch none 0.5)
		(connect_pads
			(clearance 0)
		)
		(min_thickness 0.25)
		(keepout
			(tracks allowed)
			(vias allowed)
			(pads allowed)
			(copperpour allowed)
			(footprints allowed)
		)
		(placement
			(enabled no)
			(sheetname "")
		)
		(fill
			(thermal_gap 0.5)
			(thermal_bridge_width 0.5)
			(island_removal_mode 0)
		)
		(polygon
			(pts
				(xy 157.425644 -307.660802) (xy 157.425644 -306.305966) (xy 157.90291 -306.305966) (xy 157.90291 -307.660802)
			)
		)
	)
	(zone
		(layer "In4.Cu")
		(hatch none 0.5)
		(connect_pads
			(clearance 0)
		)
		(min_thickness 0.25)
		(keepout
			(tracks allowed)
			(vias allowed)
			(pads allowed)
			(copperpour allowed)
			(footprints allowed)
		)
		(placement
			(enabled no)
			(sheetname "")
		)
		(fill
			(thermal_gap 0.5)
			(thermal_bridge_width 0.5)
			(island_removal_mode 0)
		)
		(polygon
			(pts
				(xy 291.1094 -244.235478) (xy 291.1094 -242.909598) (xy 291.64788 -242.909598) (xy 291.64788 -244.235478)
			)
		)
	)
	(zone
		(layer "In4.Cu")
		(hatch none 0.5)
		(connect_pads
			(clearance 0)
		)
		(min_thickness 0.25)
		(keepout
			(tracks allowed)
			(vias allowed)
			(pads allowed)
			(copperpour allowed)
			(footprints allowed)
		)
		(placement
			(enabled no)
			(sheetname "")
		)
		(fill
			(thermal_gap 0.5)
			(thermal_bridge_width 0.5)
			(island_removal_mode 0)
		)
		(polygon
			(pts
				(xy 43.237912 -317.303658) (xy 43.237912 -316.183518) (xy 43.799252 -316.183518) (xy 43.799252 -317.303658)
			)
		)
	)
	(zone
		(layer "In4.Cu")
		(hatch none 0.5)
		(connect_pads
			(clearance 0)
		)
		(min_thickness 0.25)
		(keepout
			(tracks allowed)
			(vias allowed)
			(pads allowed)
			(copperpour allowed)
			(footprints allowed)
		)
		(placement
			(enabled no)
			(sheetname "")
		)
		(fill
			(thermal_gap 0.5)
			(thermal_bridge_width 0.5)
			(island_removal_mode 0)
		)
		(polygon
			(pts
				(xy 255.24968 -41.1353) (xy 255.24968 -38.95852) (xy 253.48946 -38.95852) (xy 253.48946 -41.1353)
			)
		)
	)
	(zone
		(layer "In4.Cu")
		(hatch none 0.5)
		(connect_pads
			(clearance 0)
		)
		(min_thickness 0.25)
		(keepout
			(tracks allowed)
			(vias allowed)
			(pads allowed)
			(copperpour allowed)
			(footprints allowed)
		)
		(placement
			(enabled no)
			(sheetname "")
		)
		(fill
			(thermal_gap 0.5)
			(thermal_bridge_width 0.5)
			(island_removal_mode 0)
		)
		(polygon
			(pts
				(xy 298.793662 -286.433514) (xy 298.793662 -285.078678) (xy 299.270928 -285.078678) (xy 299.270928 -286.433514)
			)
		)
	)
	(zone
		(layer "In4.Cu")
		(hatch none 0.5)
		(connect_pads
			(clearance 0)
		)
		(min_thickness 0.25)
		(keepout
			(tracks allowed)
			(vias allowed)
			(pads allowed)
			(copperpour allowed)
			(footprints allowed)
		)
		(placement
			(enabled no)
			(sheetname "")
		)
		(fill
			(thermal_gap 0.5)
			(thermal_bridge_width 0.5)
			(island_removal_mode 0)
		)
		(polygon
			(pts
				(xy 296.53738 -244.339618) (xy 296.53738 -242.929918) (xy 297.07586 -242.929918) (xy 297.07586 -244.339618)
			)
		)
	)
	(zone
		(layer "In4.Cu")
		(hatch none 0.5)
		(connect_pads
			(clearance 0)
		)
		(min_thickness 0.25)
		(keepout
			(tracks allowed)
			(vias allowed)
			(pads allowed)
			(copperpour allowed)
			(footprints allowed)
		)
		(placement
			(enabled no)
			(sheetname "")
		)
		(fill
			(thermal_gap 0.5)
			(thermal_bridge_width 0.5)
			(island_removal_mode 0)
		)
		(polygon
			(pts
				(xy 279.581102 -267.279374) (xy 279.581102 -265.924538) (xy 280.058368 -265.924538) (xy 280.058368 -267.279374)
			)
		)
	)
	(zone
		(layer "In4.Cu")
		(hatch none 0.5)
		(connect_pads
			(clearance 0)
		)
		(min_thickness 0.25)
		(keepout
			(tracks allowed)
			(vias allowed)
			(pads allowed)
			(copperpour allowed)
			(footprints allowed)
		)
		(placement
			(enabled no)
			(sheetname "")
		)
		(fill
			(thermal_gap 0.5)
			(thermal_bridge_width 0.5)
			(island_removal_mode 0)
		)
		(polygon
			(pts
				(xy 283.68625 -208.603596) (xy 283.68625 -207.24876) (xy 284.163516 -207.24876) (xy 284.163516 -208.603596)
			)
		)
	)
	(zone
		(layer "In4.Cu")
		(hatch none 0.5)
		(connect_pads
			(clearance 0)
		)
		(min_thickness 0.25)
		(keepout
			(tracks allowed)
			(vias allowed)
			(pads allowed)
			(copperpour allowed)
			(footprints allowed)
		)
		(placement
			(enabled no)
			(sheetname "")
		)
		(fill
			(thermal_gap 0.5)
			(thermal_bridge_width 0.5)
			(island_removal_mode 0)
		)
		(polygon
			(pts
				(xy 52.010564 -195.763896) (xy 52.010564 -194.552316) (xy 52.569364 -194.552316) (xy 52.569364 -195.763896)
			)
		)
	)
	(zone
		(layer "In4.Cu")
		(hatch none 0.5)
		(connect_pads
			(clearance 0)
		)
		(min_thickness 0.25)
		(keepout
			(tracks allowed)
			(vias allowed)
			(pads allowed)
			(copperpour allowed)
			(footprints allowed)
		)
		(placement
			(enabled no)
			(sheetname "")
		)
		(fill
			(thermal_gap 0.5)
			(thermal_bridge_width 0.5)
			(island_removal_mode 0)
		)
		(polygon
			(pts
				(xy 35.745674 -246.895874) (xy 35.745674 -245.541038) (xy 36.22294 -245.541038) (xy 36.22294 -246.895874)
			)
		)
	)
	(zone
		(layer "In4.Cu")
		(hatch none 0.5)
		(connect_pads
			(clearance 0)
		)
		(min_thickness 0.25)
		(keepout
			(tracks allowed)
			(vias allowed)
			(pads allowed)
			(copperpour allowed)
			(footprints allowed)
		)
		(placement
			(enabled no)
			(sheetname "")
		)
		(fill
			(thermal_gap 0.5)
			(thermal_bridge_width 0.5)
			(island_removal_mode 0)
		)
		(polygon
			(pts
				(xy 283.685742 -246.895874) (xy 283.685742 -245.541038) (xy 284.163008 -245.541038) (xy 284.163008 -246.895874)
			)
		)
	)
	(zone
		(layer "In4.Cu")
		(hatch none 0.5)
		(connect_pads
			(clearance 0)
		)
		(min_thickness 0.25)
		(keepout
			(tracks allowed)
			(vias allowed)
			(pads allowed)
			(copperpour allowed)
			(footprints allowed)
		)
		(placement
			(enabled no)
			(sheetname "")
		)
		(fill
			(thermal_gap 0.5)
			(thermal_bridge_width 0.5)
			(island_removal_mode 0)
		)
		(polygon
			(pts
				(xy 283.683202 -251.528834) (xy 283.683202 -250.173998) (xy 284.160468 -250.173998) (xy 284.160468 -251.528834)
			)
		)
	)
	(zone
		(layer "In4.Cu")
		(hatch none 0.5)
		(connect_pads
			(clearance 0)
		)
		(min_thickness 0.25)
		(keepout
			(tracks allowed)
			(vias allowed)
			(pads allowed)
			(copperpour allowed)
			(footprints allowed)
		)
		(placement
			(enabled no)
			(sheetname "")
		)
		(fill
			(thermal_gap 0.5)
			(thermal_bridge_width 0.5)
			(island_removal_mode 0)
		)
		(polygon
			(pts
				(xy 48.579024 -268.077696) (xy 48.579024 -265.946636) (xy 49.092104 -265.946636) (xy 49.092104 -268.077696)
			)
		)
	)
	(zone
		(layer "In4.Cu")
		(hatch none 0.5)
		(connect_pads
			(clearance 0)
		)
		(min_thickness 0.25)
		(keepout
			(tracks allowed)
			(vias allowed)
			(pads allowed)
			(copperpour allowed)
			(footprints allowed)
		)
		(placement
			(enabled no)
			(sheetname "")
		)
		(fill
			(thermal_gap 0.5)
			(thermal_bridge_width 0.5)
			(island_removal_mode 0)
		)
		(polygon
			(pts
				(xy 148.37918 -11.00328) (xy 148.37918 -9.30656) (xy 147.27682 -9.30656) (xy 147.27682 -11.00328)
			)
		)
	)
	(zone
		(layer "In4.Cu")
		(hatch none 0.5)
		(connect_pads
			(clearance 0)
		)
		(min_thickness 0.25)
		(keepout
			(tracks allowed)
			(vias allowed)
			(pads allowed)
			(copperpour allowed)
			(footprints allowed)
		)
		(placement
			(enabled no)
			(sheetname "")
		)
		(fill
			(thermal_gap 0.5)
			(thermal_bridge_width 0.5)
			(island_removal_mode 0)
		)
		(polygon
			(pts
				(xy 50.826162 -302.240696) (xy 50.826162 -300.88586) (xy 51.303428 -300.88586) (xy 51.303428 -302.240696)
			)
		)
	)
	(zone
		(layer "In4.Cu")
		(hatch none 0.5)
		(connect_pads
			(clearance 0)
		)
		(min_thickness 0.25)
		(keepout
			(tracks allowed)
			(vias allowed)
			(pads allowed)
			(copperpour allowed)
			(footprints allowed)
		)
		(placement
			(enabled no)
			(sheetname "")
		)
		(fill
			(thermal_gap 0.5)
			(thermal_bridge_width 0.5)
			(island_removal_mode 0)
		)
		(polygon
			(pts
				(xy 120.88368 -15.79626) (xy 120.88368 -13.86586) (xy 121.91492 -13.86586) (xy 121.91492 -15.79626)
			)
		)
	)
	(zone
		(layer "In4.Cu")
		(hatch none 0.5)
		(connect_pads
			(clearance 0)
		)
		(min_thickness 0.25)
		(keepout
			(tracks allowed)
			(vias allowed)
			(pads allowed)
			(copperpour allowed)
			(footprints allowed)
		)
		(placement
			(enabled no)
			(sheetname "")
		)
		(fill
			(thermal_gap 0.5)
			(thermal_bridge_width 0.5)
			(island_removal_mode 0)
		)
		(polygon
			(pts
				(xy 187.648342 -206.901542) (xy 187.648342 -205.546706) (xy 188.125608 -205.546706) (xy 188.125608 -206.901542)
			)
		)
	)
	(zone
		(layer "In4.Cu")
		(hatch none 0.5)
		(connect_pads
			(clearance 0)
		)
		(min_thickness 0.25)
		(keepout
			(tracks allowed)
			(vias allowed)
			(pads allowed)
			(copperpour allowed)
			(footprints allowed)
		)
		(placement
			(enabled no)
			(sheetname "")
		)
		(fill
			(thermal_gap 0.5)
			(thermal_bridge_width 0.5)
			(island_removal_mode 0)
		)
		(polygon
			(pts
				(xy 255.74498 -39.19474) (xy 255.74498 -37.55898) (xy 258.35356 -37.55898) (xy 258.35356 -39.19474)
			)
		)
	)
	(zone
		(layer "In4.Cu")
		(hatch none 0.5)
		(connect_pads
			(clearance 0)
		)
		(min_thickness 0.25)
		(keepout
			(tracks allowed)
			(vias allowed)
			(pads allowed)
			(copperpour allowed)
			(footprints allowed)
		)
		(placement
			(enabled no)
			(sheetname "")
		)
		(fill
			(thermal_gap 0.5)
			(thermal_bridge_width 0.5)
			(island_removal_mode 0)
		)
		(polygon
			(pts
				(xy 283.68625 -309.764176) (xy 283.68625 -308.40934) (xy 284.163516 -308.40934) (xy 284.163516 -309.764176)
			)
		)
	)
	(zone
		(layer "In4.Cu")
		(hatch none 0.5)
		(connect_pads
			(clearance 0)
		)
		(min_thickness 0.25)
		(keepout
			(tracks allowed)
			(vias allowed)
			(pads allowed)
			(copperpour allowed)
			(footprints allowed)
		)
		(placement
			(enabled no)
			(sheetname "")
		)
		(fill
			(thermal_gap 0.5)
			(thermal_bridge_width 0.5)
			(island_removal_mode 0)
		)
		(polygon
			(pts
				(xy 435.578504 -316.6872) (xy 435.578504 -315.332364) (xy 436.05577 -315.332364) (xy 436.05577 -316.6872)
			)
		)
	)
	(zone
		(layer "In4.Cu")
		(hatch none 0.5)
		(connect_pads
			(clearance 0)
		)
		(min_thickness 0.25)
		(keepout
			(tracks allowed)
			(vias allowed)
			(pads allowed)
			(copperpour allowed)
			(footprints allowed)
		)
		(placement
			(enabled no)
			(sheetname "")
		)
		(fill
			(thermal_gap 0.5)
			(thermal_bridge_width 0.5)
			(island_removal_mode 0)
		)
		(polygon
			(pts
				(xy 170.7388 -358.216708) (xy 170.7388 -357.043228) (xy 172.48124 -357.043228) (xy 172.48124 -358.216708)
			)
		)
	)
	(zone
		(layer "In4.Cu")
		(hatch none 0.5)
		(connect_pads
			(clearance 0)
		)
		(min_thickness 0.25)
		(keepout
			(tracks allowed)
			(vias allowed)
			(pads allowed)
			(copperpour allowed)
			(footprints allowed)
		)
		(placement
			(enabled no)
			(sheetname "")
		)
		(fill
			(thermal_gap 0.5)
			(thermal_bridge_width 0.5)
			(island_removal_mode 0)
		)
		(polygon
			(pts
				(xy 62.72784 -12.72032) (xy 62.72784 -10.38098) (xy 68.2879 -10.38098) (xy 68.2879 -12.72032)
			)
		)
	)
	(zone
		(layer "In4.Cu")
		(hatch none 0.5)
		(connect_pads
			(clearance 0)
		)
		(min_thickness 0.25)
		(keepout
			(tracks allowed)
			(vias allowed)
			(pads allowed)
			(copperpour allowed)
			(footprints allowed)
		)
		(placement
			(enabled no)
			(sheetname "")
		)
		(fill
			(thermal_gap 0.5)
			(thermal_bridge_width 0.5)
			(island_removal_mode 0)
		)
		(polygon
			(pts
				(xy 343.83218 -20.066) (xy 343.83218 -18.76806) (xy 342.5698 -18.76806) (xy 342.5698 -20.066)
			)
		)
	)
	(zone
		(layer "In4.Cu")
		(hatch none 0.5)
		(connect_pads
			(clearance 0)
		)
		(min_thickness 0.25)
		(keepout
			(tracks allowed)
			(vias allowed)
			(pads allowed)
			(copperpour allowed)
			(footprints allowed)
		)
		(placement
			(enabled no)
			(sheetname "")
		)
		(fill
			(thermal_gap 0.5)
			(thermal_bridge_width 0.5)
			(island_removal_mode 0)
		)
		(polygon
			(pts
				(xy 298.73321 -203.546456) (xy 298.73321 -202.98791) (xy 299.210476 -202.98791) (xy 299.623734 -202.98791)
				(xy 299.69333 -203.057506) (xy 299.69333 -203.473558) (xy 299.620432 -203.546456) (xy 299.210476 -203.546456)
			)
		)
	)
	(zone
		(layer "In4.Cu")
		(hatch none 0.5)
		(connect_pads
			(clearance 0)
		)
		(min_thickness 0.25)
		(keepout
			(tracks allowed)
			(vias allowed)
			(pads allowed)
			(copperpour allowed)
			(footprints allowed)
		)
		(placement
			(enabled no)
			(sheetname "")
		)
		(fill
			(thermal_gap 0.5)
			(thermal_bridge_width 0.5)
			(island_removal_mode 0)
		)
		(polygon
			(pts
				(xy 143.892524 -241.683794) (xy 146.102324 -243.893594) (xy 145.391124 -244.604794) (xy 140.42136 -244.605048)
				(xy 140.42136 -241.927888) (xy 143.648684 -241.927634)
			)
		)
	)
	(zone
		(layer "In4.Cu")
		(hatch none 0.5)
		(connect_pads
			(clearance 0)
		)
		(min_thickness 0.25)
		(keepout
			(tracks allowed)
			(vias allowed)
			(pads allowed)
			(copperpour allowed)
			(footprints allowed)
		)
		(placement
			(enabled no)
			(sheetname "")
		)
		(fill
			(thermal_gap 0.5)
			(thermal_bridge_width 0.5)
			(island_removal_mode 0)
		)
		(polygon
			(pts
				(xy 35.702494 -290.210494) (xy 35.702494 -288.855658) (xy 36.17976 -288.855658) (xy 36.17976 -290.210494)
			)
		)
	)
	(zone
		(layer "In4.Cu")
		(hatch none 0.5)
		(connect_pads
			(clearance 0)
		)
		(min_thickness 0.25)
		(keepout
			(tracks allowed)
			(vias allowed)
			(pads allowed)
			(copperpour allowed)
			(footprints allowed)
		)
		(placement
			(enabled no)
			(sheetname "")
		)
		(fill
			(thermal_gap 0.5)
			(thermal_bridge_width 0.5)
			(island_removal_mode 0)
		)
		(polygon
			(pts
				(xy 130.03784 -12.93622) (xy 130.03784 -10.84326) (xy 129.0447 -10.84326) (xy 129.0447 -12.93622)
			)
		)
	)
	(zone
		(layer "In4.Cu")
		(hatch none 0.5)
		(connect_pads
			(clearance 0)
		)
		(min_thickness 0.25)
		(keepout
			(tracks allowed)
			(vias allowed)
			(pads allowed)
			(copperpour allowed)
			(footprints allowed)
		)
		(placement
			(enabled no)
			(sheetname "")
		)
		(fill
			(thermal_gap 0.5)
			(thermal_bridge_width 0.5)
			(island_removal_mode 0)
		)
		(polygon
			(pts
				(xy 291.129212 -244.229636) (xy 291.129212 -242.903756) (xy 291.667692 -242.903756) (xy 291.667692 -244.229636)
			)
		)
	)
	(zone
		(layer "In4.Cu")
		(hatch none 0.5)
		(connect_pads
			(clearance 0)
		)
		(min_thickness 0.25)
		(keepout
			(tracks allowed)
			(vias allowed)
			(pads allowed)
			(copperpour allowed)
			(footprints allowed)
		)
		(placement
			(enabled no)
			(sheetname "")
		)
		(fill
			(thermal_gap 0.5)
			(thermal_bridge_width 0.5)
			(island_removal_mode 0)
		)
		(polygon
			(pts
				(xy 187.62853 -251.107448) (xy 187.62853 -249.752612) (xy 188.105796 -249.752612) (xy 188.105796 -251.107448)
			)
		)
	)
	(zone
		(layer "In4.Cu")
		(hatch none 0.5)
		(connect_pads
			(clearance 0)
		)
		(min_thickness 0.25)
		(keepout
			(tracks allowed)
			(vias allowed)
			(pads allowed)
			(copperpour allowed)
			(footprints allowed)
		)
		(placement
			(enabled no)
			(sheetname "")
		)
		(fill
			(thermal_gap 0.5)
			(thermal_bridge_width 0.5)
			(island_removal_mode 0)
		)
		(polygon
			(pts
				(xy 309.7784 -233.171238) (xy 309.7784 -223.349058) (xy 310.25592 -223.349058) (xy 310.25592 -233.171238)
			)
		)
	)
	(zone
		(layer "In4.Cu")
		(hatch none 0.5)
		(connect_pads
			(clearance 0)
		)
		(min_thickness 0.25)
		(keepout
			(tracks allowed)
			(vias allowed)
			(pads allowed)
			(copperpour allowed)
			(footprints allowed)
		)
		(placement
			(enabled no)
			(sheetname "")
		)
		(fill
			(thermal_gap 0.5)
			(thermal_bridge_width 0.5)
			(island_removal_mode 0)
		)
		(polygon
			(pts
				(xy 392.014964 -281.669744) (xy 389.237474 -284.447234) (xy 388.617714 -284.447234) (xy 386.738114 -282.567888)
				(xy 386.738114 -281.940508) (xy 387.014974 -281.663648) (xy 387.014974 -281.44343) (xy 387.760464 -280.69794)
				(xy 387.760464 -280.625804) (xy 387.343904 -280.209244) (xy 387.343396 -280.209244) (xy 387.343396 -280.186384)
				(xy 388.775956 -278.753824) (xy 388.775956 -278.632666) (xy 387.506972 -277.363682) (xy 387.506972 -277.346156)
				(xy 387.909054 -276.944074) (xy 387.909054 -276.91461) (xy 387.187948 -276.193504) (xy 387.187948 -276.14753)
				(xy 387.78815 -275.547328) (xy 387.886194 -275.645372) (xy 388.884414 -276.643592) (xy 388.986014 -276.745192)
				(xy 392.943334 -280.702512) (xy 392.943334 -280.741374)
			)
		)
	)
	(zone
		(layer "In4.Cu")
		(hatch none 0.5)
		(connect_pads
			(clearance 0)
		)
		(min_thickness 0.25)
		(keepout
			(tracks allowed)
			(vias allowed)
			(pads allowed)
			(copperpour allowed)
			(footprints allowed)
		)
		(placement
			(enabled no)
			(sheetname "")
		)
		(fill
			(thermal_gap 0.5)
			(thermal_bridge_width 0.5)
			(island_removal_mode 0)
		)
		(polygon
			(pts
				(xy 420.480998 -231.557576) (xy 420.480998 -230.20274) (xy 420.958264 -230.20274) (xy 420.958264 -231.557576)
				(xy 420.958264 -232.501694) (xy 420.160704 -232.501694) (xy 420.160704 -231.557576)
			)
		)
	)
	(zone
		(layer "In4.Cu")
		(hatch none 0.5)
		(connect_pads
			(clearance 0)
		)
		(min_thickness 0.25)
		(keepout
			(tracks allowed)
			(vias allowed)
			(pads allowed)
			(copperpour allowed)
			(footprints allowed)
		)
		(placement
			(enabled no)
			(sheetname "")
		)
		(fill
			(thermal_gap 0.5)
			(thermal_bridge_width 0.5)
			(island_removal_mode 0)
		)
		(polygon
			(pts
				(xy 92.0496 -292.992048) (xy 92.0496 -290.553648) (xy 101.74224 -290.553648) (xy 101.74224 -292.992048)
			)
		)
	)
	(zone
		(layer "In4.Cu")
		(hatch none 0.5)
		(connect_pads
			(clearance 0)
		)
		(min_thickness 0.25)
		(keepout
			(tracks allowed)
			(vias allowed)
			(pads allowed)
			(copperpour allowed)
			(footprints allowed)
		)
		(placement
			(enabled no)
			(sheetname "")
		)
		(fill
			(thermal_gap 0.5)
			(thermal_bridge_width 0.5)
			(island_removal_mode 0)
		)
		(polygon
			(pts
				(xy 35.725862 -294.148256) (xy 35.725862 -292.79342) (xy 36.203128 -292.79342) (xy 36.203128 -294.148256)
			)
		)
	)
	(zone
		(layer "In4.Cu")
		(hatch none 0.5)
		(connect_pads
			(clearance 0)
		)
		(min_thickness 0.25)
		(keepout
			(tracks allowed)
			(vias allowed)
			(pads allowed)
			(copperpour allowed)
			(footprints allowed)
		)
		(placement
			(enabled no)
			(sheetname "")
		)
		(fill
			(thermal_gap 0.5)
			(thermal_bridge_width 0.5)
			(island_removal_mode 0)
		)
		(polygon
			(pts
				(xy 357.46182 -44.3103) (xy 357.46182 -43.10126) (xy 360.67492 -43.10126) (xy 360.67492 -44.3103)
			)
		)
	)
	(zone
		(layer "In4.Cu")
		(hatch none 0.5)
		(connect_pads
			(clearance 0)
		)
		(min_thickness 0.25)
		(keepout
			(tracks allowed)
			(vias allowed)
			(pads allowed)
			(copperpour allowed)
			(footprints allowed)
		)
		(placement
			(enabled no)
			(sheetname "")
		)
		(fill
			(thermal_gap 0.5)
			(thermal_bridge_width 0.5)
			(island_removal_mode 0)
		)
		(polygon
			(pts
				(xy 283.65323 -298.722796) (xy 283.65323 -297.36796) (xy 284.130496 -297.36796) (xy 284.130496 -298.722796)
			)
		)
	)
	(zone
		(layer "In4.Cu")
		(hatch none 0.5)
		(connect_pads
			(clearance 0)
		)
		(min_thickness 0.25)
		(keepout
			(tracks allowed)
			(vias allowed)
			(pads allowed)
			(copperpour allowed)
			(footprints allowed)
		)
		(placement
			(enabled no)
			(sheetname "")
		)
		(fill
			(thermal_gap 0.5)
			(thermal_bridge_width 0.5)
			(island_removal_mode 0)
		)
		(polygon
			(pts
				(xy 172.560742 -281.701748) (xy 172.560742 -280.346912) (xy 173.038008 -280.346912) (xy 173.038008 -281.701748)
			)
		)
	)
	(zone
		(layer "In4.Cu")
		(hatch none 0.5)
		(connect_pads
			(clearance 0)
		)
		(min_thickness 0.25)
		(keepout
			(tracks allowed)
			(vias allowed)
			(pads allowed)
			(copperpour allowed)
			(footprints allowed)
		)
		(placement
			(enabled no)
			(sheetname "")
		)
		(fill
			(thermal_gap 0.5)
			(thermal_bridge_width 0.5)
			(island_removal_mode 0)
		)
		(polygon
			(pts
				(xy 79.82966 -344.594688) (xy 79.82966 -343.012268) (xy 81.55432 -343.012268) (xy 81.55432 -344.594688)
			)
		)
	)
	(zone
		(layer "In4.Cu")
		(hatch none 0.5)
		(connect_pads
			(clearance 0)
		)
		(min_thickness 0.25)
		(keepout
			(tracks allowed)
			(vias allowed)
			(pads allowed)
			(copperpour allowed)
			(footprints allowed)
		)
		(placement
			(enabled no)
			(sheetname "")
		)
		(fill
			(thermal_gap 0.5)
			(thermal_bridge_width 0.5)
			(island_removal_mode 0)
		)
		(polygon
			(pts
				(xy 49.58588 -232.159048) (xy 49.58588 -229.420928) (xy 53.2892 -229.420928) (xy 53.2892 -232.159048)
			)
		)
	)
	(zone
		(layer "In4.Cu")
		(hatch none 0.5)
		(connect_pads
			(clearance 0)
		)
		(min_thickness 0.25)
		(keepout
			(tracks allowed)
			(vias allowed)
			(pads allowed)
			(copperpour allowed)
			(footprints allowed)
		)
		(placement
			(enabled no)
			(sheetname "")
		)
		(fill
			(thermal_gap 0.5)
			(thermal_bridge_width 0.5)
			(island_removal_mode 0)
		)
		(polygon
			(pts
				(xy 435.568598 -249.407426) (xy 435.568598 -248.05259) (xy 436.045864 -248.05259) (xy 436.045864 -249.407426)
			)
		)
	)
	(zone
		(layer "In4.Cu")
		(hatch none 0.5)
		(connect_pads
			(clearance 0)
		)
		(min_thickness 0.25)
		(keepout
			(tracks allowed)
			(vias allowed)
			(pads allowed)
			(copperpour allowed)
			(footprints allowed)
		)
		(placement
			(enabled no)
			(sheetname "")
		)
		(fill
			(thermal_gap 0.5)
			(thermal_bridge_width 0.5)
			(island_removal_mode 0)
		)
		(polygon
			(pts
				(xy 435.58841 -297.851576) (xy 435.58841 -296.49674) (xy 436.065676 -296.49674) (xy 436.065676 -297.851576)
			)
		)
	)
	(zone
		(layer "In4.Cu")
		(hatch none 0.5)
		(connect_pads
			(clearance 0)
		)
		(min_thickness 0.25)
		(keepout
			(tracks allowed)
			(vias allowed)
			(pads allowed)
			(copperpour allowed)
			(footprints allowed)
		)
		(placement
			(enabled no)
			(sheetname "")
		)
		(fill
			(thermal_gap 0.5)
			(thermal_bridge_width 0.5)
			(island_removal_mode 0)
		)
		(polygon
			(pts
				(xy 172.54093 -202.657456) (xy 172.54093 -200.41616) (xy 173.018196 -200.41616) (xy 173.018196 -202.657456)
			)
		)
	)
	(zone
		(layer "In4.Cu")
		(hatch none 0.5)
		(connect_pads
			(clearance 0)
		)
		(min_thickness 0.25)
		(keepout
			(tracks allowed)
			(vias allowed)
			(pads allowed)
			(copperpour allowed)
			(footprints allowed)
		)
		(placement
			(enabled no)
			(sheetname "")
		)
		(fill
			(thermal_gap 0.5)
			(thermal_bridge_width 0.5)
			(island_removal_mode 0)
		)
		(polygon
			(pts
				(xy 187.648342 -269.800578) (xy 187.648342 -268.92504) (xy 187.22467 -268.92504) (xy 187.22467 -267.596874)
				(xy 187.648342 -267.596874) (xy 188.125608 -267.596874) (xy 188.125608 -269.800578)
			)
		)
	)
	(zone
		(layer "In4.Cu")
		(hatch none 0.5)
		(connect_pads
			(clearance 0)
		)
		(min_thickness 0.25)
		(keepout
			(tracks allowed)
			(vias allowed)
			(pads allowed)
			(copperpour allowed)
			(footprints allowed)
		)
		(placement
			(enabled no)
			(sheetname "")
		)
		(fill
			(thermal_gap 0.5)
			(thermal_bridge_width 0.5)
			(island_removal_mode 0)
		)
		(polygon
			(pts
				(xy 157.42793 -305.50739) (xy 157.42793 -304.152554) (xy 157.42793 -303.426368) (xy 157.905196 -303.426368)
				(xy 157.905196 -304.152554) (xy 157.905196 -305.50739)
			)
		)
	)
	(zone
		(layer "In4.Cu")
		(hatch none 0.5)
		(connect_pads
			(clearance 0)
		)
		(min_thickness 0.25)
		(keepout
			(tracks allowed)
			(vias allowed)
			(pads allowed)
			(copperpour allowed)
			(footprints allowed)
		)
		(placement
			(enabled no)
			(sheetname "")
		)
		(fill
			(thermal_gap 0.5)
			(thermal_bridge_width 0.5)
			(island_removal_mode 0)
		)
		(polygon
			(pts
				(xy 439.668666 -248.557542) (xy 439.668666 -247.202706) (xy 440.145932 -247.202706) (xy 440.145932 -248.557542)
			)
		)
	)
	(zone
		(layer "In4.Cu")
		(hatch none 0.5)
		(connect_pads
			(clearance 0)
		)
		(min_thickness 0.25)
		(keepout
			(tracks allowed)
			(vias allowed)
			(pads allowed)
			(copperpour allowed)
			(footprints allowed)
		)
		(placement
			(enabled no)
			(sheetname "")
		)
		(fill
			(thermal_gap 0.5)
			(thermal_bridge_width 0.5)
			(island_removal_mode 0)
		)
		(polygon
			(pts
				(xy 296.638472 -261.252716) (xy 296.638472 -258.298696) (xy 296.994072 -258.298696) (xy 296.994072 -261.252716)
			)
		)
	)
	(zone
		(layer "In4.Cu")
		(hatch none 0.5)
		(connect_pads
			(clearance 0)
		)
		(min_thickness 0.25)
		(keepout
			(tracks allowed)
			(vias allowed)
			(pads allowed)
			(copperpour allowed)
			(footprints allowed)
		)
		(placement
			(enabled no)
			(sheetname "")
		)
		(fill
			(thermal_gap 0.5)
			(thermal_bridge_width 0.5)
			(island_removal_mode 0)
		)
		(polygon
			(pts
				(xy 46.46168 -300.421548) (xy 46.46168 -298.935648) (xy 47.92726 -298.935648) (xy 47.92726 -300.421548)
			)
		)
	)
	(zone
		(layer "In4.Cu")
		(hatch none 0.5)
		(connect_pads
			(clearance 0)
		)
		(min_thickness 0.25)
		(keepout
			(tracks allowed)
			(vias allowed)
			(pads allowed)
			(copperpour allowed)
			(footprints allowed)
		)
		(placement
			(enabled no)
			(sheetname "")
		)
		(fill
			(thermal_gap 0.5)
			(thermal_bridge_width 0.5)
			(island_removal_mode 0)
		)
		(polygon
			(pts
				(xy 172.560742 -223.901508) (xy 172.560742 -222.546672) (xy 173.038008 -222.546672) (xy 173.038008 -223.901508)
			)
		)
	)
	(zone
		(layer "In4.Cu")
		(hatch none 0.5)
		(connect_pads
			(clearance 0)
		)
		(min_thickness 0.25)
		(keepout
			(tracks allowed)
			(vias allowed)
			(pads allowed)
			(copperpour allowed)
			(footprints allowed)
		)
		(placement
			(enabled no)
			(sheetname "")
		)
		(fill
			(thermal_gap 0.5)
			(thermal_bridge_width 0.5)
			(island_removal_mode 0)
		)
		(polygon
			(pts
				(xy 39.168324 -245.100856) (xy 39.168324 -242.967256) (xy 39.605204 -242.967256) (xy 39.605204 -245.100856)
			)
		)
	)
	(zone
		(layer "In4.Cu")
		(hatch none 0.5)
		(connect_pads
			(clearance 0)
		)
		(min_thickness 0.25)
		(keepout
			(tracks allowed)
			(vias allowed)
			(pads allowed)
			(copperpour allowed)
			(footprints allowed)
		)
		(placement
			(enabled no)
			(sheetname "")
		)
		(fill
			(thermal_gap 0.5)
			(thermal_bridge_width 0.5)
			(island_removal_mode 0)
		)
		(polygon
			(pts
				(xy 435.568598 -269.80642) (xy 435.568598 -268.930882) (xy 435.144926 -268.930882) (xy 435.144926 -267.602716)
				(xy 435.568598 -267.602716) (xy 436.045864 -267.602716) (xy 436.045864 -269.80642)
			)
		)
	)
	(zone
		(layer "In4.Cu")
		(hatch none 0.5)
		(connect_pads
			(clearance 0)
		)
		(min_thickness 0.25)
		(keepout
			(tracks allowed)
			(vias allowed)
			(pads allowed)
			(copperpour allowed)
			(footprints allowed)
		)
		(placement
			(enabled no)
			(sheetname "")
		)
		(fill
			(thermal_gap 0.5)
			(thermal_bridge_width 0.5)
			(island_removal_mode 0)
		)
		(polygon
			(pts
				(xy 191.74841 -246.00154) (xy 191.74841 -244.646704) (xy 192.225676 -244.646704) (xy 192.225676 -246.00154)
			)
		)
	)
	(zone
		(layer "In4.Cu")
		(hatch none 0.5)
		(connect_pads
			(clearance 0)
		)
		(min_thickness 0.25)
		(keepout
			(tracks allowed)
			(vias allowed)
			(pads allowed)
			(copperpour allowed)
			(footprints allowed)
		)
		(placement
			(enabled no)
			(sheetname "")
		)
		(fill
			(thermal_gap 0.5)
			(thermal_bridge_width 0.5)
			(island_removal_mode 0)
		)
		(polygon
			(pts
				(xy 191.74841 -248.5517) (xy 191.74841 -247.196864) (xy 192.225676 -247.196864) (xy 192.225676 -248.5517)
			)
		)
	)
	(zone
		(layer "In4.Cu")
		(hatch none 0.5)
		(connect_pads
			(clearance 0)
		)
		(min_thickness 0.25)
		(keepout
			(tracks allowed)
			(vias allowed)
			(pads allowed)
			(copperpour allowed)
			(footprints allowed)
		)
		(placement
			(enabled no)
			(sheetname "")
		)
		(fill
			(thermal_gap 0.5)
			(thermal_bridge_width 0.5)
			(island_removal_mode 0)
		)
		(polygon
			(pts
				(xy 50.858674 -195.836794) (xy 50.858674 -194.481958) (xy 51.33594 -194.481958) (xy 51.33594 -195.836794)
			)
		)
	)
	(zone
		(layer "In4.Cu")
		(hatch none 0.5)
		(connect_pads
			(clearance 0)
		)
		(min_thickness 0.25)
		(keepout
			(tracks allowed)
			(vias allowed)
			(pads allowed)
			(copperpour allowed)
			(footprints allowed)
		)
		(placement
			(enabled no)
			(sheetname "")
		)
		(fill
			(thermal_gap 0.5)
			(thermal_bridge_width 0.5)
			(island_removal_mode 0)
		)
		(polygon
			(pts
				(xy 50.833782 -286.439356) (xy 50.833782 -285.08452) (xy 51.311048 -285.08452) (xy 51.311048 -286.439356)
			)
		)
	)
	(zone
		(layer "In4.Cu")
		(hatch none 0.5)
		(connect_pads
			(clearance 0)
		)
		(min_thickness 0.25)
		(keepout
			(tracks allowed)
			(vias allowed)
			(pads allowed)
			(copperpour allowed)
			(footprints allowed)
		)
		(placement
			(enabled no)
			(sheetname "")
		)
		(fill
			(thermal_gap 0.5)
			(thermal_bridge_width 0.5)
			(island_removal_mode 0)
		)
		(polygon
			(pts
				(xy 191.679576 -268.83614) (xy 191.679576 -267.481304) (xy 192.156842 -267.481304) (xy 192.156842 -268.83614)
			)
		)
	)
	(zone
		(layer "In4.Cu")
		(hatch none 0.5)
		(connect_pads
			(clearance 0)
		)
		(min_thickness 0.25)
		(keepout
			(tracks allowed)
			(vias allowed)
			(pads allowed)
			(copperpour allowed)
			(footprints allowed)
		)
		(placement
			(enabled no)
			(sheetname "")
		)
		(fill
			(thermal_gap 0.5)
			(thermal_bridge_width 0.5)
			(island_removal_mode 0)
		)
		(polygon
			(pts
				(xy 52.040282 -318.949578) (xy 52.040282 -317.594742) (xy 52.517548 -317.594742) (xy 52.517548 -318.949578)
			)
		)
	)
	(zone
		(layer "In4.Cu")
		(hatch none 0.5)
		(connect_pads
			(clearance 0)
		)
		(min_thickness 0.25)
		(keepout
			(tracks allowed)
			(vias allowed)
			(pads allowed)
			(copperpour allowed)
			(footprints allowed)
		)
		(placement
			(enabled no)
			(sheetname "")
		)
		(fill
			(thermal_gap 0.5)
			(thermal_bridge_width 0.5)
			(island_removal_mode 0)
		)
		(polygon
			(pts
				(xy 425.078144 -287.147) (xy 425.078144 -288.501836) (xy 424.600878 -288.501836) (xy 424.433492 -288.501836)
				(xy 423.94124 -288.501836) (xy 423.94124 -286.813498) (xy 425.078144 -286.813498)
			)
		)
	)
	(zone
		(layer "In4.Cu")
		(hatch none 0.5)
		(connect_pads
			(clearance 0)
		)
		(min_thickness 0.25)
		(keepout
			(tracks allowed)
			(vias allowed)
			(pads allowed)
			(copperpour allowed)
			(footprints allowed)
		)
		(placement
			(enabled no)
			(sheetname "")
		)
		(fill
			(thermal_gap 0.5)
			(thermal_bridge_width 0.5)
			(island_removal_mode 0)
		)
		(polygon
			(pts
				(xy 138.73988 -263.529318) (xy 138.73988 -263.399524) (xy 138.795506 -263.343898) (xy 141.605 -263.343898)
				(xy 141.790166 -263.529064) (xy 142.834614 -264.573512) (xy 142.938246 -264.573512) (xy 143.04391 -264.679176)
				(xy 143.04391 -265.291316) (xy 143.04391 -267.449808) (xy 143.034766 -267.458952) (xy 143.034766 -267.878052)
				(xy 143.001746 -267.911072) (xy 143.001746 -269.214092) (xy 143.354806 -269.567152) (xy 143.354806 -271.040352)
				(xy 143.237966 -271.157192) (xy 142.884906 -271.157192) (xy 139.622784 -267.89507) (xy 139.622784 -267.10386)
				(xy 139.573508 -267.054584) (xy 138.748262 -267.054584) (xy 138.73988 -267.046202)
			)
		)
	)
	(zone
		(layer "In4.Cu")
		(hatch none 0.5)
		(connect_pads
			(clearance 0)
		)
		(min_thickness 0.25)
		(keepout
			(tracks allowed)
			(vias allowed)
			(pads allowed)
			(copperpour allowed)
			(footprints allowed)
		)
		(placement
			(enabled no)
			(sheetname "")
		)
		(fill
			(thermal_gap 0.5)
			(thermal_bridge_width 0.5)
			(island_removal_mode 0)
		)
		(polygon
			(pts
				(xy 65.795652 -232.404158) (xy 65.795652 -223.412558) (xy 66.397632 -223.412558) (xy 66.397632 -232.404158)
			)
		)
	)
	(zone
		(layer "In4.Cu")
		(hatch none 0.5)
		(connect_pads
			(clearance 0)
		)
		(min_thickness 0.25)
		(keepout
			(tracks allowed)
			(vias allowed)
			(pads allowed)
			(copperpour allowed)
			(footprints allowed)
		)
		(placement
			(enabled no)
			(sheetname "")
		)
		(fill
			(thermal_gap 0.5)
			(thermal_bridge_width 0.5)
			(island_removal_mode 0)
		)
		(polygon
			(pts
				(xy 35.727894 -266.438634) (xy 35.727894 -265.083798) (xy 36.20516 -265.083798) (xy 36.20516 -266.438634)
			)
		)
	)
	(zone
		(layer "In4.Cu")
		(hatch none 0.5)
		(connect_pads
			(clearance 0)
		)
		(min_thickness 0.25)
		(keepout
			(tracks allowed)
			(vias allowed)
			(pads allowed)
			(copperpour allowed)
			(footprints allowed)
		)
		(placement
			(enabled no)
			(sheetname "")
		)
		(fill
			(thermal_gap 0.5)
			(thermal_bridge_width 0.5)
			(island_removal_mode 0)
		)
		(polygon
			(pts
				(xy 172.54093 -225.607372) (xy 172.54093 -224.252536) (xy 173.018196 -224.252536) (xy 173.018196 -225.607372)
			)
		)
	)
	(zone
		(layer "In4.Cu")
		(hatch none 0.5)
		(connect_pads
			(clearance 0)
		)
		(min_thickness 0.25)
		(keepout
			(tracks allowed)
			(vias allowed)
			(pads allowed)
			(copperpour allowed)
			(footprints allowed)
		)
		(placement
			(enabled no)
			(sheetname "")
		)
		(fill
			(thermal_gap 0.5)
			(thermal_bridge_width 0.5)
			(island_removal_mode 0)
		)
		(polygon
			(pts
				(xy 420.480998 -285.957518) (xy 420.480998 -284.602682) (xy 420.958264 -284.602682) (xy 420.958264 -285.957518)
			)
		)
	)
	(zone
		(layer "In4.Cu")
		(hatch none 0.5)
		(connect_pads
			(clearance 0)
		)
		(min_thickness 0.25)
		(keepout
			(tracks allowed)
			(vias allowed)
			(pads allowed)
			(copperpour allowed)
			(footprints allowed)
		)
		(placement
			(enabled no)
			(sheetname "")
		)
		(fill
			(thermal_gap 0.5)
			(thermal_bridge_width 0.5)
			(island_removal_mode 0)
		)
		(polygon
			(pts
				(xy 133.80212 -347.543628) (xy 133.80212 -344.043508) (xy 138.02614 -344.043508) (xy 138.02614 -347.543628)
			)
		)
	)
	(zone
		(layer "In4.Cu")
		(hatch none 0.5)
		(connect_pads
			(clearance 0)
		)
		(min_thickness 0.25)
		(keepout
			(tracks allowed)
			(vias allowed)
			(pads allowed)
			(copperpour allowed)
			(footprints allowed)
		)
		(placement
			(enabled no)
			(sheetname "")
		)
		(fill
			(thermal_gap 0.5)
			(thermal_bridge_width 0.5)
			(island_removal_mode 0)
		)
		(polygon
			(pts
				(xy 191.728598 -248.557542) (xy 191.728598 -247.202706) (xy 192.205864 -247.202706) (xy 192.205864 -248.557542)
			)
		)
	)
	(zone
		(layer "In4.Cu")
		(hatch none 0.5)
		(connect_pads
			(clearance 0)
		)
		(min_thickness 0.25)
		(keepout
			(tracks allowed)
			(vias allowed)
			(pads allowed)
			(copperpour allowed)
			(footprints allowed)
		)
		(placement
			(enabled no)
			(sheetname "")
		)
		(fill
			(thermal_gap 0.5)
			(thermal_bridge_width 0.5)
			(island_removal_mode 0)
		)
		(polygon
			(pts
				(xy 36.954968 -319.101978) (xy 36.954968 -317.747142) (xy 37.432234 -317.747142) (xy 37.432234 -319.101978)
			)
		)
	)
	(zone
		(layer "In4.Cu")
		(hatch none 0.5)
		(connect_pads
			(clearance 0)
		)
		(min_thickness 0.25)
		(keepout
			(tracks allowed)
			(vias allowed)
			(pads allowed)
			(copperpour allowed)
			(footprints allowed)
		)
		(placement
			(enabled no)
			(sheetname "")
		)
		(fill
			(thermal_gap 0.5)
			(thermal_bridge_width 0.5)
			(island_removal_mode 0)
		)
		(polygon
			(pts
				(xy 298.775882 -200.977754) (xy 298.775882 -199.622918) (xy 299.253148 -199.622918) (xy 299.253148 -200.977754)
				(xy 299.253148 -201.878692) (xy 298.775882 -201.878692)
			)
		)
	)
	(zone
		(layer "In4.Cu")
		(hatch none 0.5)
		(connect_pads
			(clearance 0)
		)
		(min_thickness 0.25)
		(keepout
			(tracks allowed)
			(vias allowed)
			(pads allowed)
			(copperpour allowed)
			(footprints allowed)
		)
		(placement
			(enabled no)
			(sheetname "")
		)
		(fill
			(thermal_gap 0.5)
			(thermal_bridge_width 0.5)
			(island_removal_mode 0)
		)
		(polygon
			(pts
				(xy 191.728598 -250.257564) (xy 191.728598 -248.902728) (xy 192.205864 -248.902728) (xy 192.205864 -250.257564)
			)
		)
	)
	(zone
		(layer "In4.Cu")
		(hatch none 0.5)
		(connect_pads
			(clearance 0)
		)
		(min_thickness 0.25)
		(keepout
			(tracks allowed)
			(vias allowed)
			(pads allowed)
			(copperpour allowed)
			(footprints allowed)
		)
		(placement
			(enabled no)
			(sheetname "")
		)
		(fill
			(thermal_gap 0.5)
			(thermal_bridge_width 0.5)
			(island_removal_mode 0)
		)
		(polygon
			(pts
				(xy 405.365712 -307.660802) (xy 405.365712 -306.305966) (xy 405.842978 -306.305966) (xy 405.842978 -307.660802)
			)
		)
	)
	(zone
		(layer "In4.Cu")
		(hatch none 0.5)
		(connect_pads
			(clearance 0)
		)
		(min_thickness 0.25)
		(keepout
			(tracks allowed)
			(vias allowed)
			(pads allowed)
			(copperpour allowed)
			(footprints allowed)
		)
		(placement
			(enabled no)
			(sheetname "")
		)
		(fill
			(thermal_gap 0.5)
			(thermal_bridge_width 0.5)
			(island_removal_mode 0)
		)
		(polygon
			(pts
				(xy 327.84034 -344.965528) (xy 327.84034 -343.141808) (xy 329.66406 -343.141808) (xy 329.66406 -344.965528)
			)
		)
	)
	(zone
		(layer "In4.Cu")
		(hatch none 0.5)
		(connect_pads
			(clearance 0)
		)
		(min_thickness 0.25)
		(keepout
			(tracks allowed)
			(vias allowed)
			(pads allowed)
			(copperpour allowed)
			(footprints allowed)
		)
		(placement
			(enabled no)
			(sheetname "")
		)
		(fill
			(thermal_gap 0.5)
			(thermal_bridge_width 0.5)
			(island_removal_mode 0)
		)
		(polygon
			(pts
				(xy 287.08858 -245.106698) (xy 287.08858 -242.973098) (xy 287.52546 -242.973098) (xy 287.52546 -245.106698)
			)
		)
	)
	(zone
		(layer "In4.Cu")
		(hatch none 0.5)
		(connect_pads
			(clearance 0)
		)
		(min_thickness 0.25)
		(keepout
			(tracks allowed)
			(vias allowed)
			(pads allowed)
			(copperpour allowed)
			(footprints allowed)
		)
		(placement
			(enabled no)
			(sheetname "")
		)
		(fill
			(thermal_gap 0.5)
			(thermal_bridge_width 0.5)
			(island_removal_mode 0)
		)
		(polygon
			(pts
				(xy 283.685742 -234.076494) (xy 283.685742 -232.721658) (xy 284.163008 -232.721658) (xy 284.163008 -234.076494)
			)
		)
	)
	(zone
		(layer "In4.Cu")
		(hatch none 0.5)
		(connect_pads
			(clearance 0)
		)
		(min_thickness 0.25)
		(keepout
			(tracks allowed)
			(vias allowed)
			(pads allowed)
			(copperpour allowed)
			(footprints allowed)
		)
		(placement
			(enabled no)
			(sheetname "")
		)
		(fill
			(thermal_gap 0.5)
			(thermal_bridge_width 0.5)
			(island_removal_mode 0)
		)
		(polygon
			(pts
				(xy 187.648342 -267.251688) (xy 187.648342 -265.896852) (xy 188.125608 -265.896852) (xy 188.125608 -267.251688)
			)
		)
	)
	(zone
		(layer "In4.Cu")
		(hatch none 0.5)
		(connect_pads
			(clearance 0)
		)
		(min_thickness 0.25)
		(keepout
			(tracks allowed)
			(vias allowed)
			(pads allowed)
			(copperpour allowed)
			(footprints allowed)
		)
		(placement
			(enabled no)
			(sheetname "")
		)
		(fill
			(thermal_gap 0.5)
			(thermal_bridge_width 0.5)
			(island_removal_mode 0)
		)
		(polygon
			(pts
				(xy 161.497264 -306.741322) (xy 161.497264 -305.386486) (xy 161.97453 -305.386486) (xy 161.97453 -306.741322)
			)
		)
	)
	(zone
		(layer "In4.Cu")
		(hatch none 0.5)
		(connect_pads
			(clearance 0)
		)
		(min_thickness 0.25)
		(keepout
			(tracks allowed)
			(vias allowed)
			(pads allowed)
			(copperpour allowed)
			(footprints allowed)
		)
		(placement
			(enabled no)
			(sheetname "")
		)
		(fill
			(thermal_gap 0.5)
			(thermal_bridge_width 0.5)
			(island_removal_mode 0)
		)
		(polygon
			(pts
				(xy 48.597312 -244.339618) (xy 48.597312 -242.929918) (xy 49.135792 -242.929918) (xy 49.135792 -244.339618)
			)
		)
	)
	(zone
		(layer "In4.Cu")
		(hatch none 0.5)
		(connect_pads
			(clearance 0)
		)
		(min_thickness 0.25)
		(keepout
			(tracks allowed)
			(vias allowed)
			(pads allowed)
			(copperpour allowed)
			(footprints allowed)
		)
		(placement
			(enabled no)
			(sheetname "")
		)
		(fill
			(thermal_gap 0.5)
			(thermal_bridge_width 0.5)
			(island_removal_mode 0)
		)
		(polygon
			(pts
				(xy 159.3723 -11.0236) (xy 159.3723 -9.66978) (xy 160.41878 -9.66978) (xy 160.41878 -11.0236)
			)
		)
	)
	(zone
		(layer "In4.Cu")
		(hatch none 0.5)
		(connect_pads
			(clearance 0)
		)
		(min_thickness 0.25)
		(keepout
			(tracks allowed)
			(vias allowed)
			(pads allowed)
			(copperpour allowed)
			(footprints allowed)
		)
		(placement
			(enabled no)
			(sheetname "")
		)
		(fill
			(thermal_gap 0.5)
			(thermal_bridge_width 0.5)
			(island_removal_mode 0)
		)
		(polygon
			(pts
				(xy 289.000692 -319.10782) (xy 289.000692 -317.752984) (xy 289.477958 -317.752984) (xy 289.477958 -319.10782)
			)
		)
	)
	(zone
		(layer "In4.Cu")
		(hatch none 0.5)
		(connect_pads
			(clearance 0)
		)
		(min_thickness 0.25)
		(keepout
			(tracks allowed)
			(vias allowed)
			(pads allowed)
			(copperpour allowed)
			(footprints allowed)
		)
		(placement
			(enabled no)
			(sheetname "")
		)
		(fill
			(thermal_gap 0.5)
			(thermal_bridge_width 0.5)
			(island_removal_mode 0)
		)
		(polygon
			(pts
				(xy 298.77385 -285.118556) (xy 298.77385 -283.76372) (xy 299.251116 -283.76372) (xy 299.251116 -285.118556)
			)
		)
	)
	(zone
		(layer "In4.Cu")
		(hatch none 0.5)
		(connect_pads
			(clearance 0)
		)
		(min_thickness 0.25)
		(keepout
			(tracks allowed)
			(vias allowed)
			(pads allowed)
			(copperpour allowed)
			(footprints allowed)
		)
		(placement
			(enabled no)
			(sheetname "")
		)
		(fill
			(thermal_gap 0.5)
			(thermal_bridge_width 0.5)
			(island_removal_mode 0)
		)
		(polygon
			(pts
				(xy 435.568598 -297.857418) (xy 435.568598 -296.502582) (xy 436.045864 -296.502582) (xy 436.045864 -297.857418)
			)
		)
	)
	(zone
		(layer "In4.Cu")
		(hatch none 0.5)
		(connect_pads
			(clearance 0)
		)
		(min_thickness 0.25)
		(keepout
			(tracks allowed)
			(vias allowed)
			(pads allowed)
			(copperpour allowed)
			(footprints allowed)
		)
		(placement
			(enabled no)
			(sheetname "")
		)
		(fill
			(thermal_gap 0.5)
			(thermal_bridge_width 0.5)
			(island_removal_mode 0)
		)
		(polygon
			(pts
				(xy 44.97324 -13.1699) (xy 44.97324 -11.9888) (xy 47.34814 -11.9888) (xy 47.34814 -13.1699)
			)
		)
	)
	(zone
		(layer "In4.Cu")
		(hatch none 0.5)
		(connect_pads
			(clearance 0)
		)
		(min_thickness 0.25)
		(keepout
			(tracks allowed)
			(vias allowed)
			(pads allowed)
			(copperpour allowed)
			(footprints allowed)
		)
		(placement
			(enabled no)
			(sheetname "")
		)
		(fill
			(thermal_gap 0.5)
			(thermal_bridge_width 0.5)
			(island_removal_mode 0)
		)
		(polygon
			(pts
				(xy 187.638436 -316.6872) (xy 187.638436 -315.332364) (xy 188.115702 -315.332364) (xy 188.115702 -316.6872)
			)
		)
	)
	(zone
		(layer "In4.Cu")
		(hatch none 0.5)
		(connect_pads
			(clearance 0)
		)
		(min_thickness 0.25)
		(keepout
			(tracks allowed)
			(vias allowed)
			(pads allowed)
			(copperpour allowed)
			(footprints allowed)
		)
		(placement
			(enabled no)
			(sheetname "")
		)
		(fill
			(thermal_gap 0.5)
			(thermal_bridge_width 0.5)
			(island_removal_mode 0)
		)
		(polygon
			(pts
				(xy 298.77385 -286.439356) (xy 298.77385 -285.08452) (xy 299.251116 -285.08452) (xy 299.251116 -286.439356)
			)
		)
	)
	(zone
		(layer "In4.Cu")
		(hatch none 0.5)
		(connect_pads
			(clearance 0)
		)
		(min_thickness 0.25)
		(keepout
			(tracks allowed)
			(vias allowed)
			(pads allowed)
			(copperpour allowed)
			(footprints allowed)
		)
		(placement
			(enabled no)
			(sheetname "")
		)
		(fill
			(thermal_gap 0.5)
			(thermal_bridge_width 0.5)
			(island_removal_mode 0)
		)
		(polygon
			(pts
				(xy 347.64218 -22.2504) (xy 347.64218 -21.0058) (xy 346.30614 -21.0058) (xy 346.30614 -22.2504)
			)
		)
	)
	(zone
		(layer "In4.Cu")
		(hatch none 0.5)
		(connect_pads
			(clearance 0)
		)
		(min_thickness 0.25)
		(keepout
			(tracks allowed)
			(vias allowed)
			(pads allowed)
			(copperpour allowed)
			(footprints allowed)
		)
		(placement
			(enabled no)
			(sheetname "")
		)
		(fill
			(thermal_gap 0.5)
			(thermal_bridge_width 0.5)
			(island_removal_mode 0)
		)
		(polygon
			(pts
				(xy 298.775882 -224.736914) (xy 298.775882 -223.382078) (xy 299.253148 -223.382078) (xy 299.253148 -224.736914)
			)
		)
	)
	(zone
		(layer "In4.Cu")
		(hatch none 0.5)
		(connect_pads
			(clearance 0)
		)
		(min_thickness 0.25)
		(keepout
			(tracks allowed)
			(vias allowed)
			(pads allowed)
			(copperpour allowed)
			(footprints allowed)
		)
		(placement
			(enabled no)
			(sheetname "")
		)
		(fill
			(thermal_gap 0.5)
			(thermal_bridge_width 0.5)
			(island_removal_mode 0)
		)
		(polygon
			(pts
				(xy 50.838862 -303.863756) (xy 50.838862 -302.50892) (xy 51.316128 -302.50892) (xy 51.316128 -303.863756)
			)
		)
	)
	(zone
		(layer "In4.Cu")
		(hatch none 0.5)
		(connect_pads
			(clearance 0)
		)
		(min_thickness 0.25)
		(keepout
			(tracks allowed)
			(vias allowed)
			(pads allowed)
			(copperpour allowed)
			(footprints allowed)
		)
		(placement
			(enabled no)
			(sheetname "")
		)
		(fill
			(thermal_gap 0.5)
			(thermal_bridge_width 0.5)
			(island_removal_mode 0)
		)
		(polygon
			(pts
				(xy 420.480998 -302.957484) (xy 420.480998 -301.749714) (xy 419.534594 -301.749714) (xy 419.534594 -300.74362)
				(xy 420.480998 -300.74362) (xy 420.958264 -300.74362) (xy 420.958264 -302.957484)
			)
		)
	)
	(zone
		(layer "In4.Cu")
		(hatch none 0.5)
		(connect_pads
			(clearance 0)
		)
		(min_thickness 0.25)
		(keepout
			(tracks allowed)
			(vias allowed)
			(pads allowed)
			(copperpour allowed)
			(footprints allowed)
		)
		(placement
			(enabled no)
			(sheetname "")
		)
		(fill
			(thermal_gap 0.5)
			(thermal_bridge_width 0.5)
			(island_removal_mode 0)
		)
		(polygon
			(pts
				(xy 298.775882 -205.186534) (xy 298.775882 -203.831698) (xy 299.253148 -203.831698) (xy 299.253148 -205.186534)
			)
		)
	)
	(zone
		(layer "In4.Cu")
		(hatch none 0.5)
		(connect_pads
			(clearance 0)
		)
		(min_thickness 0.25)
		(keepout
			(tracks allowed)
			(vias allowed)
			(pads allowed)
			(copperpour allowed)
			(footprints allowed)
		)
		(placement
			(enabled no)
			(sheetname "")
		)
		(fill
			(thermal_gap 0.5)
			(thermal_bridge_width 0.5)
			(island_removal_mode 0)
		)
		(polygon
			(pts
				(xy 35.745674 -295.564814) (xy 35.745674 -294.209978) (xy 36.22294 -294.209978) (xy 36.22294 -295.564814)
			)
		)
	)
	(zone
		(layer "In4.Cu")
		(hatch none 0.5)
		(connect_pads
			(clearance 0)
		)
		(min_thickness 0.25)
		(keepout
			(tracks allowed)
			(vias allowed)
			(pads allowed)
			(copperpour allowed)
			(footprints allowed)
		)
		(placement
			(enabled no)
			(sheetname "")
		)
		(fill
			(thermal_gap 0.5)
			(thermal_bridge_width 0.5)
			(island_removal_mode 0)
		)
		(polygon
			(pts
				(xy 435.568598 -263.857486) (xy 435.568598 -262.50265) (xy 436.045864 -262.50265) (xy 436.045864 -263.857486)
			)
		)
	)
	(zone
		(layer "In4.Cu")
		(hatch none 0.5)
		(connect_pads
			(clearance 0)
		)
		(min_thickness 0.25)
		(keepout
			(tracks allowed)
			(vias allowed)
			(pads allowed)
			(copperpour allowed)
			(footprints allowed)
		)
		(placement
			(enabled no)
			(sheetname "")
		)
		(fill
			(thermal_gap 0.5)
			(thermal_bridge_width 0.5)
			(island_removal_mode 0)
		)
		(polygon
			(pts
				(xy 161.56686 -8.53186) (xy 161.56686 -7.85368) (xy 163.21786 -7.85368) (xy 163.21786 -8.53186)
			)
		)
	)
	(zone
		(layer "In4.Cu")
		(hatch none 0.5)
		(connect_pads
			(clearance 0)
		)
		(min_thickness 0.25)
		(keepout
			(tracks allowed)
			(vias allowed)
			(pads allowed)
			(copperpour allowed)
			(footprints allowed)
		)
		(placement
			(enabled no)
			(sheetname "")
		)
		(fill
			(thermal_gap 0.5)
			(thermal_bridge_width 0.5)
			(island_removal_mode 0)
		)
		(polygon
			(pts
				(xy 435.58841 -252.801628) (xy 435.58841 -251.446792) (xy 436.065676 -251.446792) (xy 436.065676 -252.801628)
			)
		)
	)
	(zone
		(layer "In4.Cu")
		(hatch none 0.5)
		(connect_pads
			(clearance 0)
		)
		(min_thickness 0.25)
		(keepout
			(tracks allowed)
			(vias allowed)
			(pads allowed)
			(copperpour allowed)
			(footprints allowed)
		)
		(placement
			(enabled no)
			(sheetname "")
		)
		(fill
			(thermal_gap 0.5)
			(thermal_bridge_width 0.5)
			(island_removal_mode 0)
		)
		(polygon
			(pts
				(xy 333.13116 -341.920068) (xy 333.13116 -338.122768) (xy 337.1723 -338.122768) (xy 337.1723 -341.920068)
			)
		)
	)
	(zone
		(layer "In4.Cu")
		(hatch none 0.5)
		(connect_pads
			(clearance 0)
		)
		(min_thickness 0.25)
		(keepout
			(tracks allowed)
			(vias allowed)
			(pads allowed)
			(copperpour allowed)
			(footprints allowed)
		)
		(placement
			(enabled no)
			(sheetname "")
		)
		(fill
			(thermal_gap 0.5)
			(thermal_bridge_width 0.5)
			(island_removal_mode 0)
		)
		(polygon
			(pts
				(xy 283.667962 -266.438634) (xy 283.667962 -265.083798) (xy 284.145228 -265.083798) (xy 284.145228 -266.438634)
			)
		)
	)
	(zone
		(layer "In4.Cu")
		(hatch none 0.5)
		(connect_pads
			(clearance 0)
		)
		(min_thickness 0.25)
		(keepout
			(tracks allowed)
			(vias allowed)
			(pads allowed)
			(copperpour allowed)
			(footprints allowed)
		)
		(placement
			(enabled no)
			(sheetname "")
		)
		(fill
			(thermal_gap 0.5)
			(thermal_bridge_width 0.5)
			(island_removal_mode 0)
		)
		(polygon
			(pts
				(xy 435.568598 -233.257598) (xy 435.568598 -231.902762) (xy 436.045864 -231.902762) (xy 436.045864 -233.257598)
			)
		)
	)
	(zone
		(layer "In4.Cu")
		(hatch none 0.5)
		(connect_pads
			(clearance 0)
		)
		(min_thickness 0.25)
		(keepout
			(tracks allowed)
			(vias allowed)
			(pads allowed)
			(copperpour allowed)
			(footprints allowed)
		)
		(placement
			(enabled no)
			(sheetname "")
		)
		(fill
			(thermal_gap 0.5)
			(thermal_bridge_width 0.5)
			(island_removal_mode 0)
		)
		(polygon
			(pts
				(xy 187.62853 -297.857418) (xy 187.62853 -296.502582) (xy 188.105796 -296.502582) (xy 188.105796 -297.857418)
			)
		)
	)
	(zone
		(layer "In4.Cu")
		(hatch none 0.5)
		(connect_pads
			(clearance 0)
		)
		(min_thickness 0.25)
		(keepout
			(tracks allowed)
			(vias allowed)
			(pads allowed)
			(copperpour allowed)
			(footprints allowed)
		)
		(placement
			(enabled no)
			(sheetname "")
		)
		(fill
			(thermal_gap 0.5)
			(thermal_bridge_width 0.5)
			(island_removal_mode 0)
		)
		(polygon
			(pts
				(xy 294.667432 -259.571236) (xy 294.667432 -258.316476) (xy 295.144952 -258.316476) (xy 295.144952 -259.571236)
			)
		)
	)
	(zone
		(layer "In4.Cu")
		(hatch none 0.5)
		(connect_pads
			(clearance 0)
		)
		(min_thickness 0.25)
		(keepout
			(tracks allowed)
			(vias allowed)
			(pads allowed)
			(copperpour allowed)
			(footprints allowed)
		)
		(placement
			(enabled no)
			(sheetname "")
		)
		(fill
			(thermal_gap 0.5)
			(thermal_bridge_width 0.5)
			(island_removal_mode 0)
		)
		(polygon
			(pts
				(xy 283.66593 -313.162696) (xy 283.66593 -311.80786) (xy 284.143196 -311.80786) (xy 284.143196 -313.162696)
			)
		)
	)
	(zone
		(layer "In4.Cu")
		(hatch none 0.5)
		(connect_pads
			(clearance 0)
		)
		(min_thickness 0.25)
		(keepout
			(tracks allowed)
			(vias allowed)
			(pads allowed)
			(copperpour allowed)
			(footprints allowed)
		)
		(placement
			(enabled no)
			(sheetname "")
		)
		(fill
			(thermal_gap 0.5)
			(thermal_bridge_width 0.5)
			(island_removal_mode 0)
		)
		(polygon
			(pts
				(xy 439.619644 -268.83614) (xy 439.619644 -267.481304) (xy 440.09691 -267.481304) (xy 440.09691 -268.83614)
			)
		)
	)
	(zone
		(layer "In4.Cu")
		(hatch none 0.5)
		(connect_pads
			(clearance 0)
		)
		(min_thickness 0.25)
		(keepout
			(tracks allowed)
			(vias allowed)
			(pads allowed)
			(copperpour allowed)
			(footprints allowed)
		)
		(placement
			(enabled no)
			(sheetname "")
		)
		(fill
			(thermal_gap 0.5)
			(thermal_bridge_width 0.5)
			(island_removal_mode 0)
		)
		(polygon
			(pts
				(xy 435.58841 -265.551666) (xy 435.58841 -264.19683) (xy 436.065676 -264.19683) (xy 436.065676 -265.551666)
			)
		)
	)
	(zone
		(layer "In4.Cu")
		(hatch none 0.5)
		(connect_pads
			(clearance 0)
		)
		(min_thickness 0.25)
		(keepout
			(tracks allowed)
			(vias allowed)
			(pads allowed)
			(copperpour allowed)
			(footprints allowed)
		)
		(placement
			(enabled no)
			(sheetname "")
		)
		(fill
			(thermal_gap 0.5)
			(thermal_bridge_width 0.5)
			(island_removal_mode 0)
		)
		(polygon
			(pts
				(xy 35.725862 -246.901716) (xy 35.725862 -245.54688) (xy 36.203128 -245.54688) (xy 36.203128 -246.901716)
			)
		)
	)
	(zone
		(layer "In4.Cu")
		(hatch none 0.5)
		(connect_pads
			(clearance 0)
		)
		(min_thickness 0.25)
		(keepout
			(tracks allowed)
			(vias allowed)
			(pads allowed)
			(copperpour allowed)
			(footprints allowed)
		)
		(placement
			(enabled no)
			(sheetname "")
		)
		(fill
			(thermal_gap 0.5)
			(thermal_bridge_width 0.5)
			(island_removal_mode 0)
		)
		(polygon
			(pts
				(xy 187.618624 -314.970922) (xy 187.618624 -313.616086) (xy 188.09589 -313.616086) (xy 188.09589 -314.970922)
			)
		)
	)
	(zone
		(layer "In4.Cu")
		(hatch none 0.5)
		(connect_pads
			(clearance 0)
		)
		(min_thickness 0.25)
		(keepout
			(tracks allowed)
			(vias allowed)
			(pads allowed)
			(copperpour allowed)
			(footprints allowed)
		)
		(placement
			(enabled no)
			(sheetname "")
		)
		(fill
			(thermal_gap 0.5)
			(thermal_bridge_width 0.5)
			(island_removal_mode 0)
		)
		(polygon
			(pts
				(xy 283.706062 -309.758334) (xy 283.706062 -308.403498) (xy 284.183328 -308.403498) (xy 284.183328 -309.758334)
			)
		)
	)
	(zone
		(layer "In4.Cu")
		(hatch none 0.5)
		(connect_pads
			(clearance 0)
		)
		(min_thickness 0.25)
		(keepout
			(tracks allowed)
			(vias allowed)
			(pads allowed)
			(copperpour allowed)
			(footprints allowed)
		)
		(placement
			(enabled no)
			(sheetname "")
		)
		(fill
			(thermal_gap 0.5)
			(thermal_bridge_width 0.5)
			(island_removal_mode 0)
		)
		(polygon
			(pts
				(xy 287.108392 -245.100856) (xy 287.108392 -242.967256) (xy 287.545272 -242.967256) (xy 287.545272 -245.100856)
			)
		)
	)
	(zone
		(layer "In4.Cu")
		(hatch none 0.5)
		(connect_pads
			(clearance 0)
		)
		(min_thickness 0.25)
		(keepout
			(tracks allowed)
			(vias allowed)
			(pads allowed)
			(copperpour allowed)
			(footprints allowed)
		)
		(placement
			(enabled no)
			(sheetname "")
		)
		(fill
			(thermal_gap 0.5)
			(thermal_bridge_width 0.5)
			(island_removal_mode 0)
		)
		(polygon
			(pts
				(xy 283.66085 -269.439136) (xy 283.66085 -268.0843) (xy 284.138116 -268.0843) (xy 284.138116 -269.439136)
			)
		)
	)
	(zone
		(layer "In4.Cu")
		(hatch none 0.5)
		(connect_pads
			(clearance 0)
		)
		(min_thickness 0.25)
		(keepout
			(tracks allowed)
			(vias allowed)
			(pads allowed)
			(copperpour allowed)
			(footprints allowed)
		)
		(placement
			(enabled no)
			(sheetname "")
		)
		(fill
			(thermal_gap 0.5)
			(thermal_bridge_width 0.5)
			(island_removal_mode 0)
		)
		(polygon
			(pts
				(xy 435.568598 -237.49762) (xy 435.568598 -235.302552) (xy 436.045864 -235.302552) (xy 436.045864 -237.49762)
			)
		)
	)
	(zone
		(layer "In4.Cu")
		(hatch none 0.5)
		(connect_pads
			(clearance 0)
		)
		(min_thickness 0.25)
		(keepout
			(tracks allowed)
			(vias allowed)
			(pads allowed)
			(copperpour allowed)
			(footprints allowed)
		)
		(placement
			(enabled no)
			(sheetname "")
		)
		(fill
			(thermal_gap 0.5)
			(thermal_bridge_width 0.5)
			(island_removal_mode 0)
		)
		(polygon
			(pts
				(xy 187.661296 -309.7276) (xy 187.661296 -308.372764) (xy 188.138562 -308.372764) (xy 188.138562 -309.7276)
			)
		)
	)
	(zone
		(layer "In4.Cu")
		(hatch none 0.5)
		(connect_pads
			(clearance 0)
		)
		(min_thickness 0.25)
		(keepout
			(tracks allowed)
			(vias allowed)
			(pads allowed)
			(copperpour allowed)
			(footprints allowed)
		)
		(placement
			(enabled no)
			(sheetname "")
		)
		(fill
			(thermal_gap 0.5)
			(thermal_bridge_width 0.5)
			(island_removal_mode 0)
		)
		(polygon
			(pts
				(xy 59.490864 -195.796916) (xy 59.490864 -194.521836) (xy 60.143644 -194.521836) (xy 60.143644 -195.796916)
			)
		)
	)
	(zone
		(layer "In4.Cu")
		(hatch none 0.5)
		(connect_pads
			(clearance 0)
		)
		(min_thickness 0.25)
		(keepout
			(tracks allowed)
			(vias allowed)
			(pads allowed)
			(copperpour allowed)
			(footprints allowed)
		)
		(placement
			(enabled no)
			(sheetname "")
		)
		(fill
			(thermal_gap 0.5)
			(thermal_bridge_width 0.5)
			(island_removal_mode 0)
		)
		(polygon
			(pts
				(xy 298.786042 -226.423474) (xy 298.786042 -225.068638) (xy 299.263308 -225.068638) (xy 299.263308 -226.423474)
			)
		)
	)
	(zone
		(layer "In4.Cu")
		(hatch none 0.5)
		(connect_pads
			(clearance 0)
		)
		(min_thickness 0.25)
		(keepout
			(tracks allowed)
			(vias allowed)
			(pads allowed)
			(copperpour allowed)
			(footprints allowed)
		)
		(placement
			(enabled no)
			(sheetname "")
		)
		(fill
			(thermal_gap 0.5)
			(thermal_bridge_width 0.5)
			(island_removal_mode 0)
		)
		(polygon
			(pts
				(xy 420.480998 -228.14534) (xy 420.480998 -225.952558) (xy 420.958264 -225.952558) (xy 420.958264 -228.14534)
			)
		)
	)
	(zone
		(layer "In4.Cu")
		(hatch none 0.5)
		(connect_pads
			(clearance 0)
		)
		(min_thickness 0.25)
		(keepout
			(tracks allowed)
			(vias allowed)
			(pads allowed)
			(copperpour allowed)
			(footprints allowed)
		)
		(placement
			(enabled no)
			(sheetname "")
		)
		(fill
			(thermal_gap 0.5)
			(thermal_bridge_width 0.5)
			(island_removal_mode 0)
		)
		(polygon
			(pts
				(xy 435.631844 -312.3692) (xy 435.631844 -311.014364) (xy 436.10911 -311.014364) (xy 436.10911 -312.3692)
			)
		)
	)
	(zone
		(layer "In4.Cu")
		(hatch none 0.5)
		(connect_pads
			(clearance 0)
		)
		(min_thickness 0.25)
		(keepout
			(tracks allowed)
			(vias allowed)
			(pads allowed)
			(copperpour allowed)
			(footprints allowed)
		)
		(placement
			(enabled no)
			(sheetname "")
		)
		(fill
			(thermal_gap 0.5)
			(thermal_bridge_width 0.5)
			(island_removal_mode 0)
		)
		(polygon
			(pts
				(xy 283.68625 -210.249516) (xy 283.68625 -208.89468) (xy 284.163516 -208.89468) (xy 284.163516 -210.249516)
			)
		)
	)
	(zone
		(layer "In4.Cu")
		(hatch none 0.5)
		(connect_pads
			(clearance 0)
		)
		(min_thickness 0.25)
		(keepout
			(tracks allowed)
			(vias allowed)
			(pads allowed)
			(copperpour allowed)
			(footprints allowed)
		)
		(placement
			(enabled no)
			(sheetname "")
		)
		(fill
			(thermal_gap 0.5)
			(thermal_bridge_width 0.5)
			(island_removal_mode 0)
		)
		(polygon
			(pts
				(xy 322.76542 -247.848628) (xy 324.344284 -249.427238) (xy 324.344284 -250.152916) (xy 322.863464 -251.633736)
				(xy 322.863464 -252.764036) (xy 323.81571 -253.716282) (xy 323.81571 -254.011176) (xy 323.287136 -254.53975)
				(xy 318.746124 -254.53975) (xy 318.691006 -254.594868) (xy 318.691006 -255.129538) (xy 318.83858 -255.277112)
				(xy 319.128394 -255.277112) (xy 323.560694 -259.709412) (xy 330.344526 -259.709412) (xy 330.67371 -259.380228)
				(xy 331.222858 -259.380228) (xy 331.516482 -259.086604) (xy 331.518006 -259.086604) (xy 332.08976 -258.51485)
				(xy 332.186026 -258.51485) (xy 332.186026 -256.699004) (xy 332.051406 -256.699004) (xy 330.80579 -256.699004)
				(xy 330.17079 -256.699258) (xy 328.21499 -254.743458) (xy 328.21499 -251.949458) (xy 328.88809 -251.276358)
				(xy 328.88809 -249.066558) (xy 329.40879 -248.545858) (xy 330.47559 -248.545604) (xy 330.47559 -247.453404)
				(xy 324.02399 -247.453658) (xy 323.97319 -247.402858) (xy 322.93179 -247.402858) (xy 322.76542 -247.569228)
			)
		)
	)
	(zone
		(layer "In4.Cu")
		(hatch none 0.5)
		(connect_pads
			(clearance 0)
		)
		(min_thickness 0.25)
		(keepout
			(tracks allowed)
			(vias allowed)
			(pads allowed)
			(copperpour allowed)
			(footprints allowed)
		)
		(placement
			(enabled no)
			(sheetname "")
		)
		(fill
			(thermal_gap 0.5)
			(thermal_bridge_width 0.5)
			(island_removal_mode 0)
		)
		(polygon
			(pts
				(xy 420.50081 -204.351636) (xy 420.50081 -202.9968) (xy 420.978076 -202.9968) (xy 420.978076 -204.351636)
			)
		)
	)
	(zone
		(layer "In4.Cu")
		(hatch none 0.5)
		(connect_pads
			(clearance 0)
		)
		(min_thickness 0.25)
		(keepout
			(tracks allowed)
			(vias allowed)
			(pads allowed)
			(copperpour allowed)
			(footprints allowed)
		)
		(placement
			(enabled no)
			(sheetname "")
		)
		(fill
			(thermal_gap 0.5)
			(thermal_bridge_width 0.5)
			(island_removal_mode 0)
		)
		(polygon
			(pts
				(xy 103.719884 -290.964112) (xy 107.51185 -290.964112) (xy 110.851188 -290.964112) (xy 117.309392 -290.963858)
				(xy 117.309392 -292.269672) (xy 117.588792 -292.549072) (xy 119.163592 -292.549072) (xy 119.595392 -292.980872)
				(xy 126.631192 -292.980618) (xy 127.189992 -292.421818) (xy 131.533392 -292.421818) (xy 132.066792 -291.888418)
				(xy 136.283192 -291.888418) (xy 136.664192 -291.507418) (xy 136.664192 -290.963604) (xy 138.667744 -290.963604)
				(xy 138.798046 -290.833302) (xy 138.797792 -281.940762) (xy 139.074906 -281.663648) (xy 139.074906 -281.44343)
				(xy 139.820396 -280.69794) (xy 139.820396 -280.625804) (xy 139.819888 -280.625804) (xy 139.403328 -280.209244)
				(xy 139.403328 -280.186384) (xy 140.319506 -279.269952) (xy 140.860526 -278.728932) (xy 140.860526 -278.657304)
				(xy 140.835888 -278.632666) (xy 140.806678 -278.603456) (xy 139.566904 -277.363682) (xy 139.566904 -277.346156)
				(xy 139.968986 -276.944074) (xy 139.968986 -276.91461) (xy 139.24788 -276.193504) (xy 139.24788 -276.149054)
				(xy 139.260834 -276.1361) (xy 139.877292 -275.519388) (xy 139.356592 -274.998688) (xy 139.356592 -274.157694)
				(xy 139.540742 -273.973544) (xy 139.540742 -272.657062) (xy 140.696696 -271.501108) (xy 140.696696 -271.400524)
				(xy 140.468604 -271.172432) (xy 140.468604 -271.135094) (xy 141.55293 -270.050768) (xy 141.55293 -269.825216)
				(xy 139.622784 -267.89507) (xy 139.622784 -267.10386) (xy 139.573508 -267.054584) (xy 138.748262 -267.054584)
				(xy 138.73988 -267.046202) (xy 138.73988 -263.399524) (xy 138.795506 -263.343898) (xy 140.488416 -263.343898)
				(xy 140.569188 -263.263126) (xy 140.569188 -262.110728) (xy 140.39215 -261.93369) (xy 138.96213 -261.93369)
				(xy 138.93927 -261.91083) (xy 138.93927 -259.815584) (xy 138.952986 -259.801868) (xy 139.534138 -259.801868)
				(xy 139.59332 -259.801868) (xy 139.641072 -259.754116) (xy 139.641072 -258.1021) (xy 139.565634 -258.026662)
				(xy 139.044426 -258.026662) (xy 138.92657 -257.908806) (xy 138.92657 -257.261614) (xy 138.909044 -257.244088)
				(xy 137.41781 -257.244088) (xy 137.389362 -257.21564) (xy 137.389362 -256.191004) (xy 137.428986 -256.15138)
				(xy 139.76223 -256.15138) (xy 139.8143 -256.09931) (xy 139.8143 -255.239774) (xy 139.711938 -255.137412)
				(xy 138.848846 -255.137412) (xy 138.743944 -255.03251) (xy 137.106152 -255.03251) (xy 137.075672 -255.00203)
				(xy 137.075672 -254.935228) (xy 137.075672 -254.17272) (xy 136.988296 -254.085344) (xy 131.101846 -254.085344)
				(xy 130.95224 -253.935738) (xy 130.95224 -252.995938) (xy 130.85318 -252.896878) (xy 126.511304 -252.896878)
				(xy 125.386846 -251.77242) (xy 125.127004 -251.512578) (xy 125.127004 -250.561856) (xy 125.163072 -250.525788)
				(xy 125.386846 -250.525788) (xy 126.049532 -250.525788) (xy 126.09703 -250.47829) (xy 126.09703 -250.045474)
				(xy 125.894338 -249.842782) (xy 125.894338 -249.548142) (xy 126.077472 -249.365008) (xy 127.57023 -249.364754)
				(xy 128.049782 -249.364754) (xy 128.21158 -249.526552) (xy 129.042414 -249.526552) (xy 129.042668 -249.526298)
				(xy 129.173224 -249.656854) (xy 129.173224 -249.878088) (xy 129.145538 -249.905774) (xy 129.145538 -250.055888)
				(xy 129.145538 -250.211336) (xy 129.210308 -250.276106) (xy 129.554478 -250.276106) (xy 129.852928 -249.977656)
				(xy 137.498582 -249.977656) (xy 137.954766 -249.521472) (xy 137.954766 -245.18874) (xy 138.115802 -245.027704)
				(xy 140.293598 -245.027704) (xy 140.42136 -244.899942) (xy 140.42136 -239.2045) (xy 140.446252 -239.179608)
				(xy 141.087094 -239.179608) (xy 141.159484 -239.107218) (xy 141.159484 -234.80014) (xy 140.961618 -234.602274)
				(xy 140.699236 -234.602274) (xy 140.630656 -234.533694) (xy 140.630656 -232.471976) (xy 141.026134 -232.076498)
				(xy 141.026134 -231.661462) (xy 140.46962 -231.104948) (xy 140.46962 -230.73106) (xy 140.737082 -230.463598)
				(xy 140.737082 -230.372412) (xy 140.166598 -229.801928) (xy 140.166598 -229.33787) (xy 140.927328 -228.57714)
				(xy 140.927328 -224.412302) (xy 140.729462 -224.214436) (xy 140.044932 -224.214436) (xy 139.896596 -224.0661)
				(xy 139.896596 -219.57792) (xy 139.67968 -219.361004) (xy 139.67968 -217.885518) (xy 139.550394 -217.756232)
				(xy 139.53363 -217.756232) (xy 139.533376 -214.824564) (xy 137.675366 -212.966554) (xy 110.849664 -212.967062)
				(xy 107.510326 -212.967062) (xy 103.71836 -212.967062)
			)
		)
	)
	(zone
		(layer "In4.Cu")
		(hatch none 0.5)
		(connect_pads
			(clearance 0)
		)
		(min_thickness 0.25)
		(keepout
			(tracks allowed)
			(vias allowed)
			(pads allowed)
			(copperpour allowed)
			(footprints allowed)
		)
		(placement
			(enabled no)
			(sheetname "")
		)
		(fill
			(thermal_gap 0.5)
			(thermal_bridge_width 0.5)
			(island_removal_mode 0)
		)
		(polygon
			(pts
				(xy 164.991542 -244.301518) (xy 164.991542 -242.946682) (xy 165.468808 -242.946682) (xy 165.468808 -244.301518)
			)
		)
	)
	(zone
		(layer "In4.Cu")
		(hatch none 0.5)
		(connect_pads
			(clearance 0)
		)
		(min_thickness 0.25)
		(keepout
			(tracks allowed)
			(vias allowed)
			(pads allowed)
			(copperpour allowed)
			(footprints allowed)
		)
		(placement
			(enabled no)
			(sheetname "")
		)
		(fill
			(thermal_gap 0.5)
			(thermal_bridge_width 0.5)
			(island_removal_mode 0)
		)
		(polygon
			(pts
				(xy 283.63291 -206.078836) (xy 283.63291 -204.724) (xy 284.110176 -204.724) (xy 284.110176 -206.078836)
			)
		)
	)
	(zone
		(layer "In4.Cu")
		(hatch none 0.5)
		(connect_pads
			(clearance 0)
		)
		(min_thickness 0.25)
		(keepout
			(tracks allowed)
			(vias allowed)
			(pads allowed)
			(copperpour allowed)
			(footprints allowed)
		)
		(placement
			(enabled no)
			(sheetname "")
		)
		(fill
			(thermal_gap 0.5)
			(thermal_bridge_width 0.5)
			(island_removal_mode 0)
		)
		(polygon
			(pts
				(xy 56.133492 -244.278658) (xy 56.133492 -242.973098) (xy 56.735472 -242.973098) (xy 56.735472 -244.278658)
			)
		)
	)
	(zone
		(layer "In4.Cu")
		(hatch none 0.5)
		(connect_pads
			(clearance 0)
		)
		(min_thickness 0.25)
		(keepout
			(tracks allowed)
			(vias allowed)
			(pads allowed)
			(copperpour allowed)
			(footprints allowed)
		)
		(placement
			(enabled no)
			(sheetname "")
		)
		(fill
			(thermal_gap 0.5)
			(thermal_bridge_width 0.5)
			(island_removal_mode 0)
		)
		(polygon
			(pts
				(xy 420.480998 -199.257412) (xy 420.480998 -197.902576) (xy 420.958264 -197.902576) (xy 420.958264 -199.257412)
			)
		)
	)
	(zone
		(layer "In4.Cu")
		(hatch none 0.5)
		(connect_pads
			(clearance 0)
		)
		(min_thickness 0.25)
		(keepout
			(tracks allowed)
			(vias allowed)
			(pads allowed)
			(copperpour allowed)
			(footprints allowed)
		)
		(placement
			(enabled no)
			(sheetname "")
		)
		(fill
			(thermal_gap 0.5)
			(thermal_bridge_width 0.5)
			(island_removal_mode 0)
		)
		(polygon
			(pts
				(xy 172.54093 -229.857554) (xy 172.54093 -228.502718) (xy 173.018196 -228.502718) (xy 173.018196 -229.857554)
			)
		)
	)
	(zone
		(layer "In4.Cu")
		(hatch none 0.5)
		(connect_pads
			(clearance 0)
		)
		(min_thickness 0.25)
		(keepout
			(tracks allowed)
			(vias allowed)
			(pads allowed)
			(copperpour allowed)
			(footprints allowed)
		)
		(placement
			(enabled no)
			(sheetname "")
		)
		(fill
			(thermal_gap 0.5)
			(thermal_bridge_width 0.5)
			(island_removal_mode 0)
		)
		(polygon
			(pts
				(xy 296.564304 -319.951862) (xy 296.564304 -318.597026) (xy 297.04157 -318.597026) (xy 297.04157 -319.951862)
			)
		)
	)
	(zone
		(layer "In4.Cu")
		(hatch none 0.5)
		(connect_pads
			(clearance 0)
		)
		(min_thickness 0.25)
		(keepout
			(tracks allowed)
			(vias allowed)
			(pads allowed)
			(copperpour allowed)
			(footprints allowed)
		)
		(placement
			(enabled no)
			(sheetname "")
		)
		(fill
			(thermal_gap 0.5)
			(thermal_bridge_width 0.5)
			(island_removal_mode 0)
		)
		(polygon
			(pts
				(xy 43.189144 -244.229636) (xy 43.189144 -242.903756) (xy 43.727624 -242.903756) (xy 43.727624 -244.229636)
			)
		)
	)
	(zone
		(layer "In4.Cu")
		(hatch none 0.5)
		(connect_pads
			(clearance 0)
		)
		(min_thickness 0.25)
		(keepout
			(tracks allowed)
			(vias allowed)
			(pads allowed)
			(copperpour allowed)
			(footprints allowed)
		)
		(placement
			(enabled no)
			(sheetname "")
		)
		(fill
			(thermal_gap 0.5)
			(thermal_bridge_width 0.5)
			(island_removal_mode 0)
		)
		(polygon
			(pts
				(xy 187.641484 -309.733442) (xy 187.641484 -308.378606) (xy 188.11875 -308.378606) (xy 188.11875 -309.733442)
			)
		)
	)
	(zone
		(layer "In4.Cu")
		(hatch none 0.5)
		(connect_pads
			(clearance 0)
		)
		(min_thickness 0.25)
		(keepout
			(tracks allowed)
			(vias allowed)
			(pads allowed)
			(copperpour allowed)
			(footprints allowed)
		)
		(placement
			(enabled no)
			(sheetname "")
		)
		(fill
			(thermal_gap 0.5)
			(thermal_bridge_width 0.5)
			(island_removal_mode 0)
		)
		(polygon
			(pts
				(xy 360.914188 -358.106472) (xy 360.914188 -354.121466) (xy 362.270802 -354.121466) (xy 362.270802 -358.106472)
			)
		)
	)
	(zone
		(layer "In4.Cu")
		(hatch none 0.5)
		(connect_pads
			(clearance 0)
		)
		(min_thickness 0.25)
		(keepout
			(tracks allowed)
			(vias allowed)
			(pads allowed)
			(copperpour allowed)
			(footprints allowed)
		)
		(placement
			(enabled no)
			(sheetname "")
		)
		(fill
			(thermal_gap 0.5)
			(thermal_bridge_width 0.5)
			(island_removal_mode 0)
		)
		(polygon
			(pts
				(xy 291.25926 -261.233158) (xy 291.25926 -258.279138) (xy 291.61486 -258.279138) (xy 291.61486 -261.233158)
			)
		)
	)
	(zone
		(layer "In4.Cu")
		(hatch none 0.5)
		(connect_pads
			(clearance 0)
		)
		(min_thickness 0.25)
		(keepout
			(tracks allowed)
			(vias allowed)
			(pads allowed)
			(copperpour allowed)
			(footprints allowed)
		)
		(placement
			(enabled no)
			(sheetname "")
		)
		(fill
			(thermal_gap 0.5)
			(thermal_bridge_width 0.5)
			(island_removal_mode 0)
		)
		(polygon
			(pts
				(xy 191.14516 -13.78458) (xy 191.14516 -12.72032) (xy 193.05016 -12.72032) (xy 193.05016 -13.78458)
			)
		)
	)
	(zone
		(layer "In4.Cu")
		(hatch none 0.5)
		(connect_pads
			(clearance 0)
		)
		(min_thickness 0.25)
		(keepout
			(tracks allowed)
			(vias allowed)
			(pads allowed)
			(copperpour allowed)
			(footprints allowed)
		)
		(placement
			(enabled no)
			(sheetname "")
		)
		(fill
			(thermal_gap 0.5)
			(thermal_bridge_width 0.5)
			(island_removal_mode 0)
		)
		(polygon
			(pts
				(xy 283.706062 -208.597754) (xy 283.706062 -207.242918) (xy 284.183328 -207.242918) (xy 284.183328 -208.597754)
			)
		)
	)
	(zone
		(layer "In4.Cu")
		(hatch none 0.5)
		(connect_pads
			(clearance 0)
		)
		(min_thickness 0.25)
		(keepout
			(tracks allowed)
			(vias allowed)
			(pads allowed)
			(copperpour allowed)
			(footprints allowed)
		)
		(placement
			(enabled no)
			(sheetname "")
		)
		(fill
			(thermal_gap 0.5)
			(thermal_bridge_width 0.5)
			(island_removal_mode 0)
		)
		(polygon
			(pts
				(xy 61.825124 -305.537616) (xy 61.825124 -301.592996) (xy 62.348364 -301.592996) (xy 62.348364 -305.537616)
			)
		)
	)
	(zone
		(layer "In4.Cu")
		(hatch none 0.5)
		(connect_pads
			(clearance 0)
		)
		(min_thickness 0.25)
		(keepout
			(tracks allowed)
			(vias allowed)
			(pads allowed)
			(copperpour allowed)
			(footprints allowed)
		)
		(placement
			(enabled no)
			(sheetname "")
		)
		(fill
			(thermal_gap 0.5)
			(thermal_bridge_width 0.5)
			(island_removal_mode 0)
		)
		(polygon
			(pts
				(xy 50.838862 -195.842636) (xy 50.838862 -194.4878) (xy 51.316128 -194.4878) (xy 51.316128 -195.842636)
			)
		)
	)
	(zone
		(layer "In4.Cu")
		(hatch none 0.5)
		(connect_pads
			(clearance 0)
		)
		(min_thickness 0.25)
		(keepout
			(tracks allowed)
			(vias allowed)
			(pads allowed)
			(copperpour allowed)
			(footprints allowed)
		)
		(placement
			(enabled no)
			(sheetname "")
		)
		(fill
			(thermal_gap 0.5)
			(thermal_bridge_width 0.5)
			(island_removal_mode 0)
		)
		(polygon
			(pts
				(xy 298.798742 -303.857914) (xy 298.798742 -302.503078) (xy 299.276008 -302.503078) (xy 299.276008 -303.857914)
			)
		)
	)
	(zone
		(layer "In4.Cu")
		(hatch none 0.5)
		(connect_pads
			(clearance 0)
		)
		(min_thickness 0.25)
		(keepout
			(tracks allowed)
			(vias allowed)
			(pads allowed)
			(copperpour allowed)
			(footprints allowed)
		)
		(placement
			(enabled no)
			(sheetname "")
		)
		(fill
			(thermal_gap 0.5)
			(thermal_bridge_width 0.5)
			(island_removal_mode 0)
		)
		(polygon
			(pts
				(xy 279.586182 -246.042434) (xy 279.586182 -244.687598) (xy 280.063448 -244.687598) (xy 280.063448 -246.042434)
			)
		)
	)
	(zone
		(layer "In4.Cu")
		(hatch none 0.5)
		(connect_pads
			(clearance 0)
		)
		(min_thickness 0.25)
		(keepout
			(tracks allowed)
			(vias allowed)
			(pads allowed)
			(copperpour allowed)
			(footprints allowed)
		)
		(placement
			(enabled no)
			(sheetname "")
		)
		(fill
			(thermal_gap 0.5)
			(thermal_bridge_width 0.5)
			(island_removal_mode 0)
		)
		(polygon
			(pts
				(xy 409.457144 -306.73548) (xy 409.457144 -305.380644) (xy 409.93441 -305.380644) (xy 409.93441 -306.73548)
			)
		)
	)
	(zone
		(layer "In4.Cu")
		(hatch none 0.5)
		(connect_pads
			(clearance 0)
		)
		(min_thickness 0.25)
		(keepout
			(tracks allowed)
			(vias allowed)
			(pads allowed)
			(copperpour allowed)
			(footprints allowed)
		)
		(placement
			(enabled no)
			(sheetname "")
		)
		(fill
			(thermal_gap 0.5)
			(thermal_bridge_width 0.5)
			(island_removal_mode 0)
		)
		(polygon
			(pts
				(xy 35.725862 -313.162696) (xy 35.725862 -311.80786) (xy 36.203128 -311.80786) (xy 36.203128 -313.162696)
			)
		)
	)
	(zone
		(layer "In4.Cu")
		(hatch none 0.5)
		(connect_pads
			(clearance 0)
		)
		(min_thickness 0.25)
		(keepout
			(tracks allowed)
			(vias allowed)
			(pads allowed)
			(copperpour allowed)
			(footprints allowed)
		)
		(placement
			(enabled no)
			(sheetname "")
		)
		(fill
			(thermal_gap 0.5)
			(thermal_bridge_width 0.5)
			(island_removal_mode 0)
		)
		(polygon
			(pts
				(xy 172.560742 -199.25157) (xy 172.560742 -197.896734) (xy 173.038008 -197.896734) (xy 173.038008 -199.25157)
			)
		)
	)
	(zone
		(layer "In4.Cu")
		(hatch none 0.5)
		(connect_pads
			(clearance 0)
		)
		(min_thickness 0.25)
		(keepout
			(tracks allowed)
			(vias allowed)
			(pads allowed)
			(copperpour allowed)
			(footprints allowed)
		)
		(placement
			(enabled no)
			(sheetname "")
		)
		(fill
			(thermal_gap 0.5)
			(thermal_bridge_width 0.5)
			(island_removal_mode 0)
		)
		(polygon
			(pts
				(xy 420.480998 -223.90735) (xy 420.480998 -222.552514) (xy 420.958264 -222.552514) (xy 420.958264 -223.90735)
			)
		)
	)
	(zone
		(layer "In4.Cu")
		(hatch none 0.5)
		(connect_pads
			(clearance 0)
		)
		(min_thickness 0.25)
		(keepout
			(tracks allowed)
			(vias allowed)
			(pads allowed)
			(copperpour allowed)
			(footprints allowed)
		)
		(placement
			(enabled no)
			(sheetname "")
		)
		(fill
			(thermal_gap 0.5)
			(thermal_bridge_width 0.5)
			(island_removal_mode 0)
		)
		(polygon
			(pts
				(xy 405.38781 -244.301518) (xy 405.38781 -242.946682) (xy 405.865076 -242.946682) (xy 405.865076 -244.301518)
			)
		)
	)
	(zone
		(layer "In4.Cu")
		(hatch none 0.5)
		(connect_pads
			(clearance 0)
		)
		(min_thickness 0.25)
		(keepout
			(tracks allowed)
			(vias allowed)
			(pads allowed)
			(copperpour allowed)
			(footprints allowed)
		)
		(placement
			(enabled no)
			(sheetname "")
		)
		(fill
			(thermal_gap 0.5)
			(thermal_bridge_width 0.5)
			(island_removal_mode 0)
		)
		(polygon
			(pts
				(xy 35.743134 -251.528834) (xy 35.743134 -250.173998) (xy 36.2204 -250.173998) (xy 36.2204 -251.528834)
			)
		)
	)
	(zone
		(layer "In4.Cu")
		(hatch none 0.5)
		(connect_pads
			(clearance 0)
		)
		(min_thickness 0.25)
		(keepout
			(tracks allowed)
			(vias allowed)
			(pads allowed)
			(copperpour allowed)
			(footprints allowed)
		)
		(placement
			(enabled no)
			(sheetname "")
		)
		(fill
			(thermal_gap 0.5)
			(thermal_bridge_width 0.5)
			(island_removal_mode 0)
		)
		(polygon
			(pts
				(xy 172.560742 -305.501548) (xy 172.560742 -304.146712) (xy 173.038008 -304.146712) (xy 173.038008 -305.501548)
			)
		)
	)
	(zone
		(layer "In4.Cu")
		(hatch none 0.5)
		(connect_pads
			(clearance 0)
		)
		(min_thickness 0.25)
		(keepout
			(tracks allowed)
			(vias allowed)
			(pads allowed)
			(copperpour allowed)
			(footprints allowed)
		)
		(placement
			(enabled no)
			(sheetname "")
		)
		(fill
			(thermal_gap 0.5)
			(thermal_bridge_width 0.5)
			(island_removal_mode 0)
		)
		(polygon
			(pts
				(xy 435.621684 -311.45988) (xy 435.621684 -310.105044) (xy 436.09895 -310.105044) (xy 436.09895 -311.45988)
			)
		)
	)
	(zone
		(layer "In4.Cu")
		(hatch none 0.5)
		(connect_pads
			(clearance 0)
		)
		(min_thickness 0.25)
		(keepout
			(tracks allowed)
			(vias allowed)
			(pads allowed)
			(copperpour allowed)
			(footprints allowed)
		)
		(placement
			(enabled no)
			(sheetname "")
		)
		(fill
			(thermal_gap 0.5)
			(thermal_bridge_width 0.5)
			(island_removal_mode 0)
		)
		(polygon
			(pts
				(xy 435.568598 -267.25753) (xy 435.568598 -265.902694) (xy 436.045864 -265.902694) (xy 436.045864 -267.25753)
			)
		)
	)
	(zone
		(layer "In4.Cu")
		(hatch none 0.5)
		(connect_pads
			(clearance 0)
		)
		(min_thickness 0.25)
		(keepout
			(tracks allowed)
			(vias allowed)
			(pads allowed)
			(copperpour allowed)
			(footprints allowed)
		)
		(placement
			(enabled no)
			(sheetname "")
		)
		(fill
			(thermal_gap 0.5)
			(thermal_bridge_width 0.5)
			(island_removal_mode 0)
		)
		(polygon
			(pts
				(xy 50.833782 -282.563316) (xy 50.833782 -281.20848) (xy 51.311048 -281.20848) (xy 51.311048 -282.563316)
			)
		)
	)
	(zone
		(layer "In4.Cu")
		(hatch none 0.5)
		(connect_pads
			(clearance 0)
		)
		(min_thickness 0.25)
		(keepout
			(tracks allowed)
			(vias allowed)
			(pads allowed)
			(copperpour allowed)
			(footprints allowed)
		)
		(placement
			(enabled no)
			(sheetname "")
		)
		(fill
			(thermal_gap 0.5)
			(thermal_bridge_width 0.5)
			(island_removal_mode 0)
		)
		(polygon
			(pts
				(xy 108.94314 -15.22984) (xy 108.94314 -13.45184) (xy 109.7915 -13.45184) (xy 109.7915 -15.22984)
			)
		)
	)
	(zone
		(layer "In4.Cu")
		(hatch none 0.5)
		(connect_pads
			(clearance 0)
		)
		(min_thickness 0.25)
		(keepout
			(tracks allowed)
			(vias allowed)
			(pads allowed)
			(copperpour allowed)
			(footprints allowed)
		)
		(placement
			(enabled no)
			(sheetname "")
		)
		(fill
			(thermal_gap 0.5)
			(thermal_bridge_width 0.5)
			(island_removal_mode 0)
		)
		(polygon
			(pts
				(xy 420.50081 -307.20157) (xy 420.50081 -305.846734) (xy 420.978076 -305.846734) (xy 420.978076 -307.20157)
			)
		)
	)
	(zone
		(layer "In4.Cu")
		(hatch none 0.5)
		(connect_pads
			(clearance 0)
		)
		(min_thickness 0.25)
		(keepout
			(tracks allowed)
			(vias allowed)
			(pads allowed)
			(copperpour allowed)
			(footprints allowed)
		)
		(placement
			(enabled no)
			(sheetname "")
		)
		(fill
			(thermal_gap 0.5)
			(thermal_bridge_width 0.5)
			(island_removal_mode 0)
		)
		(polygon
			(pts
				(xy 191.728598 -268.107414) (xy 191.728598 -266.752578) (xy 192.205864 -266.752578) (xy 192.205864 -268.107414)
			)
		)
	)
	(zone
		(layer "In4.Cu")
		(hatch none 0.5)
		(connect_pads
			(clearance 0)
		)
		(min_thickness 0.25)
		(keepout
			(tracks allowed)
			(vias allowed)
			(pads allowed)
			(copperpour allowed)
			(footprints allowed)
		)
		(placement
			(enabled no)
			(sheetname "")
		)
		(fill
			(thermal_gap 0.5)
			(thermal_bridge_width 0.5)
			(island_removal_mode 0)
		)
		(polygon
			(pts
				(xy 298.786042 -280.848054) (xy 298.786042 -279.493218) (xy 299.263308 -279.493218) (xy 299.263308 -280.848054)
			)
		)
	)
	(zone
		(layer "In4.Cu")
		(hatch none 0.5)
		(connect_pads
			(clearance 0)
		)
		(min_thickness 0.25)
		(keepout
			(tracks allowed)
			(vias allowed)
			(pads allowed)
			(copperpour allowed)
			(footprints allowed)
		)
		(placement
			(enabled no)
			(sheetname "")
		)
		(fill
			(thermal_gap 0.5)
			(thermal_bridge_width 0.5)
			(island_removal_mode 0)
		)
		(polygon
			(pts
				(xy 187.62853 -234.957366) (xy 187.62853 -233.60253) (xy 188.105796 -233.60253) (xy 188.105796 -234.957366)
			)
		)
	)
	(zone
		(layer "In4.Cu")
		(hatch none 0.5)
		(connect_pads
			(clearance 0)
		)
		(min_thickness 0.25)
		(keepout
			(tracks allowed)
			(vias allowed)
			(pads allowed)
			(copperpour allowed)
			(footprints allowed)
		)
		(placement
			(enabled no)
			(sheetname "")
		)
		(fill
			(thermal_gap 0.5)
			(thermal_bridge_width 0.5)
			(island_removal_mode 0)
		)
		(polygon
			(pts
				(xy 187.62853 -291.057584) (xy 187.62853 -289.702748) (xy 188.105796 -289.702748) (xy 188.105796 -291.057584)
			)
		)
	)
	(zone
		(layer "In4.Cu")
		(hatch none 0.5)
		(connect_pads
			(clearance 0)
		)
		(min_thickness 0.25)
		(keepout
			(tracks allowed)
			(vias allowed)
			(pads allowed)
			(copperpour allowed)
			(footprints allowed)
		)
		(placement
			(enabled no)
			(sheetname "")
		)
		(fill
			(thermal_gap 0.5)
			(thermal_bridge_width 0.5)
			(island_removal_mode 0)
		)
		(polygon
			(pts
				(xy 298.667932 -317.419736) (xy 298.667932 -316.111636) (xy 299.267372 -316.111636) (xy 299.267372 -317.419736)
			)
		)
	)
	(zone
		(layer "In4.Cu")
		(hatch none 0.5)
		(connect_pads
			(clearance 0)
		)
		(min_thickness 0.25)
		(keepout
			(tracks allowed)
			(vias allowed)
			(pads allowed)
			(copperpour allowed)
			(footprints allowed)
		)
		(placement
			(enabled no)
			(sheetname "")
		)
		(fill
			(thermal_gap 0.5)
			(thermal_bridge_width 0.5)
			(island_removal_mode 0)
		)
		(polygon
			(pts
				(xy 35.720782 -268.123416) (xy 35.720782 -266.76858) (xy 36.198048 -266.76858) (xy 36.198048 -268.123416)
			)
		)
	)
	(zone
		(layer "In4.Cu")
		(hatch none 0.5)
		(connect_pads
			(clearance 0)
		)
		(min_thickness 0.25)
		(keepout
			(tracks allowed)
			(vias allowed)
			(pads allowed)
			(copperpour allowed)
			(footprints allowed)
		)
		(placement
			(enabled no)
			(sheetname "")
		)
		(fill
			(thermal_gap 0.5)
			(thermal_bridge_width 0.5)
			(island_removal_mode 0)
		)
		(polygon
			(pts
				(xy 283.662882 -311.437274) (xy 283.662882 -310.082438) (xy 284.140148 -310.082438) (xy 284.140148 -311.437274)
			)
		)
	)
	(zone
		(layer "In4.Cu")
		(hatch none 0.5)
		(connect_pads
			(clearance 0)
		)
		(min_thickness 0.25)
		(keepout
			(tracks allowed)
			(vias allowed)
			(pads allowed)
			(copperpour allowed)
			(footprints allowed)
		)
		(placement
			(enabled no)
			(sheetname "")
		)
		(fill
			(thermal_gap 0.5)
			(thermal_bridge_width 0.5)
			(island_removal_mode 0)
		)
		(polygon
			(pts
				(xy 283.64815 -266.444476) (xy 283.64815 -265.08964) (xy 284.125416 -265.08964) (xy 284.125416 -266.444476)
			)
		)
	)
	(zone
		(layer "In4.Cu")
		(hatch none 0.5)
		(connect_pads
			(clearance 0)
		)
		(min_thickness 0.25)
		(keepout
			(tracks allowed)
			(vias allowed)
			(pads allowed)
			(copperpour allowed)
			(footprints allowed)
		)
		(placement
			(enabled no)
			(sheetname "")
		)
		(fill
			(thermal_gap 0.5)
			(thermal_bridge_width 0.5)
			(island_removal_mode 0)
		)
		(polygon
			(pts
				(xy 283.704538 -317.250572) (xy 283.704538 -315.999368) (xy 284.329632 -315.999368) (xy 284.329632 -317.250572)
			)
		)
	)
	(zone
		(layer "In4.Cu")
		(hatch none 0.5)
		(connect_pads
			(clearance 0)
		)
		(min_thickness 0.25)
		(keepout
			(tracks allowed)
			(vias allowed)
			(pads allowed)
			(copperpour allowed)
			(footprints allowed)
		)
		(placement
			(enabled no)
			(sheetname "")
		)
		(fill
			(thermal_gap 0.5)
			(thermal_bridge_width 0.5)
			(island_removal_mode 0)
		)
		(polygon
			(pts
				(xy 187.661804 -311.465722) (xy 187.661804 -310.110886) (xy 188.13907 -310.110886) (xy 188.13907 -311.465722)
			)
		)
	)
	(zone
		(layer "In4.Cu")
		(hatch none 0.5)
		(connect_pads
			(clearance 0)
		)
		(min_thickness 0.25)
		(keepout
			(tracks allowed)
			(vias allowed)
			(pads allowed)
			(copperpour allowed)
			(footprints allowed)
		)
		(placement
			(enabled no)
			(sheetname "")
		)
		(fill
			(thermal_gap 0.5)
			(thermal_bridge_width 0.5)
			(island_removal_mode 0)
		)
		(polygon
			(pts
				(xy 435.568598 -289.357562) (xy 435.568598 -288.002726) (xy 436.045864 -288.002726) (xy 436.045864 -289.357562)
			)
		)
	)
	(zone
		(layer "In4.Cu")
		(hatch none 0.5)
		(connect_pads
			(clearance 0)
		)
		(min_thickness 0.25)
		(keepout
			(tracks allowed)
			(vias allowed)
			(pads allowed)
			(copperpour allowed)
			(footprints allowed)
		)
		(placement
			(enabled no)
			(sheetname "")
		)
		(fill
			(thermal_gap 0.5)
			(thermal_bridge_width 0.5)
			(island_removal_mode 0)
		)
		(polygon
			(pts
				(xy 145.796 -9.23544) (xy 145.796 -8.0264) (xy 140.34516 -8.0264) (xy 140.34516 -9.23544)
			)
		)
	)
	(zone
		(layer "In4.Cu")
		(hatch none 0.5)
		(connect_pads
			(clearance 0)
		)
		(min_thickness 0.25)
		(keepout
			(tracks allowed)
			(vias allowed)
			(pads allowed)
			(copperpour allowed)
			(footprints allowed)
		)
		(placement
			(enabled no)
			(sheetname "")
		)
		(fill
			(thermal_gap 0.5)
			(thermal_bridge_width 0.5)
			(island_removal_mode 0)
		)
		(polygon
			(pts
				(xy 31.641034 -267.279374) (xy 31.641034 -265.924538) (xy 32.1183 -265.924538) (xy 32.1183 -267.279374)
			)
		)
	)
	(zone
		(layer "In4.Cu")
		(hatch none 0.5)
		(connect_pads
			(clearance 0)
		)
		(min_thickness 0.25)
		(keepout
			(tracks allowed)
			(vias allowed)
			(pads allowed)
			(copperpour allowed)
			(footprints allowed)
		)
		(placement
			(enabled no)
			(sheetname "")
		)
		(fill
			(thermal_gap 0.5)
			(thermal_bridge_width 0.5)
			(island_removal_mode 0)
		)
		(polygon
			(pts
				(xy 187.648342 -233.251756) (xy 187.648342 -231.89692) (xy 188.125608 -231.89692) (xy 188.125608 -233.251756)
			)
		)
	)
	(zone
		(layer "In4.Cu")
		(hatch none 0.5)
		(connect_pads
			(clearance 0)
		)
		(min_thickness 0.25)
		(keepout
			(tracks allowed)
			(vias allowed)
			(pads allowed)
			(copperpour allowed)
			(footprints allowed)
		)
		(placement
			(enabled no)
			(sheetname "")
		)
		(fill
			(thermal_gap 0.5)
			(thermal_bridge_width 0.5)
			(island_removal_mode 0)
		)
		(polygon
			(pts
				(xy 63.717424 -244.397276) (xy 63.717424 -241.308636) (xy 64.111124 -241.308636) (xy 64.111124 -244.397276)
			)
		)
	)
	(zone
		(layer "In4.Cu")
		(hatch none 0.5)
		(connect_pads
			(clearance 0)
		)
		(min_thickness 0.25)
		(keepout
			(tracks allowed)
			(vias allowed)
			(pads allowed)
			(copperpour allowed)
			(footprints allowed)
		)
		(placement
			(enabled no)
			(sheetname "")
		)
		(fill
			(thermal_gap 0.5)
			(thermal_bridge_width 0.5)
			(island_removal_mode 0)
		)
		(polygon
			(pts
				(xy 283.673042 -248.636536) (xy 283.673042 -248.01195) (xy 284.150308 -248.01195) (xy 284.456378 -248.01195)
				(xy 284.52826 -248.083832) (xy 284.52826 -248.550938) (xy 284.442662 -248.636536) (xy 284.150308 -248.636536)
			)
		)
	)
	(zone
		(layer "In4.Cu")
		(hatch none 0.5)
		(connect_pads
			(clearance 0)
		)
		(min_thickness 0.25)
		(keepout
			(tracks allowed)
			(vias allowed)
			(pads allowed)
			(copperpour allowed)
			(footprints allowed)
		)
		(placement
			(enabled no)
			(sheetname "")
		)
		(fill
			(thermal_gap 0.5)
			(thermal_bridge_width 0.5)
			(island_removal_mode 0)
		)
		(polygon
			(pts
				(xy 35.732974 -238.379254) (xy 35.732974 -237.024418) (xy 36.21024 -237.024418) (xy 36.21024 -238.379254)
			)
		)
	)
	(zone
		(layer "In4.Cu")
		(hatch none 0.5)
		(connect_pads
			(clearance 0)
		)
		(min_thickness 0.25)
		(keepout
			(tracks allowed)
			(vias allowed)
			(pads allowed)
			(copperpour allowed)
			(footprints allowed)
		)
		(placement
			(enabled no)
			(sheetname "")
		)
		(fill
			(thermal_gap 0.5)
			(thermal_bridge_width 0.5)
			(island_removal_mode 0)
		)
		(polygon
			(pts
				(xy 299.93082 -195.769738) (xy 299.93082 -194.558158) (xy 300.48962 -194.558158) (xy 300.48962 -195.769738)
			)
		)
	)
	(zone
		(layer "In4.Cu")
		(hatch none 0.5)
		(connect_pads
			(clearance 0)
		)
		(min_thickness 0.25)
		(keepout
			(tracks allowed)
			(vias allowed)
			(pads allowed)
			(copperpour allowed)
			(footprints allowed)
		)
		(placement
			(enabled no)
			(sheetname "")
		)
		(fill
			(thermal_gap 0.5)
			(thermal_bridge_width 0.5)
			(island_removal_mode 0)
		)
		(polygon
			(pts
				(xy 35.746182 -210.249516) (xy 35.746182 -208.89468) (xy 36.223448 -208.89468) (xy 36.223448 -210.249516)
			)
		)
	)
	(zone
		(layer "In4.Cu")
		(hatch none 0.5)
		(connect_pads
			(clearance 0)
		)
		(min_thickness 0.25)
		(keepout
			(tracks allowed)
			(vias allowed)
			(pads allowed)
			(copperpour allowed)
			(footprints allowed)
		)
		(placement
			(enabled no)
			(sheetname "")
		)
		(fill
			(thermal_gap 0.5)
			(thermal_bridge_width 0.5)
			(island_removal_mode 0)
		)
		(polygon
			(pts
				(xy 912.731474 -85.360764) (xy 929.617394 -85.360764) (xy 929.884094 -85.094064) (xy 929.884094 -69.993764)
				(xy 928.177214 -68.286884) (xy 912.728934 -68.286884) (xy 912.010114 -69.005704) (xy 912.010114 -69.915024)
				(xy 911.557994 -70.367144) (xy 911.557994 -84.187284)
			)
		)
	)
	(zone
		(layer "In4.Cu")
		(hatch none 0.5)
		(connect_pads
			(clearance 0)
		)
		(min_thickness 0.25)
		(keepout
			(tracks allowed)
			(vias allowed)
			(pads allowed)
			(copperpour allowed)
			(footprints allowed)
		)
		(placement
			(enabled no)
			(sheetname "")
		)
		(fill
			(thermal_gap 0.5)
			(thermal_bridge_width 0.5)
			(island_removal_mode 0)
		)
		(polygon
			(pts
				(xy 187.648342 -293.623238) (xy 187.648342 -291.396928) (xy 188.125608 -291.396928) (xy 188.125608 -293.623238)
			)
		)
	)
	(zone
		(layer "In4.Cu")
		(hatch none 0.5)
		(connect_pads
			(clearance 0)
		)
		(min_thickness 0.25)
		(keepout
			(tracks allowed)
			(vias allowed)
			(pads allowed)
			(copperpour allowed)
			(footprints allowed)
		)
		(placement
			(enabled no)
			(sheetname "")
		)
		(fill
			(thermal_gap 0.5)
			(thermal_bridge_width 0.5)
			(island_removal_mode 0)
		)
		(polygon
			(pts
				(xy 46.737524 -318.307212) (xy 46.737524 -316.045596) (xy 47.278544 -316.045596) (xy 47.278544 -318.307212)
			)
		)
	)
	(zone
		(layer "In4.Cu")
		(hatch none 0.5)
		(connect_pads
			(clearance 0)
		)
		(min_thickness 0.25)
		(keepout
			(tracks allowed)
			(vias allowed)
			(pads allowed)
			(copperpour allowed)
			(footprints allowed)
		)
		(placement
			(enabled no)
			(sheetname "")
		)
		(fill
			(thermal_gap 0.5)
			(thermal_bridge_width 0.5)
			(island_removal_mode 0)
		)
		(polygon
			(pts
				(xy 35.765994 -210.243674) (xy 35.765994 -208.888838) (xy 36.24326 -208.888838) (xy 36.24326 -210.243674)
			)
		)
	)
	(zone
		(layer "In4.Cu")
		(hatch none 0.5)
		(connect_pads
			(clearance 0)
		)
		(min_thickness 0.25)
		(keepout
			(tracks allowed)
			(vias allowed)
			(pads allowed)
			(copperpour allowed)
			(footprints allowed)
		)
		(placement
			(enabled no)
			(sheetname "")
		)
		(fill
			(thermal_gap 0.5)
			(thermal_bridge_width 0.5)
			(island_removal_mode 0)
		)
		(polygon
			(pts
				(xy 309.70982 -245.106698) (xy 309.70982 -242.929918) (xy 310.33212 -242.929918) (xy 310.33212 -245.106698)
			)
		)
	)
	(zone
		(layer "In4.Cu")
		(hatch none 0.5)
		(connect_pads
			(clearance 0)
		)
		(min_thickness 0.25)
		(keepout
			(tracks allowed)
			(vias allowed)
			(pads allowed)
			(copperpour allowed)
			(footprints allowed)
		)
		(placement
			(enabled no)
			(sheetname "")
		)
		(fill
			(thermal_gap 0.5)
			(thermal_bridge_width 0.5)
			(island_removal_mode 0)
		)
		(polygon
			(pts
				(xy 283.685742 -294.142414) (xy 283.685742 -292.787578) (xy 284.163008 -292.787578) (xy 284.163008 -294.142414)
			)
		)
	)
	(zone
		(layer "In4.Cu")
		(hatch none 0.5)
		(connect_pads
			(clearance 0)
		)
		(min_thickness 0.25)
		(keepout
			(tracks allowed)
			(vias allowed)
			(pads allowed)
			(copperpour allowed)
			(footprints allowed)
		)
		(placement
			(enabled no)
			(sheetname "")
		)
		(fill
			(thermal_gap 0.5)
			(thermal_bridge_width 0.5)
			(island_removal_mode 0)
		)
		(polygon
			(pts
				(xy 50.826162 -280.853896) (xy 50.826162 -279.49906) (xy 51.303428 -279.49906) (xy 51.303428 -280.853896)
			)
		)
	)
	(zone
		(layer "In4.Cu")
		(hatch none 0.5)
		(connect_pads
			(clearance 0)
		)
		(min_thickness 0.25)
		(keepout
			(tracks allowed)
			(vias allowed)
			(pads allowed)
			(copperpour allowed)
			(footprints allowed)
		)
		(placement
			(enabled no)
			(sheetname "")
		)
		(fill
			(thermal_gap 0.5)
			(thermal_bridge_width 0.5)
			(island_removal_mode 0)
		)
		(polygon
			(pts
				(xy 309.6895 -301.205138) (xy 309.6895 -298.065698) (xy 310.13654 -298.065698) (xy 310.13654 -301.205138)
			)
		)
	)
	(zone
		(layer "In4.Cu")
		(hatch none 0.5)
		(connect_pads
			(clearance 0)
		)
		(min_thickness 0.25)
		(keepout
			(tracks allowed)
			(vias allowed)
			(pads allowed)
			(copperpour allowed)
			(footprints allowed)
		)
		(placement
			(enabled no)
			(sheetname "")
		)
		(fill
			(thermal_gap 0.5)
			(thermal_bridge_width 0.5)
			(island_removal_mode 0)
		)
		(polygon
			(pts
				(xy 31.646114 -246.042434) (xy 31.646114 -244.687598) (xy 32.12338 -244.687598) (xy 32.12338 -246.042434)
			)
		)
	)
	(zone
		(layer "In4.Cu")
		(hatch none 0.5)
		(connect_pads
			(clearance 0)
		)
		(min_thickness 0.25)
		(keepout
			(tracks allowed)
			(vias allowed)
			(pads allowed)
			(copperpour allowed)
			(footprints allowed)
		)
		(placement
			(enabled no)
			(sheetname "")
		)
		(fill
			(thermal_gap 0.5)
			(thermal_bridge_width 0.5)
			(island_removal_mode 0)
		)
		(polygon
			(pts
				(xy 283.673042 -238.379254) (xy 283.673042 -237.024418) (xy 284.150308 -237.024418) (xy 284.150308 -238.379254)
			)
		)
	)
	(zone
		(layer "In4.Cu")
		(hatch none 0.5)
		(connect_pads
			(clearance 0)
		)
		(min_thickness 0.25)
		(keepout
			(tracks allowed)
			(vias allowed)
			(pads allowed)
			(copperpour allowed)
			(footprints allowed)
		)
		(placement
			(enabled no)
			(sheetname "")
		)
		(fill
			(thermal_gap 0.5)
			(thermal_bridge_width 0.5)
			(island_removal_mode 0)
		)
		(polygon
			(pts
				(xy 283.64815 -235.819696) (xy 283.64815 -234.46486) (xy 284.125416 -234.46486) (xy 284.125416 -235.819696)
			)
		)
	)
	(zone
		(layer "In4.Cu")
		(hatch none 0.5)
		(connect_pads
			(clearance 0)
		)
		(min_thickness 0.25)
		(keepout
			(tracks allowed)
			(vias allowed)
			(pads allowed)
			(copperpour allowed)
			(footprints allowed)
		)
		(placement
			(enabled no)
			(sheetname "")
		)
		(fill
			(thermal_gap 0.5)
			(thermal_bridge_width 0.5)
			(island_removal_mode 0)
		)
		(polygon
			(pts
				(xy 176.663096 -319.15608) (xy 176.663096 -317.801244) (xy 177.140362 -317.801244) (xy 177.140362 -319.15608)
			)
		)
	)
	(zone
		(layer "In4.Cu")
		(hatch none 0.5)
		(connect_pads
			(clearance 0)
		)
		(min_thickness 0.25)
		(keepout
			(tracks allowed)
			(vias allowed)
			(pads allowed)
			(copperpour allowed)
			(footprints allowed)
		)
		(placement
			(enabled no)
			(sheetname "")
		)
		(fill
			(thermal_gap 0.5)
			(thermal_bridge_width 0.5)
			(island_removal_mode 0)
		)
		(polygon
			(pts
				(xy 420.480998 -305.50739) (xy 420.480998 -304.152554) (xy 420.958264 -304.152554) (xy 420.958264 -305.50739)
			)
		)
	)
	(zone
		(layer "In4.Cu")
		(hatch none 0.5)
		(connect_pads
			(clearance 0)
		)
		(min_thickness 0.25)
		(keepout
			(tracks allowed)
			(vias allowed)
			(pads allowed)
			(copperpour allowed)
			(footprints allowed)
		)
		(placement
			(enabled no)
			(sheetname "")
		)
		(fill
			(thermal_gap 0.5)
			(thermal_bridge_width 0.5)
			(island_removal_mode 0)
		)
		(polygon
			(pts
				(xy 191.74841 -250.251722) (xy 191.74841 -248.896886) (xy 192.225676 -248.896886) (xy 192.225676 -250.251722)
			)
		)
	)
	(zone
		(layer "In4.Cu")
		(hatch none 0.5)
		(connect_pads
			(clearance 0)
		)
		(min_thickness 0.25)
		(keepout
			(tracks allowed)
			(vias allowed)
			(pads allowed)
			(copperpour allowed)
			(footprints allowed)
		)
		(placement
			(enabled no)
			(sheetname "")
		)
		(fill
			(thermal_gap 0.5)
			(thermal_bridge_width 0.5)
			(island_removal_mode 0)
		)
		(polygon
			(pts
				(xy 283.680662 -268.117574) (xy 283.680662 -266.762738) (xy 284.157928 -266.762738) (xy 284.157928 -268.117574)
			)
		)
	)
	(zone
		(layer "In4.Cu")
		(hatch none 0.5)
		(connect_pads
			(clearance 0)
		)
		(min_thickness 0.25)
		(keepout
			(tracks allowed)
			(vias allowed)
			(pads allowed)
			(copperpour allowed)
			(footprints allowed)
		)
		(placement
			(enabled no)
			(sheetname "")
		)
		(fill
			(thermal_gap 0.5)
			(thermal_bridge_width 0.5)
			(island_removal_mode 0)
		)
		(polygon
			(pts
				(xy 420.50081 -228.139498) (xy 420.50081 -225.946716) (xy 420.978076 -225.946716) (xy 420.978076 -228.139498)
			)
		)
	)
	(zone
		(layer "In4.Cu")
		(hatch none 0.5)
		(connect_pads
			(clearance 0)
		)
		(min_thickness 0.25)
		(keepout
			(tracks allowed)
			(vias allowed)
			(pads allowed)
			(copperpour allowed)
			(footprints allowed)
		)
		(placement
			(enabled no)
			(sheetname "")
		)
		(fill
			(thermal_gap 0.5)
			(thermal_bridge_width 0.5)
			(island_removal_mode 0)
		)
		(polygon
			(pts
				(xy 172.560742 -307.20157) (xy 172.560742 -305.846734) (xy 173.038008 -305.846734) (xy 173.038008 -307.20157)
			)
		)
	)
	(zone
		(layer "In4.Cu")
		(hatch none 0.5)
		(connect_pads
			(clearance 0)
		)
		(min_thickness 0.25)
		(keepout
			(tracks allowed)
			(vias allowed)
			(pads allowed)
			(copperpour allowed)
			(footprints allowed)
		)
		(placement
			(enabled no)
			(sheetname "")
		)
		(fill
			(thermal_gap 0.5)
			(thermal_bridge_width 0.5)
			(island_removal_mode 0)
		)
		(polygon
			(pts
				(xy 35.765994 -309.758334) (xy 35.765994 -308.403498) (xy 36.24326 -308.403498) (xy 36.24326 -309.758334)
			)
		)
	)
	(zone
		(layer "In4.Cu")
		(hatch none 0.5)
		(connect_pads
			(clearance 0)
		)
		(min_thickness 0.25)
		(keepout
			(tracks allowed)
			(vias allowed)
			(pads allowed)
			(copperpour allowed)
			(footprints allowed)
		)
		(placement
			(enabled no)
			(sheetname "")
		)
		(fill
			(thermal_gap 0.5)
			(thermal_bridge_width 0.5)
			(island_removal_mode 0)
		)
		(polygon
			(pts
				(xy 48.604424 -319.957704) (xy 48.604424 -318.602868) (xy 49.08169 -318.602868) (xy 49.08169 -319.957704)
			)
		)
	)
	(zone
		(layer "In4.Cu")
		(hatch none 0.5)
		(connect_pads
			(clearance 0)
		)
		(min_thickness 0.25)
		(keepout
			(tracks allowed)
			(vias allowed)
			(pads allowed)
			(copperpour allowed)
			(footprints allowed)
		)
		(placement
			(enabled no)
			(sheetname "")
		)
		(fill
			(thermal_gap 0.5)
			(thermal_bridge_width 0.5)
			(island_removal_mode 0)
		)
		(polygon
			(pts
				(xy 326.81418 -347.952568) (xy 326.81418 -346.306648) (xy 329.11542 -346.306648) (xy 329.11542 -347.952568)
			)
		)
	)
	(zone
		(layer "In4.Cu")
		(hatch none 0.5)
		(connect_pads
			(clearance 0)
		)
		(min_thickness 0.25)
		(keepout
			(tracks allowed)
			(vias allowed)
			(pads allowed)
			(copperpour allowed)
			(footprints allowed)
		)
		(placement
			(enabled no)
			(sheetname "")
		)
		(fill
			(thermal_gap 0.5)
			(thermal_bridge_width 0.5)
			(island_removal_mode 0)
		)
		(polygon
			(pts
				(xy 172.54093 -243.457476) (xy 172.54093 -242.96116) (xy 172.144944 -242.96116) (xy 172.144944 -242.10264)
				(xy 172.54093 -242.10264) (xy 173.018196 -242.10264) (xy 173.30166 -242.10264) (xy 173.30166 -242.977924)
				(xy 173.018196 -242.977924) (xy 173.018196 -243.457476)
			)
		)
	)
	(zone
		(layer "In4.Cu")
		(hatch none 0.5)
		(connect_pads
			(clearance 0)
		)
		(min_thickness 0.25)
		(keepout
			(tracks allowed)
			(vias allowed)
			(pads allowed)
			(copperpour allowed)
			(footprints allowed)
		)
		(placement
			(enabled no)
			(sheetname "")
		)
		(fill
			(thermal_gap 0.5)
			(thermal_bridge_width 0.5)
			(island_removal_mode 0)
		)
		(polygon
			(pts
				(xy 61.769244 -301.199296) (xy 61.769244 -298.059856) (xy 62.216284 -298.059856) (xy 62.216284 -301.199296)
			)
		)
	)
	(zone
		(layer "In4.Cu")
		(hatch none 0.5)
		(connect_pads
			(clearance 0)
		)
		(min_thickness 0.25)
		(keepout
			(tracks allowed)
			(vias allowed)
			(pads allowed)
			(copperpour allowed)
			(footprints allowed)
		)
		(placement
			(enabled no)
			(sheetname "")
		)
		(fill
			(thermal_gap 0.5)
			(thermal_bridge_width 0.5)
			(island_removal_mode 0)
		)
		(polygon
			(pts
				(xy 35.765994 -211.343494) (xy 35.765994 -209.988658) (xy 36.24326 -209.988658) (xy 36.24326 -211.343494)
			)
		)
	)
	(zone
		(layer "In4.Cu")
		(hatch none 0.5)
		(connect_pads
			(clearance 0)
		)
		(min_thickness 0.25)
		(keepout
			(tracks allowed)
			(vias allowed)
			(pads allowed)
			(copperpour allowed)
			(footprints allowed)
		)
		(placement
			(enabled no)
			(sheetname "")
		)
		(fill
			(thermal_gap 0.5)
			(thermal_bridge_width 0.5)
			(island_removal_mode 0)
		)
		(polygon
			(pts
				(xy 36.935156 -319.10782) (xy 36.935156 -317.752984) (xy 37.412422 -317.752984) (xy 37.412422 -319.10782)
			)
		)
	)
	(zone
		(layer "In4.Cu")
		(hatch none 0.5)
		(connect_pads
			(clearance 0)
		)
		(min_thickness 0.25)
		(keepout
			(tracks allowed)
			(vias allowed)
			(pads allowed)
			(copperpour allowed)
			(footprints allowed)
		)
		(placement
			(enabled no)
			(sheetname "")
		)
		(fill
			(thermal_gap 0.5)
			(thermal_bridge_width 0.5)
			(island_removal_mode 0)
		)
		(polygon
			(pts
				(xy 439.668666 -246.007382) (xy 439.668666 -244.652546) (xy 440.145932 -244.652546) (xy 440.145932 -246.007382)
			)
		)
	)
	(zone
		(layer "In4.Cu")
		(hatch none 0.5)
		(connect_pads
			(clearance 0)
		)
		(min_thickness 0.25)
		(keepout
			(tracks allowed)
			(vias allowed)
			(pads allowed)
			(copperpour allowed)
			(footprints allowed)
		)
		(placement
			(enabled no)
			(sheetname "")
		)
		(fill
			(thermal_gap 0.5)
			(thermal_bridge_width 0.5)
			(island_removal_mode 0)
		)
		(polygon
			(pts
				(xy 86.2965 -341.782908) (xy 86.2965 -340.073488) (xy 89.27592 -340.073488) (xy 89.27592 -341.782908)
			)
		)
	)
	(zone
		(layer "In4.Cu")
		(hatch none 0.5)
		(connect_pads
			(clearance 0)
		)
		(min_thickness 0.25)
		(keepout
			(tracks allowed)
			(vias allowed)
			(pads allowed)
			(copperpour allowed)
			(footprints allowed)
		)
		(placement
			(enabled no)
			(sheetname "")
		)
		(fill
			(thermal_gap 0.5)
			(thermal_bridge_width 0.5)
			(island_removal_mode 0)
		)
		(polygon
			(pts
				(xy 279.581102 -269.826994) (xy 279.581102 -268.472158) (xy 280.058368 -268.472158) (xy 280.058368 -269.826994)
			)
		)
	)
	(zone
		(layer "In4.Cu")
		(hatch none 0.5)
		(connect_pads
			(clearance 0)
		)
		(min_thickness 0.25)
		(keepout
			(tracks allowed)
			(vias allowed)
			(pads allowed)
			(copperpour allowed)
			(footprints allowed)
		)
		(placement
			(enabled no)
			(sheetname "")
		)
		(fill
			(thermal_gap 0.5)
			(thermal_bridge_width 0.5)
			(island_removal_mode 0)
		)
		(polygon
			(pts
				(xy 59.471052 -195.802758) (xy 59.471052 -194.527678) (xy 60.123832 -194.527678) (xy 60.123832 -195.802758)
			)
		)
	)
	(zone
		(layer "In4.Cu")
		(hatch none 0.5)
		(connect_pads
			(clearance 0)
		)
		(min_thickness 0.25)
		(keepout
			(tracks allowed)
			(vias allowed)
			(pads allowed)
			(copperpour allowed)
			(footprints allowed)
		)
		(placement
			(enabled no)
			(sheetname "")
		)
		(fill
			(thermal_gap 0.5)
			(thermal_bridge_width 0.5)
			(island_removal_mode 0)
		)
		(polygon
			(pts
				(xy 50.838862 -305.242976) (xy 50.838862 -303.88814) (xy 51.316128 -303.88814) (xy 51.316128 -305.242976)
			)
		)
	)
	(zone
		(layer "In4.Cu")
		(hatch none 0.5)
		(connect_pads
			(clearance 0)
		)
		(min_thickness 0.25)
		(keepout
			(tracks allowed)
			(vias allowed)
			(pads allowed)
			(copperpour allowed)
			(footprints allowed)
		)
		(placement
			(enabled no)
			(sheetname "")
		)
		(fill
			(thermal_gap 0.5)
			(thermal_bridge_width 0.5)
			(island_removal_mode 0)
		)
		(polygon
			(pts
				(xy 283.680662 -269.433294) (xy 283.680662 -268.078458) (xy 284.157928 -268.078458) (xy 284.157928 -269.433294)
			)
		)
	)
	(zone
		(layer "In4.Cu")
		(hatch none 0.5)
		(connect_pads
			(clearance 0)
		)
		(min_thickness 0.25)
		(keepout
			(tracks allowed)
			(vias allowed)
			(pads allowed)
			(copperpour allowed)
			(footprints allowed)
		)
		(placement
			(enabled no)
			(sheetname "")
		)
		(fill
			(thermal_gap 0.5)
			(thermal_bridge_width 0.5)
			(island_removal_mode 0)
		)
		(polygon
			(pts
				(xy 298.798742 -305.237134) (xy 298.798742 -303.882298) (xy 299.276008 -303.882298) (xy 299.276008 -305.237134)
			)
		)
	)
	(zone
		(layer "In4.Cu")
		(hatch none 0.5)
		(connect_pads
			(clearance 0)
		)
		(min_thickness 0.25)
		(keepout
			(tracks allowed)
			(vias allowed)
			(pads allowed)
			(copperpour allowed)
			(footprints allowed)
		)
		(placement
			(enabled no)
			(sheetname "")
		)
		(fill
			(thermal_gap 0.5)
			(thermal_bridge_width 0.5)
			(island_removal_mode 0)
		)
		(polygon
			(pts
				(xy 435.58841 -244.301518) (xy 435.58841 -242.946682) (xy 436.065676 -242.946682) (xy 436.065676 -244.301518)
			)
		)
	)
	(zone
		(layer "In4.Cu")
		(hatch none 0.5)
		(connect_pads
			(clearance 0)
		)
		(min_thickness 0.25)
		(keepout
			(tracks allowed)
			(vias allowed)
			(pads allowed)
			(copperpour allowed)
			(footprints allowed)
		)
		(placement
			(enabled no)
			(sheetname "")
		)
		(fill
			(thermal_gap 0.5)
			(thermal_bridge_width 0.5)
			(island_removal_mode 0)
		)
		(polygon
			(pts
				(xy 307.41112 -195.802758) (xy 307.41112 -194.527678) (xy 308.0639 -194.527678) (xy 308.0639 -195.802758)
			)
		)
	)
	(zone
		(layer "In4.Cu")
		(hatch none 0.5)
		(connect_pads
			(clearance 0)
		)
		(min_thickness 0.25)
		(keepout
			(tracks allowed)
			(vias allowed)
			(pads allowed)
			(copperpour allowed)
			(footprints allowed)
		)
		(placement
			(enabled no)
			(sheetname "")
		)
		(fill
			(thermal_gap 0.5)
			(thermal_bridge_width 0.5)
			(island_removal_mode 0)
		)
		(polygon
			(pts
				(xy 298.727622 -252.700028) (xy 298.727622 -251.730764) (xy 299.177964 -251.730764) (xy 299.177964 -252.700028)
			)
		)
	)
	(zone
		(layer "In4.Cu")
		(hatch none 0.5)
		(connect_pads
			(clearance 0)
		)
		(min_thickness 0.25)
		(keepout
			(tracks allowed)
			(vias allowed)
			(pads allowed)
			(copperpour allowed)
			(footprints allowed)
		)
		(placement
			(enabled no)
			(sheetname "")
		)
		(fill
			(thermal_gap 0.5)
			(thermal_bridge_width 0.5)
			(island_removal_mode 0)
		)
		(polygon
			(pts
				(xy 187.62853 -252.80747) (xy 187.62853 -251.452634) (xy 188.105796 -251.452634) (xy 188.105796 -252.80747)
			)
		)
	)
	(zone
		(layer "In4.Cu")
		(hatch none 0.5)
		(connect_pads
			(clearance 0)
		)
		(min_thickness 0.25)
		(keepout
			(tracks allowed)
			(vias allowed)
			(pads allowed)
			(copperpour allowed)
			(footprints allowed)
		)
		(placement
			(enabled no)
			(sheetname "")
		)
		(fill
			(thermal_gap 0.5)
			(thermal_bridge_width 0.5)
			(island_removal_mode 0)
		)
		(polygon
			(pts
				(xy 279.56129 -269.832836) (xy 279.56129 -268.478) (xy 280.038556 -268.478) (xy 280.038556 -269.832836)
			)
		)
	)
	(zone
		(layer "In4.Cu")
		(hatch none 0.5)
		(connect_pads
			(clearance 0)
		)
		(min_thickness 0.25)
		(keepout
			(tracks allowed)
			(vias allowed)
			(pads allowed)
			(copperpour allowed)
			(footprints allowed)
		)
		(placement
			(enabled no)
			(sheetname "")
		)
		(fill
			(thermal_gap 0.5)
			(thermal_bridge_width 0.5)
			(island_removal_mode 0)
		)
		(polygon
			(pts
				(xy 283.62275 -290.216336) (xy 283.62275 -288.8615) (xy 284.100016 -288.8615) (xy 284.100016 -290.216336)
			)
		)
	)
	(zone
		(layer "In4.Cu")
		(hatch none 0.5)
		(connect_pads
			(clearance 0)
		)
		(min_thickness 0.25)
		(keepout
			(tracks allowed)
			(vias allowed)
			(pads allowed)
			(copperpour allowed)
			(footprints allowed)
		)
		(placement
			(enabled no)
			(sheetname "")
		)
		(fill
			(thermal_gap 0.5)
			(thermal_bridge_width 0.5)
			(island_removal_mode 0)
		)
		(polygon
			(pts
				(xy 187.62853 -289.357562) (xy 187.62853 -288.002726) (xy 188.105796 -288.002726) (xy 188.105796 -289.357562)
			)
		)
	)
	(zone
		(layer "In4.Cu")
		(hatch none 0.5)
		(connect_pads
			(clearance 0)
		)
		(min_thickness 0.25)
		(keepout
			(tracks allowed)
			(vias allowed)
			(pads allowed)
			(copperpour allowed)
			(footprints allowed)
		)
		(placement
			(enabled no)
			(sheetname "")
		)
		(fill
			(thermal_gap 0.5)
			(thermal_bridge_width 0.5)
			(island_removal_mode 0)
		)
		(polygon
			(pts
				(xy 276.122892 -246.007636) (xy 276.122892 -244.6528) (xy 276.600158 -244.6528) (xy 276.600158 -246.007636)
			)
		)
	)
	(zone
		(layer "In4.Cu")
		(hatch none 0.5)
		(connect_pads
			(clearance 0)
		)
		(min_thickness 0.25)
		(keepout
			(tracks allowed)
			(vias allowed)
			(pads allowed)
			(copperpour allowed)
			(footprints allowed)
		)
		(placement
			(enabled no)
			(sheetname "")
		)
		(fill
			(thermal_gap 0.5)
			(thermal_bridge_width 0.5)
			(island_removal_mode 0)
		)
		(polygon
			(pts
				(xy 307.563012 -318.204596) (xy 307.563012 -316.906656) (xy 308.068472 -316.906656) (xy 308.068472 -318.204596)
			)
		)
	)
	(zone
		(layer "In4.Cu")
		(hatch none 0.5)
		(connect_pads
			(clearance 0)
		)
		(min_thickness 0.25)
		(keepout
			(tracks allowed)
			(vias allowed)
			(pads allowed)
			(copperpour allowed)
			(footprints allowed)
		)
		(placement
			(enabled no)
			(sheetname "")
		)
		(fill
			(thermal_gap 0.5)
			(thermal_bridge_width 0.5)
			(island_removal_mode 0)
		)
		(polygon
			(pts
				(xy 309.765192 -305.537616) (xy 309.765192 -301.592996) (xy 310.288432 -301.592996) (xy 310.288432 -305.537616)
			)
		)
	)
	(zone
		(layer "In4.Cu")
		(hatch none 0.5)
		(connect_pads
			(clearance 0)
		)
		(min_thickness 0.25)
		(keepout
			(tracks allowed)
			(vias allowed)
			(pads allowed)
			(copperpour allowed)
			(footprints allowed)
		)
		(placement
			(enabled no)
			(sheetname "")
		)
		(fill
			(thermal_gap 0.5)
			(thermal_bridge_width 0.5)
			(island_removal_mode 0)
		)
		(polygon
			(pts
				(xy 425.058332 -287.152842) (xy 425.058332 -288.507678) (xy 424.581066 -288.507678) (xy 424.41368 -288.507678)
				(xy 423.921428 -288.507678) (xy 423.921428 -286.81934) (xy 425.058332 -286.81934)
			)
		)
	)
	(zone
		(layer "In4.Cu")
		(hatch none 0.5)
		(connect_pads
			(clearance 0)
		)
		(min_thickness 0.25)
		(keepout
			(tracks allowed)
			(vias allowed)
			(pads allowed)
			(copperpour allowed)
			(footprints allowed)
		)
		(placement
			(enabled no)
			(sheetname "")
		)
		(fill
			(thermal_gap 0.5)
			(thermal_bridge_width 0.5)
			(island_removal_mode 0)
		)
		(polygon
			(pts
				(xy 27.09164 -125.956568) (xy 27.09164 -124.788168) (xy 28.23718 -124.788168) (xy 28.23718 -125.956568)
			)
		)
	)
	(zone
		(layer "In4.Cu")
		(hatch none 0.5)
		(connect_pads
			(clearance 0)
		)
		(min_thickness 0.25)
		(keepout
			(tracks allowed)
			(vias allowed)
			(pads allowed)
			(copperpour allowed)
			(footprints allowed)
		)
		(placement
			(enabled no)
			(sheetname "")
		)
		(fill
			(thermal_gap 0.5)
			(thermal_bridge_width 0.5)
			(island_removal_mode 0)
		)
		(polygon
			(pts
				(xy 283.66593 -295.570656) (xy 283.66593 -294.21582) (xy 284.143196 -294.21582) (xy 284.143196 -295.570656)
			)
		)
	)
	(zone
		(layer "In4.Cu")
		(hatch none 0.5)
		(connect_pads
			(clearance 0)
		)
		(min_thickness 0.25)
		(keepout
			(tracks allowed)
			(vias allowed)
			(pads allowed)
			(copperpour allowed)
			(footprints allowed)
		)
		(placement
			(enabled no)
			(sheetname "")
		)
		(fill
			(thermal_gap 0.5)
			(thermal_bridge_width 0.5)
			(island_removal_mode 0)
		)
		(polygon
			(pts
				(xy 50.845974 -308.145434) (xy 50.845974 -306.790598) (xy 51.32324 -306.790598) (xy 51.32324 -308.145434)
			)
		)
	)
	(zone
		(layer "In4.Cu")
		(hatch none 0.5)
		(connect_pads
			(clearance 0)
		)
		(min_thickness 0.25)
		(keepout
			(tracks allowed)
			(vias allowed)
			(pads allowed)
			(copperpour allowed)
			(footprints allowed)
		)
		(placement
			(enabled no)
			(sheetname "")
		)
		(fill
			(thermal_gap 0.5)
			(thermal_bridge_width 0.5)
			(island_removal_mode 0)
		)
		(polygon
			(pts
				(xy 435.568598 -246.007382) (xy 435.568598 -244.652546) (xy 436.045864 -244.652546) (xy 436.045864 -246.007382)
			)
		)
	)
	(zone
		(layer "In4.Cu")
		(hatch none 0.5)
		(connect_pads
			(clearance 0)
		)
		(min_thickness 0.25)
		(keepout
			(tracks allowed)
			(vias allowed)
			(pads allowed)
			(copperpour allowed)
			(footprints allowed)
		)
		(placement
			(enabled no)
			(sheetname "")
		)
		(fill
			(thermal_gap 0.5)
			(thermal_bridge_width 0.5)
			(island_removal_mode 0)
		)
		(polygon
			(pts
				(xy 187.62853 -233.257598) (xy 187.62853 -231.902762) (xy 188.105796 -231.902762) (xy 188.105796 -233.257598)
			)
		)
	)
	(zone
		(layer "In4.Cu")
		(hatch none 0.5)
		(connect_pads
			(clearance 0)
		)
		(min_thickness 0.25)
		(keepout
			(tracks allowed)
			(vias allowed)
			(pads allowed)
			(copperpour allowed)
			(footprints allowed)
		)
		(placement
			(enabled no)
			(sheetname "")
		)
		(fill
			(thermal_gap 0.5)
			(thermal_bridge_width 0.5)
			(island_removal_mode 0)
		)
		(polygon
			(pts
				(xy 435.568598 -293.62908) (xy 435.568598 -291.40277) (xy 436.045864 -291.40277) (xy 436.045864 -293.62908)
			)
		)
	)
	(zone
		(layer "In4.Cu")
		(hatch none 0.5)
		(connect_pads
			(clearance 0)
		)
		(min_thickness 0.25)
		(keepout
			(tracks allowed)
			(vias allowed)
			(pads allowed)
			(copperpour allowed)
			(footprints allowed)
		)
		(placement
			(enabled no)
			(sheetname "")
		)
		(fill
			(thermal_gap 0.5)
			(thermal_bridge_width 0.5)
			(island_removal_mode 0)
		)
		(polygon
			(pts
				(xy 298.77893 -195.842636) (xy 298.77893 -194.4878) (xy 299.256196 -194.4878) (xy 299.256196 -195.842636)
			)
		)
	)
	(zone
		(layer "In4.Cu")
		(hatch none 0.5)
		(connect_pads
			(clearance 0)
		)
		(min_thickness 0.25)
		(keepout
			(tracks allowed)
			(vias allowed)
			(pads allowed)
			(copperpour allowed)
			(footprints allowed)
		)
		(placement
			(enabled no)
			(sheetname "")
		)
		(fill
			(thermal_gap 0.5)
			(thermal_bridge_width 0.5)
			(island_removal_mode 0)
		)
		(polygon
			(pts
				(xy 414.93948 -366.875568) (xy 414.93948 -365.592868) (xy 416.36442 -365.592868) (xy 416.36442 -366.875568)
			)
		)
	)
	(zone
		(layer "In4.Cu")
		(hatch none 0.5)
		(connect_pads
			(clearance 0)
		)
		(min_thickness 0.25)
		(keepout
			(tracks allowed)
			(vias allowed)
			(pads allowed)
			(copperpour allowed)
			(footprints allowed)
		)
		(placement
			(enabled no)
			(sheetname "")
		)
		(fill
			(thermal_gap 0.5)
			(thermal_bridge_width 0.5)
			(island_removal_mode 0)
		)
		(polygon
			(pts
				(xy 61.767212 -307.169058) (xy 61.767212 -305.749198) (xy 62.254892 -305.749198) (xy 62.254892 -307.169058)
			)
		)
	)
	(zone
		(layer "In4.Cu")
		(hatch none 0.5)
		(connect_pads
			(clearance 0)
		)
		(min_thickness 0.25)
		(keepout
			(tracks allowed)
			(vias allowed)
			(pads allowed)
			(copperpour allowed)
			(footprints allowed)
		)
		(placement
			(enabled no)
			(sheetname "")
		)
		(fill
			(thermal_gap 0.5)
			(thermal_bridge_width 0.5)
			(island_removal_mode 0)
		)
		(polygon
			(pts
				(xy 283.652722 -206.072994) (xy 283.652722 -204.718158) (xy 284.129988 -204.718158) (xy 284.129988 -206.072994)
			)
		)
	)
	(zone
		(layer "In4.Cu")
		(hatch none 0.5)
		(connect_pads
			(clearance 0)
		)
		(min_thickness 0.25)
		(keepout
			(tracks allowed)
			(vias allowed)
			(pads allowed)
			(copperpour allowed)
			(footprints allowed)
		)
		(placement
			(enabled no)
			(sheetname "")
		)
		(fill
			(thermal_gap 0.5)
			(thermal_bridge_width 0.5)
			(island_removal_mode 0)
		)
		(polygon
			(pts
				(xy 187.648342 -241.751612) (xy 187.648342 -240.396776) (xy 188.125608 -240.396776) (xy 188.125608 -241.751612)
			)
		)
	)
	(zone
		(layer "In4.Cu")
		(hatch none 0.5)
		(connect_pads
			(clearance 0)
		)
		(min_thickness 0.25)
		(keepout
			(tracks allowed)
			(vias allowed)
			(pads allowed)
			(copperpour allowed)
			(footprints allowed)
		)
		(placement
			(enabled no)
			(sheetname "")
		)
		(fill
			(thermal_gap 0.5)
			(thermal_bridge_width 0.5)
			(island_removal_mode 0)
		)
		(polygon
			(pts
				(xy 35.712654 -206.072994) (xy 35.712654 -204.718158) (xy 36.18992 -204.718158) (xy 36.18992 -206.072994)
			)
		)
	)
	(zone
		(layer "In4.Cu")
		(hatch none 0.5)
		(connect_pads
			(clearance 0)
		)
		(min_thickness 0.25)
		(keepout
			(tracks allowed)
			(vias allowed)
			(pads allowed)
			(copperpour allowed)
			(footprints allowed)
		)
		(placement
			(enabled no)
			(sheetname "")
		)
		(fill
			(thermal_gap 0.5)
			(thermal_bridge_width 0.5)
			(island_removal_mode 0)
		)
		(polygon
			(pts
				(xy 35.703002 -264.691876) (xy 35.703002 -263.33704) (xy 36.180268 -263.33704) (xy 36.180268 -264.691876)
			)
		)
	)
	(zone
		(layer "In4.Cu")
		(hatch none 0.5)
		(connect_pads
			(clearance 0)
		)
		(min_thickness 0.25)
		(keepout
			(tracks allowed)
			(vias allowed)
			(pads allowed)
			(copperpour allowed)
			(footprints allowed)
		)
		(placement
			(enabled no)
			(sheetname "")
		)
		(fill
			(thermal_gap 0.5)
			(thermal_bridge_width 0.5)
			(island_removal_mode 0)
		)
		(polygon
			(pts
				(xy 69.58076 -12.66444) (xy 69.58076 -11.37412) (xy 73.04532 -11.37412) (xy 73.04532 -12.66444)
			)
		)
	)
	(zone
		(layer "In4.Cu")
		(hatch none 0.5)
		(connect_pads
			(clearance 0)
		)
		(min_thickness 0.25)
		(keepout
			(tracks allowed)
			(vias allowed)
			(pads allowed)
			(copperpour allowed)
			(footprints allowed)
		)
		(placement
			(enabled no)
			(sheetname "")
		)
		(fill
			(thermal_gap 0.5)
			(thermal_bridge_width 0.5)
			(island_removal_mode 0)
		)
		(polygon
			(pts
				(xy 130.85826 -11.176) (xy 130.85826 -8.85698) (xy 132.22224 -8.85698) (xy 132.22224 -11.176)
			)
		)
	)
	(zone
		(layer "In4.Cu")
		(hatch none 0.5)
		(connect_pads
			(clearance 0)
		)
		(min_thickness 0.25)
		(keepout
			(tracks allowed)
			(vias allowed)
			(pads allowed)
			(copperpour allowed)
			(footprints allowed)
		)
		(placement
			(enabled no)
			(sheetname "")
		)
		(fill
			(thermal_gap 0.5)
			(thermal_bridge_width 0.5)
			(island_removal_mode 0)
		)
		(polygon
			(pts
				(xy 298.75607 -200.983596) (xy 298.75607 -199.62876) (xy 299.233336 -199.62876) (xy 299.233336 -200.983596)
				(xy 299.233336 -201.884534) (xy 298.75607 -201.884534)
			)
		)
	)
	(zone
		(layer "In4.Cu")
		(hatch none 0.5)
		(connect_pads
			(clearance 0)
		)
		(min_thickness 0.25)
		(keepout
			(tracks allowed)
			(vias allowed)
			(pads allowed)
			(copperpour allowed)
			(footprints allowed)
		)
		(placement
			(enabled no)
			(sheetname "")
		)
		(fill
			(thermal_gap 0.5)
			(thermal_bridge_width 0.5)
			(island_removal_mode 0)
		)
		(polygon
			(pts
				(xy 296.12082 -367.685828) (xy 296.12082 -366.001808) (xy 298.77766 -366.001808) (xy 298.77766 -367.685828)
			)
		)
	)
	(zone
		(layer "In4.Cu")
		(hatch none 0.5)
		(connect_pads
			(clearance 0)
		)
		(min_thickness 0.25)
		(keepout
			(tracks allowed)
			(vias allowed)
			(pads allowed)
			(copperpour allowed)
			(footprints allowed)
		)
		(placement
			(enabled no)
			(sheetname "")
		)
		(fill
			(thermal_gap 0.5)
			(thermal_bridge_width 0.5)
			(island_removal_mode 0)
		)
		(polygon
			(pts
				(xy 405.367998 -305.50739) (xy 405.367998 -304.152554) (xy 405.367998 -303.426368) (xy 405.845264 -303.426368)
				(xy 405.845264 -304.152554) (xy 405.845264 -305.50739)
			)
		)
	)
	(zone
		(layer "In4.Cu")
		(hatch none 0.5)
		(connect_pads
			(clearance 0)
		)
		(min_thickness 0.25)
		(keepout
			(tracks allowed)
			(vias allowed)
			(pads allowed)
			(copperpour allowed)
			(footprints allowed)
		)
		(placement
			(enabled no)
			(sheetname "")
		)
		(fill
			(thermal_gap 0.5)
			(thermal_bridge_width 0.5)
			(island_removal_mode 0)
		)
		(polygon
			(pts
				(xy 35.713162 -315.994796) (xy 35.713162 -314.63996) (xy 36.190428 -314.63996) (xy 36.190428 -315.994796)
			)
		)
	)
	(zone
		(layer "In4.Cu")
		(hatch none 0.5)
		(connect_pads
			(clearance 0)
		)
		(min_thickness 0.25)
		(keepout
			(tracks allowed)
			(vias allowed)
			(pads allowed)
			(copperpour allowed)
			(footprints allowed)
		)
		(placement
			(enabled no)
			(sheetname "")
		)
		(fill
			(thermal_gap 0.5)
			(thermal_bridge_width 0.5)
			(island_removal_mode 0)
		)
		(polygon
			(pts
				(xy 187.62853 -269.80642) (xy 187.62853 -268.930882) (xy 187.204858 -268.930882) (xy 187.204858 -267.602716)
				(xy 187.62853 -267.602716) (xy 188.105796 -267.602716) (xy 188.105796 -269.80642)
			)
		)
	)
	(zone
		(layer "In4.Cu")
		(hatch none 0.5)
		(connect_pads
			(clearance 0)
		)
		(min_thickness 0.25)
		(keepout
			(tracks allowed)
			(vias allowed)
			(pads allowed)
			(copperpour allowed)
			(footprints allowed)
		)
		(placement
			(enabled no)
			(sheetname "")
		)
		(fill
			(thermal_gap 0.5)
			(thermal_bridge_width 0.5)
			(island_removal_mode 0)
		)
		(polygon
			(pts
				(xy 298.70273 -197.582536) (xy 298.70273 -196.2277) (xy 299.179996 -196.2277) (xy 299.179996 -197.582536)
			)
		)
	)
	(zone
		(layer "In4.Cu")
		(hatch none 0.5)
		(connect_pads
			(clearance 0)
		)
		(min_thickness 0.25)
		(keepout
			(tracks allowed)
			(vias allowed)
			(pads allowed)
			(copperpour allowed)
			(footprints allowed)
		)
		(placement
			(enabled no)
			(sheetname "")
		)
		(fill
			(thermal_gap 0.5)
			(thermal_bridge_width 0.5)
			(island_removal_mode 0)
		)
		(polygon
			(pts
				(xy 176.643284 -319.161922) (xy 176.643284 -317.807086) (xy 177.12055 -317.807086) (xy 177.12055 -319.161922)
			)
		)
	)
	(zone
		(layer "In4.Cu")
		(hatch none 0.5)
		(connect_pads
			(clearance 0)
		)
		(min_thickness 0.25)
		(keepout
			(tracks allowed)
			(vias allowed)
			(pads allowed)
			(copperpour allowed)
			(footprints allowed)
		)
		(placement
			(enabled no)
			(sheetname "")
		)
		(fill
			(thermal_gap 0.5)
			(thermal_bridge_width 0.5)
			(island_removal_mode 0)
		)
		(polygon
			(pts
				(xy 35.708082 -266.444476) (xy 35.708082 -265.08964) (xy 36.185348 -265.08964) (xy 36.185348 -266.444476)
			)
		)
	)
	(zone
		(layer "In4.Cu")
		(hatch none 0.5)
		(connect_pads
			(clearance 0)
		)
		(min_thickness 0.25)
		(keepout
			(tracks allowed)
			(vias allowed)
			(pads allowed)
			(copperpour allowed)
			(footprints allowed)
		)
		(placement
			(enabled no)
			(sheetname "")
		)
		(fill
			(thermal_gap 0.5)
			(thermal_bridge_width 0.5)
			(island_removal_mode 0)
		)
		(polygon
			(pts
				(xy 298.796202 -229.011734) (xy 298.796202 -227.656898) (xy 299.273468 -227.656898) (xy 299.273468 -229.011734)
				(xy 299.273468 -231.929432) (xy 298.796202 -231.929432)
			)
		)
	)
	(zone
		(layer "In4.Cu")
		(hatch none 0.5)
		(connect_pads
			(clearance 0)
		)
		(min_thickness 0.25)
		(keepout
			(tracks allowed)
			(vias allowed)
			(pads allowed)
			(copperpour allowed)
			(footprints allowed)
		)
		(placement
			(enabled no)
			(sheetname "")
		)
		(fill
			(thermal_gap 0.5)
			(thermal_bridge_width 0.5)
			(island_removal_mode 0)
		)
		(polygon
			(pts
				(xy 50.816002 -224.742756) (xy 50.816002 -223.38792) (xy 51.293268 -223.38792) (xy 51.293268 -224.742756)
			)
		)
	)
	(zone
		(layer "In4.Cu")
		(hatch none 0.5)
		(connect_pads
			(clearance 0)
		)
		(min_thickness 0.25)
		(keepout
			(tracks allowed)
			(vias allowed)
			(pads allowed)
			(copperpour allowed)
			(footprints allowed)
		)
		(placement
			(enabled no)
			(sheetname "")
		)
		(fill
			(thermal_gap 0.5)
			(thermal_bridge_width 0.5)
			(island_removal_mode 0)
		)
		(polygon
			(pts
				(xy 41.060624 -319.10782) (xy 41.060624 -317.752984) (xy 41.53789 -317.752984) (xy 41.53789 -319.10782)
			)
		)
	)
	(zone
		(layer "In4.Cu")
		(hatch none 0.5)
		(connect_pads
			(clearance 0)
		)
		(min_thickness 0.25)
		(keepout
			(tracks allowed)
			(vias allowed)
			(pads allowed)
			(copperpour allowed)
			(footprints allowed)
		)
		(placement
			(enabled no)
			(sheetname "")
		)
		(fill
			(thermal_gap 0.5)
			(thermal_bridge_width 0.5)
			(island_removal_mode 0)
		)
		(polygon
			(pts
				(xy 283.67355 -214.567516) (xy 283.67355 -213.21268) (xy 284.150816 -213.21268) (xy 284.150816 -214.567516)
			)
		)
	)
	(zone
		(layer "In4.Cu")
		(hatch none 0.5)
		(connect_pads
			(clearance 0)
		)
		(min_thickness 0.25)
		(keepout
			(tracks allowed)
			(vias allowed)
			(pads allowed)
			(copperpour allowed)
			(footprints allowed)
		)
		(placement
			(enabled no)
			(sheetname "")
		)
		(fill
			(thermal_gap 0.5)
			(thermal_bridge_width 0.5)
			(island_removal_mode 0)
		)
		(polygon
			(pts
				(xy 420.50081 -285.951676) (xy 420.50081 -284.59684) (xy 420.978076 -284.59684) (xy 420.978076 -285.951676)
			)
		)
	)
	(zone
		(layer "In4.Cu")
		(hatch none 0.5)
		(connect_pads
			(clearance 0)
		)
		(min_thickness 0.25)
		(keepout
			(tracks allowed)
			(vias allowed)
			(pads allowed)
			(copperpour allowed)
			(footprints allowed)
		)
		(placement
			(enabled no)
			(sheetname "")
		)
		(fill
			(thermal_gap 0.5)
			(thermal_bridge_width 0.5)
			(island_removal_mode 0)
		)
		(polygon
			(pts
				(xy 283.667962 -235.813854) (xy 283.667962 -234.459018) (xy 284.145228 -234.459018) (xy 284.145228 -235.813854)
			)
		)
	)
	(zone
		(layer "In4.Cu")
		(hatch none 0.5)
		(connect_pads
			(clearance 0)
		)
		(min_thickness 0.25)
		(keepout
			(tracks allowed)
			(vias allowed)
			(pads allowed)
			(copperpour allowed)
			(footprints allowed)
		)
		(placement
			(enabled no)
			(sheetname "")
		)
		(fill
			(thermal_gap 0.5)
			(thermal_bridge_width 0.5)
			(island_removal_mode 0)
		)
		(polygon
			(pts
				(xy 172.54093 -281.70759) (xy 172.54093 -280.352754) (xy 173.018196 -280.352754) (xy 173.018196 -281.70759)
			)
		)
	)
	(zone
		(layer "In4.Cu")
		(hatch none 0.5)
		(connect_pads
			(clearance 0)
		)
		(min_thickness 0.25)
		(keepout
			(tracks allowed)
			(vias allowed)
			(pads allowed)
			(copperpour allowed)
			(footprints allowed)
		)
		(placement
			(enabled no)
			(sheetname "")
		)
		(fill
			(thermal_gap 0.5)
			(thermal_bridge_width 0.5)
			(island_removal_mode 0)
		)
		(polygon
			(pts
				(xy 298.77893 -305.242976) (xy 298.77893 -303.88814) (xy 299.256196 -303.88814) (xy 299.256196 -305.242976)
			)
		)
	)
	(zone
		(layer "In4.Cu")
		(hatch none 0.5)
		(connect_pads
			(clearance 0)
		)
		(min_thickness 0.25)
		(keepout
			(tracks allowed)
			(vias allowed)
			(pads allowed)
			(copperpour allowed)
			(footprints allowed)
		)
		(placement
			(enabled no)
			(sheetname "")
		)
		(fill
			(thermal_gap 0.5)
			(thermal_bridge_width 0.5)
			(island_removal_mode 0)
		)
		(polygon
			(pts
				(xy 13.94206 -18.74012) (xy 13.94206 -15.85214) (xy 17.25422 -15.85214) (xy 17.25422 -18.74012)
			)
		)
	)
	(zone
		(layer "In4.Cu")
		(hatch none 0.5)
		(connect_pads
			(clearance 0)
		)
		(min_thickness 0.25)
		(keepout
			(tracks allowed)
			(vias allowed)
			(pads allowed)
			(copperpour allowed)
			(footprints allowed)
		)
		(placement
			(enabled no)
			(sheetname "")
		)
		(fill
			(thermal_gap 0.5)
			(thermal_bridge_width 0.5)
			(island_removal_mode 0)
		)
		(polygon
			(pts
				(xy 50.845974 -226.423474) (xy 50.845974 -225.068638) (xy 51.32324 -225.068638) (xy 51.32324 -226.423474)
			)
		)
	)
	(zone
		(layer "In4.Cu")
		(hatch none 0.5)
		(connect_pads
			(clearance 0)
		)
		(min_thickness 0.25)
		(keepout
			(tracks allowed)
			(vias allowed)
			(pads allowed)
			(copperpour allowed)
			(footprints allowed)
		)
		(placement
			(enabled no)
			(sheetname "")
		)
		(fill
			(thermal_gap 0.5)
			(thermal_bridge_width 0.5)
			(island_removal_mode 0)
		)
		(polygon
			(pts
				(xy 435.58841 -289.35172) (xy 435.58841 -287.996884) (xy 436.065676 -287.996884) (xy 436.065676 -289.35172)
			)
		)
	)
	(zone
		(layer "In4.Cu")
		(hatch none 0.5)
		(connect_pads
			(clearance 0)
		)
		(min_thickness 0.25)
		(keepout
			(tracks allowed)
			(vias allowed)
			(pads allowed)
			(copperpour allowed)
			(footprints allowed)
		)
		(placement
			(enabled no)
			(sheetname "")
		)
		(fill
			(thermal_gap 0.5)
			(thermal_bridge_width 0.5)
			(island_removal_mode 0)
		)
		(polygon
			(pts
				(xy 172.560742 -287.651698) (xy 172.560742 -286.296862) (xy 173.038008 -286.296862) (xy 173.038008 -287.651698)
				(xy 173.32579 -287.651698) (xy 173.32579 -289.019742) (xy 173.037754 -289.019742) (xy 172.156374 -289.019742)
				(xy 172.156374 -287.651698) (xy 172.403262 -287.651698)
			)
		)
	)
	(zone
		(layer "In4.Cu")
		(hatch none 0.5)
		(connect_pads
			(clearance 0)
		)
		(min_thickness 0.25)
		(keepout
			(tracks allowed)
			(vias allowed)
			(pads allowed)
			(copperpour allowed)
			(footprints allowed)
		)
		(placement
			(enabled no)
			(sheetname "")
		)
		(fill
			(thermal_gap 0.5)
			(thermal_bridge_width 0.5)
			(island_removal_mode 0)
		)
		(polygon
			(pts
				(xy 283.66593 -246.030496) (xy 283.66593 -244.67566) (xy 284.143196 -244.67566) (xy 284.143196 -246.030496)
			)
		)
	)
	(zone
		(layer "In4.Cu")
		(hatch none 0.5)
		(connect_pads
			(clearance 0)
		)
		(min_thickness 0.25)
		(keepout
			(tracks allowed)
			(vias allowed)
			(pads allowed)
			(copperpour allowed)
			(footprints allowed)
		)
		(placement
			(enabled no)
			(sheetname "")
		)
		(fill
			(thermal_gap 0.5)
			(thermal_bridge_width 0.5)
			(island_removal_mode 0)
		)
		(polygon
			(pts
				(xy 283.706062 -211.343494) (xy 283.706062 -209.988658) (xy 284.183328 -209.988658) (xy 284.183328 -211.343494)
			)
		)
	)
	(zone
		(layer "In4.Cu")
		(hatch none 0.5)
		(connect_pads
			(clearance 0)
		)
		(min_thickness 0.25)
		(keepout
			(tracks allowed)
			(vias allowed)
			(pads allowed)
			(copperpour allowed)
			(footprints allowed)
		)
		(placement
			(enabled no)
			(sheetname "")
		)
		(fill
			(thermal_gap 0.5)
			(thermal_bridge_width 0.5)
			(island_removal_mode 0)
		)
		(polygon
			(pts
				(xy 35.708082 -240.922556) (xy 35.708082 -239.56772) (xy 36.185348 -239.56772) (xy 36.185348 -240.922556)
			)
		)
	)
	(zone
		(layer "In4.Cu")
		(hatch none 0.5)
		(connect_pads
			(clearance 0)
		)
		(min_thickness 0.25)
		(keepout
			(tracks allowed)
			(vias allowed)
			(pads allowed)
			(copperpour allowed)
			(footprints allowed)
		)
		(placement
			(enabled no)
			(sheetname "")
		)
		(fill
			(thermal_gap 0.5)
			(thermal_bridge_width 0.5)
			(island_removal_mode 0)
		)
		(polygon
			(pts
				(xy 185.41238 -12.8651) (xy 185.41238 -9.9568) (xy 181.65064 -9.9568) (xy 181.65064 -12.8651)
			)
		)
	)
	(zone
		(layer "In4.Cu")
		(hatch none 0.5)
		(connect_pads
			(clearance 0)
		)
		(min_thickness 0.25)
		(keepout
			(tracks allowed)
			(vias allowed)
			(pads allowed)
			(copperpour allowed)
			(footprints allowed)
		)
		(placement
			(enabled no)
			(sheetname "")
		)
		(fill
			(thermal_gap 0.5)
			(thermal_bridge_width 0.5)
			(island_removal_mode 0)
		)
		(polygon
			(pts
				(xy 420.480998 -287.65754) (xy 420.480998 -286.302704) (xy 420.958264 -286.302704) (xy 420.958264 -287.65754)
				(xy 421.246046 -287.65754) (xy 421.246046 -289.025584) (xy 420.95801 -289.025584) (xy 420.07663 -289.025584)
				(xy 420.07663 -287.65754) (xy 420.323518 -287.65754)
			)
		)
	)
	(zone
		(layer "In4.Cu")
		(hatch none 0.5)
		(connect_pads
			(clearance 0)
		)
		(min_thickness 0.25)
		(keepout
			(tracks allowed)
			(vias allowed)
			(pads allowed)
			(copperpour allowed)
			(footprints allowed)
		)
		(placement
			(enabled no)
			(sheetname "")
		)
		(fill
			(thermal_gap 0.5)
			(thermal_bridge_width 0.5)
			(island_removal_mode 0)
		)
		(polygon
			(pts
				(xy 298.76623 -308.151276) (xy 298.76623 -306.79644) (xy 299.243496 -306.79644) (xy 299.243496 -308.151276)
			)
		)
	)
	(zone
		(layer "In4.Cu")
		(hatch none 0.5)
		(connect_pads
			(clearance 0)
		)
		(min_thickness 0.25)
		(keepout
			(tracks allowed)
			(vias allowed)
			(pads allowed)
			(copperpour allowed)
			(footprints allowed)
		)
		(placement
			(enabled no)
			(sheetname "")
		)
		(fill
			(thermal_gap 0.5)
			(thermal_bridge_width 0.5)
			(island_removal_mode 0)
		)
		(polygon
			(pts
				(xy 435.558184 -213.70544) (xy 435.558184 -212.350604) (xy 436.03545 -212.350604) (xy 436.03545 -213.70544)
			)
		)
	)
	(zone
		(layer "In4.Cu")
		(hatch none 0.5)
		(connect_pads
			(clearance 0)
		)
		(min_thickness 0.25)
		(keepout
			(tracks allowed)
			(vias allowed)
			(pads allowed)
			(copperpour allowed)
			(footprints allowed)
		)
		(placement
			(enabled no)
			(sheetname "")
		)
		(fill
			(thermal_gap 0.5)
			(thermal_bridge_width 0.5)
			(island_removal_mode 0)
		)
		(polygon
			(pts
				(xy 283.68117 -261.316216) (xy 283.68117 -259.96138) (xy 284.158436 -259.96138) (xy 284.158436 -261.316216)
			)
		)
	)
	(zone
		(layer "In4.Cu")
		(hatch none 0.5)
		(connect_pads
			(clearance 0)
		)
		(min_thickness 0.25)
		(keepout
			(tracks allowed)
			(vias allowed)
			(pads allowed)
			(copperpour allowed)
			(footprints allowed)
		)
		(placement
			(enabled no)
			(sheetname "")
		)
		(fill
			(thermal_gap 0.5)
			(thermal_bridge_width 0.5)
			(island_removal_mode 0)
		)
		(polygon
			(pts
				(xy 298.76623 -280.853896) (xy 298.76623 -279.49906) (xy 299.243496 -279.49906) (xy 299.243496 -280.853896)
			)
		)
	)
	(zone
		(layer "In4.Cu")
		(hatch none 0.5)
		(connect_pads
			(clearance 0)
		)
		(min_thickness 0.25)
		(keepout
			(tracks allowed)
			(vias allowed)
			(pads allowed)
			(copperpour allowed)
			(footprints allowed)
		)
		(placement
			(enabled no)
			(sheetname "")
		)
		(fill
			(thermal_gap 0.5)
			(thermal_bridge_width 0.5)
			(island_removal_mode 0)
		)
		(polygon
			(pts
				(xy 157.447742 -244.301518) (xy 157.447742 -242.946682) (xy 157.925008 -242.946682) (xy 157.925008 -244.301518)
			)
		)
	)
	(zone
		(layer "In4.Cu")
		(hatch none 0.5)
		(connect_pads
			(clearance 0)
		)
		(min_thickness 0.25)
		(keepout
			(tracks allowed)
			(vias allowed)
			(pads allowed)
			(copperpour allowed)
			(footprints allowed)
		)
		(placement
			(enabled no)
			(sheetname "")
		)
		(fill
			(thermal_gap 0.5)
			(thermal_bridge_width 0.5)
			(island_removal_mode 0)
		)
		(polygon
			(pts
				(xy 35.740594 -268.117574) (xy 35.740594 -266.762738) (xy 36.21786 -266.762738) (xy 36.21786 -268.117574)
			)
		)
	)
	(zone
		(layer "In4.Cu")
		(hatch none 0.5)
		(connect_pads
			(clearance 0)
		)
		(min_thickness 0.25)
		(keepout
			(tracks allowed)
			(vias allowed)
			(pads allowed)
			(copperpour allowed)
			(footprints allowed)
		)
		(placement
			(enabled no)
			(sheetname "")
		)
		(fill
			(thermal_gap 0.5)
			(thermal_bridge_width 0.5)
			(island_removal_mode 0)
		)
		(polygon
			(pts
				(xy 172.560742 -243.451634) (xy 172.560742 -242.955318) (xy 172.164756 -242.955318) (xy 172.164756 -242.096798)
				(xy 172.560742 -242.096798) (xy 173.038008 -242.096798) (xy 173.321472 -242.096798) (xy 173.321472 -242.972082)
				(xy 173.038008 -242.972082) (xy 173.038008 -243.451634)
			)
		)
	)
	(zone
		(layer "In4.Cu")
		(hatch none 0.5)
		(connect_pads
			(clearance 0)
		)
		(min_thickness 0.25)
		(keepout
			(tracks allowed)
			(vias allowed)
			(pads allowed)
			(copperpour allowed)
			(footprints allowed)
		)
		(placement
			(enabled no)
			(sheetname "")
		)
		(fill
			(thermal_gap 0.5)
			(thermal_bridge_width 0.5)
			(island_removal_mode 0)
		)
		(polygon
			(pts
				(xy 50.816002 -205.192376) (xy 50.816002 -203.83754) (xy 51.293268 -203.83754) (xy 51.293268 -205.192376)
			)
		)
	)
	(zone
		(layer "In4.Cu")
		(hatch none 0.5)
		(connect_pads
			(clearance 0)
		)
		(min_thickness 0.25)
		(keepout
			(tracks allowed)
			(vias allowed)
			(pads allowed)
			(copperpour allowed)
			(footprints allowed)
		)
		(placement
			(enabled no)
			(sheetname "")
		)
		(fill
			(thermal_gap 0.5)
			(thermal_bridge_width 0.5)
			(island_removal_mode 0)
		)
		(polygon
			(pts
				(xy 328.10704 -57.729628) (xy 328.10704 -39.454328) (xy 345.65082 -39.454328) (xy 345.65082 -57.729628)
			)
		)
	)
	(zone
		(layer "In4.Cu")
		(hatch none 0.5)
		(connect_pads
			(clearance 0)
		)
		(min_thickness 0.25)
		(keepout
			(tracks allowed)
			(vias allowed)
			(pads allowed)
			(copperpour allowed)
			(footprints allowed)
		)
		(placement
			(enabled no)
			(sheetname "")
		)
		(fill
			(thermal_gap 0.5)
			(thermal_bridge_width 0.5)
			(island_removal_mode 0)
		)
		(polygon
			(pts
				(xy 35.720782 -269.439136) (xy 35.720782 -268.0843) (xy 36.198048 -268.0843) (xy 36.198048 -269.439136)
			)
		)
	)
	(zone
		(layer "In4.Cu")
		(hatch none 0.5)
		(connect_pads
			(clearance 0)
		)
		(min_thickness 0.25)
		(keepout
			(tracks allowed)
			(vias allowed)
			(pads allowed)
			(copperpour allowed)
			(footprints allowed)
		)
		(placement
			(enabled no)
			(sheetname "")
		)
		(fill
			(thermal_gap 0.5)
			(thermal_bridge_width 0.5)
			(island_removal_mode 0)
		)
		(polygon
			(pts
				(xy 87.79764 -338.902548) (xy 87.79764 -338.005928) (xy 89.36736 -338.005928) (xy 89.36736 -338.902548)
			)
		)
	)
	(zone
		(layer "In4.Cu")
		(hatch none 0.5)
		(connect_pads
			(clearance 0)
		)
		(min_thickness 0.25)
		(keepout
			(tracks allowed)
			(vias allowed)
			(pads allowed)
			(copperpour allowed)
			(footprints allowed)
		)
		(placement
			(enabled no)
			(sheetname "")
		)
		(fill
			(thermal_gap 0.5)
			(thermal_bridge_width 0.5)
			(island_removal_mode 0)
		)
		(polygon
			(pts
				(xy 191.659764 -268.841982) (xy 191.659764 -267.487146) (xy 192.13703 -267.487146) (xy 192.13703 -268.841982)
			)
		)
	)
	(zone
		(layer "In4.Cu")
		(hatch none 0.5)
		(connect_pads
			(clearance 0)
		)
		(min_thickness 0.25)
		(keepout
			(tracks allowed)
			(vias allowed)
			(pads allowed)
			(copperpour allowed)
			(footprints allowed)
		)
		(placement
			(enabled no)
			(sheetname "")
		)
		(fill
			(thermal_gap 0.5)
			(thermal_bridge_width 0.5)
			(island_removal_mode 0)
		)
		(polygon
			(pts
				(xy 276.142704 -246.001794) (xy 276.142704 -244.646958) (xy 276.61997 -244.646958) (xy 276.61997 -246.001794)
			)
		)
	)
	(zone
		(layer "In4.Cu")
		(hatch none 0.5)
		(connect_pads
			(clearance 0)
		)
		(min_thickness 0.25)
		(keepout
			(tracks allowed)
			(vias allowed)
			(pads allowed)
			(copperpour allowed)
			(footprints allowed)
		)
		(placement
			(enabled no)
			(sheetname "")
		)
		(fill
			(thermal_gap 0.5)
			(thermal_bridge_width 0.5)
			(island_removal_mode 0)
		)
		(polygon
			(pts
				(xy 283.66085 -268.123416) (xy 283.66085 -266.76858) (xy 284.138116 -266.76858) (xy 284.138116 -268.123416)
			)
		)
	)
	(zone
		(layer "In4.Cu")
		(hatch none 0.5)
		(connect_pads
			(clearance 0)
		)
		(min_thickness 0.25)
		(keepout
			(tracks allowed)
			(vias allowed)
			(pads allowed)
			(copperpour allowed)
			(footprints allowed)
		)
		(placement
			(enabled no)
			(sheetname "")
		)
		(fill
			(thermal_gap 0.5)
			(thermal_bridge_width 0.5)
			(island_removal_mode 0)
		)
		(polygon
			(pts
				(xy 435.612032 -312.375042) (xy 435.612032 -311.020206) (xy 436.089298 -311.020206) (xy 436.089298 -312.375042)
			)
		)
	)
	(zone
		(layer "In4.Cu")
		(hatch none 0.5)
		(connect_pads
			(clearance 0)
		)
		(min_thickness 0.25)
		(keepout
			(tracks allowed)
			(vias allowed)
			(pads allowed)
			(copperpour allowed)
			(footprints allowed)
		)
		(placement
			(enabled no)
			(sheetname "")
		)
		(fill
			(thermal_gap 0.5)
			(thermal_bridge_width 0.5)
			(island_removal_mode 0)
		)
		(polygon
			(pts
				(xy 65.917572 -303.823878) (xy 65.917572 -298.251118) (xy 66.367152 -298.251118) (xy 66.367152 -303.823878)
			)
		)
	)
	(zone
		(layer "In4.Cu")
		(hatch none 0.5)
		(connect_pads
			(clearance 0)
		)
		(min_thickness 0.25)
		(keepout
			(tracks allowed)
			(vias allowed)
			(pads allowed)
			(copperpour allowed)
			(footprints allowed)
		)
		(placement
			(enabled no)
			(sheetname "")
		)
		(fill
			(thermal_gap 0.5)
			(thermal_bridge_width 0.5)
			(island_removal_mode 0)
		)
		(polygon
			(pts
				(xy 50.833782 -287.694116) (xy 50.833782 -286.33928) (xy 51.311048 -286.33928) (xy 51.311048 -287.694116)
			)
		)
	)
	(zone
		(layer "In4.Cu")
		(hatch none 0.5)
		(connect_pads
			(clearance 0)
		)
		(min_thickness 0.25)
		(keepout
			(tracks allowed)
			(vias allowed)
			(pads allowed)
			(copperpour allowed)
			(footprints allowed)
		)
		(placement
			(enabled no)
			(sheetname "")
		)
		(fill
			(thermal_gap 0.5)
			(thermal_bridge_width 0.5)
			(island_removal_mode 0)
		)
		(polygon
			(pts
				(xy 172.560742 -285.951676) (xy 172.560742 -284.59684) (xy 173.038008 -284.59684) (xy 173.038008 -285.951676)
			)
		)
	)
	(zone
		(layer "In4.Cu")
		(hatch none 0.5)
		(connect_pads
			(clearance 0)
		)
		(min_thickness 0.25)
		(keepout
			(tracks allowed)
			(vias allowed)
			(pads allowed)
			(copperpour allowed)
			(footprints allowed)
		)
		(placement
			(enabled no)
			(sheetname "")
		)
		(fill
			(thermal_gap 0.5)
			(thermal_bridge_width 0.5)
			(island_removal_mode 0)
		)
		(polygon
			(pts
				(xy 51.980592 -287.636458) (xy 51.980592 -285.439358) (xy 52.587652 -285.439358) (xy 52.587652 -287.636458)
			)
		)
	)
	(zone
		(layer "In4.Cu")
		(hatch none 0.5)
		(connect_pads
			(clearance 0)
		)
		(min_thickness 0.25)
		(keepout
			(tracks allowed)
			(vias allowed)
			(pads allowed)
			(copperpour allowed)
			(footprints allowed)
		)
		(placement
			(enabled no)
			(sheetname "")
		)
		(fill
			(thermal_gap 0.5)
			(thermal_bridge_width 0.5)
			(island_removal_mode 0)
		)
		(polygon
			(pts
				(xy 155.88742 -10.94994) (xy 155.88742 -9.50722) (xy 156.70022 -9.50722) (xy 156.70022 -10.94994)
			)
		)
	)
	(zone
		(layer "In4.Cu")
		(hatch none 0.5)
		(connect_pads
			(clearance 0)
		)
		(min_thickness 0.25)
		(keepout
			(tracks allowed)
			(vias allowed)
			(pads allowed)
			(copperpour allowed)
			(footprints allowed)
		)
		(placement
			(enabled no)
			(sheetname "")
		)
		(fill
			(thermal_gap 0.5)
			(thermal_bridge_width 0.5)
			(island_removal_mode 0)
		)
		(polygon
			(pts
				(xy 187.638436 -308.00802) (xy 187.638436 -306.653184) (xy 188.115702 -306.653184) (xy 188.115702 -308.00802)
			)
		)
	)
	(zone
		(layer "In4.Cu")
		(hatch none 0.5)
		(connect_pads
			(clearance 0)
		)
		(min_thickness 0.25)
		(keepout
			(tracks allowed)
			(vias allowed)
			(pads allowed)
			(copperpour allowed)
			(footprints allowed)
		)
		(placement
			(enabled no)
			(sheetname "")
		)
		(fill
			(thermal_gap 0.5)
			(thermal_bridge_width 0.5)
			(island_removal_mode 0)
		)
		(polygon
			(pts
				(xy 309.798212 -233.165396) (xy 309.798212 -223.343216) (xy 310.275732 -223.343216) (xy 310.275732 -233.165396)
			)
		)
	)
	(zone
		(layer "In4.Cu")
		(hatch none 0.5)
		(connect_pads
			(clearance 0)
		)
		(min_thickness 0.25)
		(keepout
			(tracks allowed)
			(vias allowed)
			(pads allowed)
			(copperpour allowed)
			(footprints allowed)
		)
		(placement
			(enabled no)
			(sheetname "")
		)
		(fill
			(thermal_gap 0.5)
			(thermal_bridge_width 0.5)
			(island_removal_mode 0)
		)
		(polygon
			(pts
				(xy 298.75607 -205.192376) (xy 298.75607 -203.83754) (xy 299.233336 -203.83754) (xy 299.233336 -205.192376)
			)
		)
	)
	(zone
		(layer "In4.Cu")
		(hatch none 0.5)
		(connect_pads
			(clearance 0)
		)
		(min_thickness 0.25)
		(keepout
			(tracks allowed)
			(vias allowed)
			(pads allowed)
			(copperpour allowed)
			(footprints allowed)
		)
		(placement
			(enabled no)
			(sheetname "")
		)
		(fill
			(thermal_gap 0.5)
			(thermal_bridge_width 0.5)
			(island_removal_mode 0)
		)
		(polygon
			(pts
				(xy 187.62853 -244.30736) (xy 187.62853 -242.952524) (xy 188.105796 -242.952524) (xy 188.105796 -244.30736)
			)
		)
	)
	(zone
		(layer "In4.Cu")
		(hatch none 0.5)
		(connect_pads
			(clearance 0)
		)
		(min_thickness 0.25)
		(keepout
			(tracks allowed)
			(vias allowed)
			(pads allowed)
			(copperpour allowed)
			(footprints allowed)
		)
		(placement
			(enabled no)
			(sheetname "")
		)
		(fill
			(thermal_gap 0.5)
			(thermal_bridge_width 0.5)
			(island_removal_mode 0)
		)
		(polygon
			(pts
				(xy 50.858674 -288.473134) (xy 50.858674 -287.118298) (xy 51.33594 -287.118298) (xy 51.33594 -288.473134)
			)
		)
	)
	(zone
		(layer "In4.Cu")
		(hatch none 0.5)
		(connect_pads
			(clearance 0)
		)
		(min_thickness 0.25)
		(keepout
			(tracks allowed)
			(vias allowed)
			(pads allowed)
			(copperpour allowed)
			(footprints allowed)
		)
		(placement
			(enabled no)
			(sheetname "")
		)
		(fill
			(thermal_gap 0.5)
			(thermal_bridge_width 0.5)
			(island_removal_mode 0)
		)
		(polygon
			(pts
				(xy 220.27134 -18.72234) (xy 220.27134 -17.97304) (xy 221.6531 -17.97304) (xy 221.6531 -18.72234)
			)
		)
	)
	(zone
		(layer "In4.Cu")
		(hatch none 0.5)
		(connect_pads
			(clearance 0)
		)
		(min_thickness 0.25)
		(keepout
			(tracks allowed)
			(vias allowed)
			(pads allowed)
			(copperpour allowed)
			(footprints allowed)
		)
		(placement
			(enabled no)
			(sheetname "")
		)
		(fill
			(thermal_gap 0.5)
			(thermal_bridge_width 0.5)
			(island_removal_mode 0)
		)
		(polygon
			(pts
				(xy 48.678592 -261.258558) (xy 48.678592 -258.304538) (xy 49.034192 -258.304538) (xy 49.034192 -261.258558)
			)
		)
	)
	(zone
		(layer "In4.Cu")
		(hatch none 0.5)
		(connect_pads
			(clearance 0)
		)
		(min_thickness 0.25)
		(keepout
			(tracks allowed)
			(vias allowed)
			(pads allowed)
			(copperpour allowed)
			(footprints allowed)
		)
		(placement
			(enabled no)
			(sheetname "")
		)
		(fill
			(thermal_gap 0.5)
			(thermal_bridge_width 0.5)
			(island_removal_mode 0)
		)
		(polygon
			(pts
				(xy 50.838862 -288.478976) (xy 50.838862 -287.12414) (xy 51.316128 -287.12414) (xy 51.316128 -288.478976)
			)
		)
	)
	(zone
		(layer "In4.Cu")
		(hatch none 0.5)
		(connect_pads
			(clearance 0)
		)
		(min_thickness 0.25)
		(keepout
			(tracks allowed)
			(vias allowed)
			(pads allowed)
			(copperpour allowed)
			(footprints allowed)
		)
		(placement
			(enabled no)
			(sheetname "")
		)
		(fill
			(thermal_gap 0.5)
			(thermal_bridge_width 0.5)
			(island_removal_mode 0)
		)
		(polygon
			(pts
				(xy 339.56244 -292.885368) (xy 339.56244 -290.693348) (xy 349.41256 -290.693348) (xy 349.41256 -292.885368)
			)
		)
	)
	(zone
		(layer "In4.Cu")
		(hatch none 0.5)
		(connect_pads
			(clearance 0)
		)
		(min_thickness 0.25)
		(keepout
			(tracks allowed)
			(vias allowed)
			(pads allowed)
			(copperpour allowed)
			(footprints allowed)
		)
		(placement
			(enabled no)
			(sheetname "")
		)
		(fill
			(thermal_gap 0.5)
			(thermal_bridge_width 0.5)
			(island_removal_mode 0)
		)
		(polygon
			(pts
				(xy 372.9609 -341.854028) (xy 372.9609 -335.735168) (xy 381.6223 -335.735168) (xy 381.6223 -341.854028)
			)
		)
	)
	(zone
		(layer "In4.Cu")
		(hatch none 0.5)
		(connect_pads
			(clearance 0)
		)
		(min_thickness 0.25)
		(keepout
			(tracks allowed)
			(vias allowed)
			(pads allowed)
			(copperpour allowed)
			(footprints allowed)
		)
		(placement
			(enabled no)
			(sheetname "")
		)
		(fill
			(thermal_gap 0.5)
			(thermal_bridge_width 0.5)
			(island_removal_mode 0)
		)
		(polygon
			(pts
				(xy 35.732974 -239.334294) (xy 35.732974 -237.979458) (xy 36.21024 -237.979458) (xy 36.21024 -239.334294)
			)
		)
	)
	(zone
		(layer "In4.Cu")
		(hatch none 0.5)
		(connect_pads
			(clearance 0)
		)
		(min_thickness 0.25)
		(keepout
			(tracks allowed)
			(vias allowed)
			(pads allowed)
			(copperpour allowed)
			(footprints allowed)
		)
		(placement
			(enabled no)
			(sheetname "")
		)
		(fill
			(thermal_gap 0.5)
			(thermal_bridge_width 0.5)
			(island_removal_mode 0)
		)
		(polygon
			(pts
				(xy 187.691776 -312.3692) (xy 187.691776 -311.014364) (xy 188.169042 -311.014364) (xy 188.169042 -312.3692)
			)
		)
	)
	(zone
		(layer "In4.Cu")
		(hatch none 0.5)
		(connect_pads
			(clearance 0)
		)
		(min_thickness 0.25)
		(keepout
			(tracks allowed)
			(vias allowed)
			(pads allowed)
			(copperpour allowed)
			(footprints allowed)
		)
		(placement
			(enabled no)
			(sheetname "")
		)
		(fill
			(thermal_gap 0.5)
			(thermal_bridge_width 0.5)
			(island_removal_mode 0)
		)
		(polygon
			(pts
				(xy 435.58841 -240.05159) (xy 435.58841 -238.696754) (xy 436.065676 -238.696754) (xy 436.065676 -240.05159)
			)
		)
	)
	(zone
		(layer "In4.Cu")
		(hatch none 0.5)
		(connect_pads
			(clearance 0)
		)
		(min_thickness 0.25)
		(keepout
			(tracks allowed)
			(vias allowed)
			(pads allowed)
			(copperpour allowed)
			(footprints allowed)
		)
		(placement
			(enabled no)
			(sheetname "")
		)
		(fill
			(thermal_gap 0.5)
			(thermal_bridge_width 0.5)
			(island_removal_mode 0)
		)
		(polygon
			(pts
				(xy 283.700982 -261.310374) (xy 283.700982 -259.955538) (xy 284.178248 -259.955538) (xy 284.178248 -261.310374)
			)
		)
	)
	(zone
		(layer "In4.Cu")
		(hatch none 0.5)
		(connect_pads
			(clearance 0)
		)
		(min_thickness 0.25)
		(keepout
			(tracks allowed)
			(vias allowed)
			(pads allowed)
			(copperpour allowed)
			(footprints allowed)
		)
		(placement
			(enabled no)
			(sheetname "")
		)
		(fill
			(thermal_gap 0.5)
			(thermal_bridge_width 0.5)
			(island_removal_mode 0)
		)
		(polygon
			(pts
				(xy 283.66593 -234.082336) (xy 283.66593 -232.7275) (xy 284.143196 -232.7275) (xy 284.143196 -234.082336)
			)
		)
	)
	(zone
		(layer "In4.Cu")
		(hatch none 0.5)
		(connect_pads
			(clearance 0)
		)
		(min_thickness 0.25)
		(keepout
			(tracks allowed)
			(vias allowed)
			(pads allowed)
			(copperpour allowed)
			(footprints allowed)
		)
		(placement
			(enabled no)
			(sheetname "")
		)
		(fill
			(thermal_gap 0.5)
			(thermal_bridge_width 0.5)
			(island_removal_mode 0)
		)
		(polygon
			(pts
				(xy 28.182824 -246.007636) (xy 28.182824 -244.6528) (xy 28.66009 -244.6528) (xy 28.66009 -246.007636)
			)
		)
	)
	(zone
		(layer "In4.Cu")
		(hatch none 0.5)
		(connect_pads
			(clearance 0)
		)
		(min_thickness 0.25)
		(keepout
			(tracks allowed)
			(vias allowed)
			(pads allowed)
			(copperpour allowed)
			(footprints allowed)
		)
		(placement
			(enabled no)
			(sheetname "")
		)
		(fill
			(thermal_gap 0.5)
			(thermal_bridge_width 0.5)
			(island_removal_mode 0)
		)
		(polygon
			(pts
				(xy 405.385524 -307.65496) (xy 405.385524 -306.300124) (xy 405.86279 -306.300124) (xy 405.86279 -307.65496)
			)
		)
	)
	(zone
		(layer "In4.Cu")
		(hatch none 0.5)
		(connect_pads
			(clearance 0)
		)
		(min_thickness 0.25)
		(keepout
			(tracks allowed)
			(vias allowed)
			(pads allowed)
			(copperpour allowed)
			(footprints allowed)
		)
		(placement
			(enabled no)
			(sheetname "")
		)
		(fill
			(thermal_gap 0.5)
			(thermal_bridge_width 0.5)
			(island_removal_mode 0)
		)
		(polygon
			(pts
				(xy 50.816002 -200.983596) (xy 50.816002 -199.62876) (xy 51.293268 -199.62876) (xy 51.293268 -200.983596)
				(xy 51.293268 -201.884534) (xy 50.816002 -201.884534)
			)
		)
	)
	(zone
		(layer "In4.Cu")
		(hatch none 0.5)
		(connect_pads
			(clearance 0)
		)
		(min_thickness 0.25)
		(keepout
			(tracks allowed)
			(vias allowed)
			(pads allowed)
			(copperpour allowed)
			(footprints allowed)
		)
		(placement
			(enabled no)
			(sheetname "")
		)
		(fill
			(thermal_gap 0.5)
			(thermal_bridge_width 0.5)
			(island_removal_mode 0)
		)
		(polygon
			(pts
				(xy 187.648342 -296.151554) (xy 187.648342 -294.796718) (xy 188.125608 -294.796718) (xy 188.125608 -296.151554)
			)
		)
	)
	(zone
		(layer "In4.Cu")
		(hatch none 0.5)
		(connect_pads
			(clearance 0)
		)
		(min_thickness 0.25)
		(keepout
			(tracks allowed)
			(vias allowed)
			(pads allowed)
			(copperpour allowed)
			(footprints allowed)
		)
		(placement
			(enabled no)
			(sheetname "")
		)
		(fill
			(thermal_gap 0.5)
			(thermal_bridge_width 0.5)
			(island_removal_mode 0)
		)
		(polygon
			(pts
				(xy 39.148512 -245.106698) (xy 39.148512 -242.973098) (xy 39.585392 -242.973098) (xy 39.585392 -245.106698)
			)
		)
	)
	(zone
		(layer "In4.Cu")
		(hatch none 0.5)
		(connect_pads
			(clearance 0)
		)
		(min_thickness 0.25)
		(keepout
			(tracks allowed)
			(vias allowed)
			(pads allowed)
			(copperpour allowed)
			(footprints allowed)
		)
		(placement
			(enabled no)
			(sheetname "")
		)
		(fill
			(thermal_gap 0.5)
			(thermal_bridge_width 0.5)
			(island_removal_mode 0)
		)
		(polygon
			(pts
				(xy 48.624236 -319.951862) (xy 48.624236 -318.597026) (xy 49.101502 -318.597026) (xy 49.101502 -319.951862)
			)
		)
	)
	(zone
		(layer "In4.Cu")
		(hatch none 0.5)
		(connect_pads
			(clearance 0)
		)
		(min_thickness 0.25)
		(keepout
			(tracks allowed)
			(vias allowed)
			(pads allowed)
			(copperpour allowed)
			(footprints allowed)
		)
		(placement
			(enabled no)
			(sheetname "")
		)
		(fill
			(thermal_gap 0.5)
			(thermal_bridge_width 0.5)
			(island_removal_mode 0)
		)
		(polygon
			(pts
				(xy 435.58841 -205.20152) (xy 435.58841 -203.846684) (xy 436.065676 -203.846684) (xy 436.065676 -205.20152)
			)
		)
	)
	(zone
		(layer "In4.Cu")
		(hatch none 0.5)
		(connect_pads
			(clearance 0)
		)
		(min_thickness 0.25)
		(keepout
			(tracks allowed)
			(vias allowed)
			(pads allowed)
			(copperpour allowed)
			(footprints allowed)
		)
		(placement
			(enabled no)
			(sheetname "")
		)
		(fill
			(thermal_gap 0.5)
			(thermal_bridge_width 0.5)
			(island_removal_mode 0)
		)
		(polygon
			(pts
				(xy 386.679948 -263.529318) (xy 386.679948 -263.399524) (xy 386.735574 -263.343898) (xy 389.545068 -263.343898)
				(xy 389.730234 -263.529064) (xy 390.774682 -264.573512) (xy 390.878314 -264.573512) (xy 390.983978 -264.679176)
				(xy 390.983978 -265.291316) (xy 390.983978 -267.449808) (xy 390.974834 -267.458952) (xy 390.974834 -267.878052)
				(xy 390.941814 -267.911072) (xy 390.941814 -269.214092) (xy 391.294874 -269.567152) (xy 391.294874 -271.040352)
				(xy 391.178034 -271.157192) (xy 390.824974 -271.157192) (xy 387.562852 -267.89507) (xy 387.562852 -267.10386)
				(xy 387.513576 -267.054584) (xy 386.68833 -267.054584) (xy 386.679948 -267.046202)
			)
		)
	)
	(zone
		(layer "In4.Cu")
		(hatch none 0.5)
		(connect_pads
			(clearance 0)
		)
		(min_thickness 0.25)
		(keepout
			(tracks allowed)
			(vias allowed)
			(pads allowed)
			(copperpour allowed)
			(footprints allowed)
		)
		(placement
			(enabled no)
			(sheetname "")
		)
		(fill
			(thermal_gap 0.5)
			(thermal_bridge_width 0.5)
			(island_removal_mode 0)
		)
		(polygon
			(pts
				(xy 420.50081 -281.701748) (xy 420.50081 -280.346912) (xy 420.978076 -280.346912) (xy 420.978076 -281.701748)
			)
		)
	)
	(zone
		(layer "In4.Cu")
		(hatch none 0.5)
		(connect_pads
			(clearance 0)
		)
		(min_thickness 0.25)
		(keepout
			(tracks allowed)
			(vias allowed)
			(pads allowed)
			(copperpour allowed)
			(footprints allowed)
		)
		(placement
			(enabled no)
			(sheetname "")
		)
		(fill
			(thermal_gap 0.5)
			(thermal_bridge_width 0.5)
			(island_removal_mode 0)
		)
		(polygon
			(pts
				(xy 49.911 -358.325928) (xy 49.911 -357.520748) (xy 51.18862 -357.520748) (xy 51.18862 -358.325928)
			)
		)
	)
	(zone
		(layer "In4.Cu")
		(hatch none 0.5)
		(connect_pads
			(clearance 0)
		)
		(min_thickness 0.25)
		(keepout
			(tracks allowed)
			(vias allowed)
			(pads allowed)
			(copperpour allowed)
			(footprints allowed)
		)
		(placement
			(enabled no)
			(sheetname "")
		)
		(fill
			(thermal_gap 0.5)
			(thermal_bridge_width 0.5)
			(island_removal_mode 0)
		)
		(polygon
			(pts
				(xy 56.153304 -244.272816) (xy 56.153304 -242.967256) (xy 56.755284 -242.967256) (xy 56.755284 -244.272816)
			)
		)
	)
	(zone
		(layer "In4.Cu")
		(hatch none 0.5)
		(connect_pads
			(clearance 0)
		)
		(min_thickness 0.25)
		(keepout
			(tracks allowed)
			(vias allowed)
			(pads allowed)
			(copperpour allowed)
			(footprints allowed)
		)
		(placement
			(enabled no)
			(sheetname "")
		)
		(fill
			(thermal_gap 0.5)
			(thermal_bridge_width 0.5)
			(island_removal_mode 0)
		)
		(polygon
			(pts
				(xy 54.269132 -245.066058) (xy 54.269132 -242.909598) (xy 54.807612 -242.909598) (xy 54.807612 -245.066058)
			)
		)
	)
	(zone
		(layer "In4.Cu")
		(hatch none 0.5)
		(connect_pads
			(clearance 0)
		)
		(min_thickness 0.25)
		(keepout
			(tracks allowed)
			(vias allowed)
			(pads allowed)
			(copperpour allowed)
			(footprints allowed)
		)
		(placement
			(enabled no)
			(sheetname "")
		)
		(fill
			(thermal_gap 0.5)
			(thermal_bridge_width 0.5)
			(island_removal_mode 0)
		)
		(polygon
			(pts
				(xy 35.713162 -238.385096) (xy 35.713162 -237.03026) (xy 36.190428 -237.03026) (xy 36.190428 -238.385096)
			)
		)
	)
	(zone
		(layer "In4.Cu")
		(hatch none 0.5)
		(connect_pads
			(clearance 0)
		)
		(min_thickness 0.25)
		(keepout
			(tracks allowed)
			(vias allowed)
			(pads allowed)
			(copperpour allowed)
			(footprints allowed)
		)
		(placement
			(enabled no)
			(sheetname "")
		)
		(fill
			(thermal_gap 0.5)
			(thermal_bridge_width 0.5)
			(island_removal_mode 0)
		)
		(polygon
			(pts
				(xy 35.746182 -211.349336) (xy 35.746182 -209.9945) (xy 36.223448 -209.9945) (xy 36.223448 -211.349336)
			)
		)
	)
	(zone
		(layer "In4.Cu")
		(hatch none 0.5)
		(connect_pads
			(clearance 0)
		)
		(min_thickness 0.25)
		(keepout
			(tracks allowed)
			(vias allowed)
			(pads allowed)
			(copperpour allowed)
			(footprints allowed)
		)
		(placement
			(enabled no)
			(sheetname "")
		)
		(fill
			(thermal_gap 0.5)
			(thermal_bridge_width 0.5)
			(island_removal_mode 0)
		)
		(polygon
			(pts
				(xy 420.50081 -229.851712) (xy 420.50081 -228.496876) (xy 420.978076 -228.496876) (xy 420.978076 -229.851712)
			)
		)
	)
	(zone
		(layer "In4.Cu")
		(hatch none 0.5)
		(connect_pads
			(clearance 0)
		)
		(min_thickness 0.25)
		(keepout
			(tracks allowed)
			(vias allowed)
			(pads allowed)
			(copperpour allowed)
			(footprints allowed)
		)
		(placement
			(enabled no)
			(sheetname "")
		)
		(fill
			(thermal_gap 0.5)
			(thermal_bridge_width 0.5)
			(island_removal_mode 0)
		)
		(polygon
			(pts
				(xy 31.626302 -246.048276) (xy 31.626302 -244.69344) (xy 32.103568 -244.69344) (xy 32.103568 -246.048276)
			)
		)
	)
	(zone
		(layer "In4.Cu")
		(hatch none 0.5)
		(connect_pads
			(clearance 0)
		)
		(min_thickness 0.25)
		(keepout
			(tracks allowed)
			(vias allowed)
			(pads allowed)
			(copperpour allowed)
			(footprints allowed)
		)
		(placement
			(enabled no)
			(sheetname "")
		)
		(fill
			(thermal_gap 0.5)
			(thermal_bridge_width 0.5)
			(island_removal_mode 0)
		)
		(polygon
			(pts
				(xy 45.45838 -244.307868) (xy 45.45838 -241.455448) (xy 48.50638 -241.455448) (xy 48.50638 -244.307868)
			)
		)
	)
	(zone
		(layer "In4.Cu")
		(hatch none 0.5)
		(connect_pads
			(clearance 0)
		)
		(min_thickness 0.25)
		(keepout
			(tracks allowed)
			(vias allowed)
			(pads allowed)
			(copperpour allowed)
			(footprints allowed)
		)
		(placement
			(enabled no)
			(sheetname "")
		)
		(fill
			(thermal_gap 0.5)
			(thermal_bridge_width 0.5)
			(island_removal_mode 0)
		)
		(polygon
			(pts
				(xy 435.568598 -241.757454) (xy 435.568598 -240.402618) (xy 436.045864 -240.402618) (xy 436.045864 -241.757454)
			)
		)
	)
	(zone
		(layer "In4.Cu")
		(hatch none 0.5)
		(connect_pads
			(clearance 0)
		)
		(min_thickness 0.25)
		(keepout
			(tracks allowed)
			(vias allowed)
			(pads allowed)
			(copperpour allowed)
			(footprints allowed)
		)
		(placement
			(enabled no)
			(sheetname "")
		)
		(fill
			(thermal_gap 0.5)
			(thermal_bridge_width 0.5)
			(island_removal_mode 0)
		)
		(polygon
			(pts
				(xy 191.728598 -246.007382) (xy 191.728598 -244.652546) (xy 192.205864 -244.652546) (xy 192.205864 -246.007382)
			)
		)
	)
	(zone
		(layer "In4.Cu")
		(hatch none 0.5)
		(connect_pads
			(clearance 0)
		)
		(min_thickness 0.25)
		(keepout
			(tracks allowed)
			(vias allowed)
			(pads allowed)
			(copperpour allowed)
			(footprints allowed)
		)
		(placement
			(enabled no)
			(sheetname "")
		)
		(fill
			(thermal_gap 0.5)
			(thermal_bridge_width 0.5)
			(island_removal_mode 0)
		)
		(polygon
			(pts
				(xy 172.560742 -228.139498) (xy 172.560742 -225.946716) (xy 173.038008 -225.946716) (xy 173.038008 -228.139498)
			)
		)
	)
	(zone
		(layer "In4.Cu")
		(hatch none 0.5)
		(connect_pads
			(clearance 0)
		)
		(min_thickness 0.25)
		(keepout
			(tracks allowed)
			(vias allowed)
			(pads allowed)
			(copperpour allowed)
			(footprints allowed)
		)
		(placement
			(enabled no)
			(sheetname "")
		)
		(fill
			(thermal_gap 0.5)
			(thermal_bridge_width 0.5)
			(island_removal_mode 0)
		)
		(polygon
			(pts
				(xy 50.826162 -306.632356) (xy 50.826162 -305.27752) (xy 51.303428 -305.27752) (xy 51.303428 -306.632356)
			)
		)
	)
	(zone
		(layer "In4.Cu")
		(hatch none 0.5)
		(connect_pads
			(clearance 0)
		)
		(min_thickness 0.25)
		(keepout
			(tracks allowed)
			(vias allowed)
			(pads allowed)
			(copperpour allowed)
			(footprints allowed)
		)
		(placement
			(enabled no)
			(sheetname "")
		)
		(fill
			(thermal_gap 0.5)
			(thermal_bridge_width 0.5)
			(island_removal_mode 0)
		)
		(polygon
			(pts
				(xy 35.745674 -314.569094) (xy 35.745674 -313.214258) (xy 36.22294 -313.214258) (xy 36.22294 -314.569094)
			)
		)
	)
	(zone
		(layer "In4.Cu")
		(hatch none 0.5)
		(connect_pads
			(clearance 0)
		)
		(min_thickness 0.25)
		(keepout
			(tracks allowed)
			(vias allowed)
			(pads allowed)
			(copperpour allowed)
			(footprints allowed)
		)
		(placement
			(enabled no)
			(sheetname "")
		)
		(fill
			(thermal_gap 0.5)
			(thermal_bridge_width 0.5)
			(island_removal_mode 0)
		)
		(polygon
			(pts
				(xy 102.049326 -352.343212) (xy 107.914186 -352.343212) (xy 109.285786 -353.714812) (xy 112.003586 -353.714812)
				(xy 112.267746 -353.978972) (xy 112.267746 -354.481892) (xy 112.206786 -354.542852) (xy 108.935266 -354.542852)
				(xy 107.601766 -353.209352) (xy 102.326186 -353.209352) (xy 101.363526 -354.172012) (xy 101.363526 -362.719112)
				(xy 103.047546 -364.403132) (xy 104.873806 -364.403132) (xy 106.148886 -365.678212) (xy 106.148886 -366.290352)
				(xy 105.859326 -366.579912) (xy 104.947466 -366.579912) (xy 104.680766 -366.313212) (xy 104.680766 -365.568992)
				(xy 104.248966 -365.137192) (xy 102.615746 -365.137192) (xy 100.522786 -363.044232) (xy 100.522786 -353.869752)
			)
		)
	)
	(zone
		(layer "In4.Cu")
		(hatch none 0.5)
		(connect_pads
			(clearance 0)
		)
		(min_thickness 0.25)
		(keepout
			(tracks allowed)
			(vias allowed)
			(pads allowed)
			(copperpour allowed)
			(footprints allowed)
		)
		(placement
			(enabled no)
			(sheetname "")
		)
		(fill
			(thermal_gap 0.5)
			(thermal_bridge_width 0.5)
			(island_removal_mode 0)
		)
		(polygon
			(pts
				(xy 420.50081 -202.651614) (xy 420.50081 -200.410318) (xy 420.978076 -200.410318) (xy 420.978076 -202.651614)
			)
		)
	)
	(zone
		(layer "In4.Cu")
		(hatch none 0.5)
		(connect_pads
			(clearance 0)
		)
		(min_thickness 0.25)
		(keepout
			(tracks allowed)
			(vias allowed)
			(pads allowed)
			(copperpour allowed)
			(footprints allowed)
		)
		(placement
			(enabled no)
			(sheetname "")
		)
		(fill
			(thermal_gap 0.5)
			(thermal_bridge_width 0.5)
			(island_removal_mode 0)
		)
		(polygon
			(pts
				(xy 298.76623 -306.632356) (xy 298.76623 -305.27752) (xy 299.243496 -305.27752) (xy 299.243496 -306.632356)
			)
		)
	)
	(zone
		(layer "In4.Cu")
		(hatch none 0.5)
		(connect_pads
			(clearance 0)
		)
		(min_thickness 0.25)
		(keepout
			(tracks allowed)
			(vias allowed)
			(pads allowed)
			(copperpour allowed)
			(footprints allowed)
		)
		(placement
			(enabled no)
			(sheetname "")
		)
		(fill
			(thermal_gap 0.5)
			(thermal_bridge_width 0.5)
			(island_removal_mode 0)
		)
		(polygon
			(pts
				(xy 279.56129 -267.285216) (xy 279.56129 -265.93038) (xy 280.038556 -265.93038) (xy 280.038556 -267.285216)
			)
		)
	)
	(zone
		(layer "In4.Cu")
		(hatch none 0.5)
		(connect_pads
			(clearance 0)
		)
		(min_thickness 0.25)
		(keepout
			(tracks allowed)
			(vias allowed)
			(pads allowed)
			(copperpour allowed)
			(footprints allowed)
		)
		(placement
			(enabled no)
			(sheetname "")
		)
		(fill
			(thermal_gap 0.5)
			(thermal_bridge_width 0.5)
			(island_removal_mode 0)
		)
		(polygon
			(pts
				(xy 349.948246 -352.391472) (xy 355.993446 -352.391472) (xy 357.357426 -353.755452) (xy 360.306366 -353.755452)
				(xy 360.486706 -353.935792) (xy 360.486706 -354.486972) (xy 360.435906 -354.537772) (xy 359.993946 -354.537772)
				(xy 359.917746 -354.461572) (xy 357.009446 -354.461572) (xy 355.675946 -353.128072) (xy 350.207326 -353.128072)
				(xy 349.303086 -354.032312) (xy 349.303086 -362.513372) (xy 351.228406 -364.438692) (xy 353.108006 -364.438692)
				(xy 353.651566 -364.982252) (xy 353.651566 -367.105692) (xy 353.966526 -367.420652) (xy 353.966526 -367.636552)
				(xy 353.862386 -367.740692) (xy 352.696526 -367.740692) (xy 352.587306 -367.631472) (xy 352.587306 -367.407952)
				(xy 352.899726 -367.095532) (xy 352.899726 -365.393732) (xy 352.668586 -365.162592) (xy 350.880426 -365.162592)
				(xy 348.579186 -362.861352) (xy 348.579186 -353.760532)
			)
		)
	)
	(zone
		(layer "In4.Cu")
		(hatch none 0.5)
		(connect_pads
			(clearance 0)
		)
		(min_thickness 0.25)
		(keepout
			(tracks allowed)
			(vias allowed)
			(pads allowed)
			(copperpour allowed)
			(footprints allowed)
		)
		(placement
			(enabled no)
			(sheetname "")
		)
		(fill
			(thermal_gap 0.5)
			(thermal_bridge_width 0.5)
			(island_removal_mode 0)
		)
		(polygon
			(pts
				(xy 31.641034 -269.826994) (xy 31.641034 -268.472158) (xy 32.1183 -268.472158) (xy 32.1183 -269.826994)
			)
		)
	)
	(zone
		(layer "In4.Cu")
		(hatch none 0.5)
		(connect_pads
			(clearance 0)
		)
		(min_thickness 0.25)
		(keepout
			(tracks allowed)
			(vias allowed)
			(pads allowed)
			(copperpour allowed)
			(footprints allowed)
		)
		(placement
			(enabled no)
			(sheetname "")
		)
		(fill
			(thermal_gap 0.5)
			(thermal_bridge_width 0.5)
			(island_removal_mode 0)
		)
		(polygon
			(pts
				(xy 187.62853 -263.857486) (xy 187.62853 -262.50265) (xy 188.105796 -262.50265) (xy 188.105796 -263.857486)
			)
		)
	)
	(zone
		(layer "In4.Cu")
		(hatch none 0.5)
		(connect_pads
			(clearance 0)
		)
		(min_thickness 0.25)
		(keepout
			(tracks allowed)
			(vias allowed)
			(pads allowed)
			(copperpour allowed)
			(footprints allowed)
		)
		(placement
			(enabled no)
			(sheetname "")
		)
		(fill
			(thermal_gap 0.5)
			(thermal_bridge_width 0.5)
			(island_removal_mode 0)
		)
		(polygon
			(pts
				(xy 334.831944 -290.964366) (xy 351.659952 -290.964112) (xy 351.658428 -212.967062) (xy 334.016604 -212.967316)
				(xy 333.878174 -213.105746) (xy 333.878428 -219.768674) (xy 333.685134 -219.961968) (xy 330.634594 -219.961968)
				(xy 330.531724 -220.064838) (xy 330.531724 -236.296962) (xy 330.56576 -236.330998) (xy 330.628752 -236.330998)
				(xy 330.778866 -236.330998) (xy 330.827888 -236.38002) (xy 330.827888 -236.480604) (xy 330.827888 -248.44756)
				(xy 330.900532 -248.520204) (xy 330.984606 -248.520204) (xy 332.359 -248.520204) (xy 333.9338 -250.095004)
				(xy 334.15859 -250.095004) (xy 341.941658 -250.095004) (xy 342.824562 -250.977908) (xy 342.824562 -252.907546)
				(xy 339.781134 -252.907546) (xy 339.625178 -252.75159) (xy 332.303882 -252.75159) (xy 332.186026 -252.869446)
				(xy 332.186026 -258.947158) (xy 332.287118 -259.04825) (xy 332.35519 -259.04825) (xy 335.963006 -259.04825)
				(xy 336.344006 -259.42925) (xy 336.344006 -259.73405) (xy 336.471006 -259.86105) (xy 342.389206 -259.86105)
				(xy 342.643206 -259.60705) (xy 342.643206 -259.25145) (xy 343.100406 -258.79425) (xy 343.100406 -258.46405)
				(xy 343.354406 -258.21005) (xy 344.040206 -258.21005) (xy 344.091006 -258.26085) (xy 344.370406 -258.26085)
				(xy 344.472006 -258.15925) (xy 344.751406 -258.15925) (xy 344.853006 -258.26085) (xy 345.284806 -258.260596)
				(xy 345.361006 -258.184396) (xy 345.818206 -258.184396) (xy 345.919806 -258.285996) (xy 346.199206 -258.285996)
				(xy 346.275406 -258.209796) (xy 346.758006 -258.209796) (xy 346.834206 -258.285996) (xy 347.037406 -258.285996)
				(xy 347.342206 -257.981196) (xy 347.342206 -257.701796) (xy 347.748606 -257.295396) (xy 347.748606 -256.888996)
				(xy 348.282006 -256.355596) (xy 348.282006 -255.949196) (xy 348.967806 -255.263396) (xy 349.526606 -255.263396)
				(xy 349.602806 -255.339596) (xy 349.602806 -255.847596) (xy 349.425006 -256.025396) (xy 348.815406 -256.025396)
				(xy 348.586806 -256.253996) (xy 348.586806 -256.711196) (xy 348.409006 -256.888996) (xy 348.256606 -256.888996)
				(xy 348.053406 -257.092196) (xy 348.053406 -257.396996) (xy 347.570806 -257.879596) (xy 347.570806 -258.387596)
				(xy 347.367606 -258.590796) (xy 346.656406 -258.590796) (xy 346.631006 -258.565396) (xy 343.557606 -258.56565)
				(xy 343.329006 -258.79425) (xy 343.329006 -259.14985) (xy 342.897206 -259.58165) (xy 342.897206 -260.03885)
				(xy 342.795606 -260.14045) (xy 342.617806 -260.14045) (xy 342.490806 -260.26745) (xy 342.059006 -260.26745)
				(xy 341.957406 -260.16585) (xy 341.551006 -260.16585) (xy 341.424006 -260.29285) (xy 341.144606 -260.29285)
				(xy 341.017606 -260.16585) (xy 340.712806 -260.16585) (xy 340.636606 -260.24205) (xy 340.179406 -260.24205)
				(xy 340.103206 -260.16585) (xy 339.722206 -260.16585) (xy 339.620606 -260.26745) (xy 339.239606 -260.26745)
				(xy 339.087206 -260.11505) (xy 338.858606 -260.11505) (xy 338.706206 -260.26745) (xy 338.376006 -260.26745)
				(xy 338.299806 -260.19125) (xy 336.318606 -260.19125) (xy 336.013806 -259.88645) (xy 336.013806 -259.58165)
				(xy 335.759806 -259.32765) (xy 335.480406 -259.32765) (xy 335.353406 -259.45465) (xy 334.947006 -259.45465)
				(xy 334.820006 -259.32765) (xy 334.591406 -259.32765) (xy 334.464406 -259.45465) (xy 333.981806 -259.45465)
				(xy 333.854806 -259.32765) (xy 333.651606 -259.32765) (xy 333.499206 -259.48005) (xy 332.991206 -259.48005)
				(xy 332.864206 -259.35305) (xy 332.788006 -259.35305) (xy 332.483206 -259.65785) (xy 332.379828 -259.761228)
				(xy 330.784454 -259.761228) (xy 330.70419 -259.841492) (xy 330.611734 -259.933948) (xy 330.611734 -268.164818)
				(xy 330.666852 -268.219936) (xy 331.191616 -268.219936) (xy 331.290422 -268.318742) (xy 331.290422 -268.952218)
				(xy 331.147674 -269.094966) (xy 331.147674 -271.420336) (xy 331.347318 -271.61998) (xy 331.347318 -271.77746)
				(xy 331.427582 -271.857724) (xy 331.801724 -271.857724) (xy 332.356968 -271.30248) (xy 332.632812 -271.30248)
				(xy 333.034132 -271.7038) (xy 333.034132 -271.739868) (xy 331.724 -273.05) (xy 331.724 -273.137884)
				(xy 332.458822 -273.872706) (xy 332.458822 -273.876516) (xy 331.58684 -274.748498) (xy 331.58684 -276.786848)
				(xy 331.521308 -276.85238) (xy 330.905866 -277.467822) (xy 330.905866 -277.815802) (xy 330.905866 -278.011128)
				(xy 333.03464 -280.139902) (xy 333.03464 -281.538934) (xy 332.026514 -282.54706) (xy 332.026514 -282.64358)
				(xy 332.253336 -282.870402) (xy 332.253336 -282.993846) (xy 332.044294 -283.202888) (xy 332.044294 -283.30144)
				(xy 332.66253 -283.919676) (xy 332.66253 -283.955744) (xy 332.158848 -284.459426) (xy 332.158848 -284.66669)
				(xy 332.698344 -285.206186) (xy 332.698344 -285.28518) (xy 332.498192 -285.485332) (xy 332.498192 -285.66364)
				(xy 333.102458 -286.267906) (xy 333.102458 -286.353504) (xy 332.744826 -286.711136) (xy 332.744826 -287.264348)
				(xy 332.88478 -287.404302) (xy 332.88478 -287.655508) (xy 332.968092 -287.73882) (xy 333.983838 -287.73882)
				(xy 333.983838 -288.620708) (xy 334.109314 -288.620708) (xy 334.633824 -288.620708) (xy 334.633824 -289.235896)
				(xy 334.678274 -289.280346) (xy 334.678528 -290.81095)
			)
		)
	)
	(zone
		(layer "In4.Cu")
		(hatch none 0.5)
		(connect_pads
			(clearance 0)
		)
		(min_thickness 0.25)
		(keepout
			(tracks allowed)
			(vias allowed)
			(pads allowed)
			(copperpour allowed)
			(footprints allowed)
		)
		(placement
			(enabled no)
			(sheetname "")
		)
		(fill
			(thermal_gap 0.5)
			(thermal_bridge_width 0.5)
			(island_removal_mode 0)
		)
		(polygon
			(pts
				(xy 309.727092 -307.163216) (xy 309.727092 -305.743356) (xy 310.214772 -305.743356) (xy 310.214772 -307.163216)
			)
		)
	)
	(zone
		(layer "In4.Cu")
		(hatch none 0.5)
		(connect_pads
			(clearance 0)
		)
		(min_thickness 0.25)
		(keepout
			(tracks allowed)
			(vias allowed)
			(pads allowed)
			(copperpour allowed)
			(footprints allowed)
		)
		(placement
			(enabled no)
			(sheetname "")
		)
		(fill
			(thermal_gap 0.5)
			(thermal_bridge_width 0.5)
			(island_removal_mode 0)
		)
		(polygon
			(pts
				(xy 298.793662 -287.688274) (xy 298.793662 -286.333438) (xy 299.270928 -286.333438) (xy 299.270928 -287.688274)
			)
		)
	)
	(zone
		(layer "In4.Cu")
		(hatch none 0.5)
		(connect_pads
			(clearance 0)
		)
		(min_thickness 0.25)
		(keepout
			(tracks allowed)
			(vias allowed)
			(pads allowed)
			(copperpour allowed)
			(footprints allowed)
		)
		(placement
			(enabled no)
			(sheetname "")
		)
		(fill
			(thermal_gap 0.5)
			(thermal_bridge_width 0.5)
			(island_removal_mode 0)
		)
		(polygon
			(pts
				(xy 172.54093 -231.557576) (xy 172.54093 -230.20274) (xy 173.018196 -230.20274) (xy 173.018196 -231.557576)
				(xy 173.018196 -232.501694) (xy 172.220636 -232.501694) (xy 172.220636 -231.557576)
			)
		)
	)
	(zone
		(layer "In4.Cu")
		(hatch none 0.5)
		(connect_pads
			(clearance 0)
		)
		(min_thickness 0.25)
		(keepout
			(tracks allowed)
			(vias allowed)
			(pads allowed)
			(copperpour allowed)
			(footprints allowed)
		)
		(placement
			(enabled no)
			(sheetname "")
		)
		(fill
			(thermal_gap 0.5)
			(thermal_bridge_width 0.5)
			(island_removal_mode 0)
		)
		(polygon
			(pts
				(xy 420.480998 -284.257496) (xy 420.480998 -282.0924) (xy 420.958264 -282.0924) (xy 420.958264 -284.257496)
			)
		)
	)
	(zone
		(layer "In4.Cu")
		(hatch none 0.5)
		(connect_pads
			(clearance 0)
		)
		(min_thickness 0.25)
		(keepout
			(tracks allowed)
			(vias allowed)
			(pads allowed)
			(copperpour allowed)
			(footprints allowed)
		)
		(placement
			(enabled no)
			(sheetname "")
		)
		(fill
			(thermal_gap 0.5)
			(thermal_bridge_width 0.5)
			(island_removal_mode 0)
		)
		(polygon
			(pts
				(xy 283.65323 -238.385096) (xy 283.65323 -237.03026) (xy 284.130496 -237.03026) (xy 284.130496 -238.385096)
			)
		)
	)
	(zone
		(layer "In4.Cu")
		(hatch none 0.5)
		(connect_pads
			(clearance 0)
		)
		(min_thickness 0.25)
		(keepout
			(tracks allowed)
			(vias allowed)
			(pads allowed)
			(copperpour allowed)
			(footprints allowed)
		)
		(placement
			(enabled no)
			(sheetname "")
		)
		(fill
			(thermal_gap 0.5)
			(thermal_bridge_width 0.5)
			(island_removal_mode 0)
		)
		(polygon
			(pts
				(xy 435.568598 -205.207362) (xy 435.568598 -203.852526) (xy 436.045864 -203.852526) (xy 436.045864 -205.207362)
			)
		)
	)
	(zone
		(layer "In4.Cu")
		(hatch none 0.5)
		(connect_pads
			(clearance 0)
		)
		(min_thickness 0.25)
		(keepout
			(tracks allowed)
			(vias allowed)
			(pads allowed)
			(copperpour allowed)
			(footprints allowed)
		)
		(placement
			(enabled no)
			(sheetname "")
		)
		(fill
			(thermal_gap 0.5)
			(thermal_bridge_width 0.5)
			(island_removal_mode 0)
		)
		(polygon
			(pts
				(xy 390.935464 -271.467834) (xy 392.04646 -271.467834) (xy 392.83386 -272.255234) (xy 389.074914 -276.014434)
				(xy 388.541514 -276.014688) (xy 387.299454 -274.772882) (xy 387.299454 -274.629372) (xy 387.29666 -274.626578)
				(xy 387.29666 -274.157694) (xy 387.48081 -273.973544) (xy 387.48081 -272.657062) (xy 388.636764 -271.501108)
				(xy 388.636764 -271.400524) (xy 388.408672 -271.172432) (xy 388.408672 -271.139666) (xy 388.408672 -271.134586)
				(xy 389.3693 -270.173958) (xy 389.37438 -270.173958) (xy 390.668256 -271.467834)
			)
		)
	)
	(zone
		(layer "In4.Cu")
		(hatch none 0.5)
		(connect_pads
			(clearance 0)
		)
		(min_thickness 0.25)
		(keepout
			(tracks allowed)
			(vias allowed)
			(pads allowed)
			(copperpour allowed)
			(footprints allowed)
		)
		(placement
			(enabled no)
			(sheetname "")
		)
		(fill
			(thermal_gap 0.5)
			(thermal_bridge_width 0.5)
			(island_removal_mode 0)
		)
		(polygon
			(pts
				(xy 35.692842 -206.078836) (xy 35.692842 -204.724) (xy 36.170108 -204.724) (xy 36.170108 -206.078836)
			)
		)
	)
	(zone
		(layer "In4.Cu")
		(hatch none 0.5)
		(connect_pads
			(clearance 0)
		)
		(min_thickness 0.25)
		(keepout
			(tracks allowed)
			(vias allowed)
			(pads allowed)
			(copperpour allowed)
			(footprints allowed)
		)
		(placement
			(enabled no)
			(sheetname "")
		)
		(fill
			(thermal_gap 0.5)
			(thermal_bridge_width 0.5)
			(island_removal_mode 0)
		)
		(polygon
			(pts
				(xy 35.740594 -269.433294) (xy 35.740594 -268.078458) (xy 36.21786 -268.078458) (xy 36.21786 -269.433294)
			)
		)
	)
	(zone
		(layer "In4.Cu")
		(hatch none 0.5)
		(connect_pads
			(clearance 0)
		)
		(min_thickness 0.25)
		(keepout
			(tracks allowed)
			(vias allowed)
			(pads allowed)
			(copperpour allowed)
			(footprints allowed)
		)
		(placement
			(enabled no)
			(sheetname "")
		)
		(fill
			(thermal_gap 0.5)
			(thermal_bridge_width 0.5)
			(island_removal_mode 0)
		)
		(polygon
			(pts
				(xy 294.677592 -318.307212) (xy 294.677592 -316.045596) (xy 295.218612 -316.045596) (xy 295.218612 -318.307212)
			)
		)
	)
	(zone
		(layer "In4.Cu")
		(hatch none 0.5)
		(connect_pads
			(clearance 0)
		)
		(min_thickness 0.25)
		(keepout
			(tracks allowed)
			(vias allowed)
			(pads allowed)
			(copperpour allowed)
			(footprints allowed)
		)
		(placement
			(enabled no)
			(sheetname "")
		)
		(fill
			(thermal_gap 0.5)
			(thermal_bridge_width 0.5)
			(island_removal_mode 0)
		)
		(polygon
			(pts
				(xy 35.76447 -317.250572) (xy 35.76447 -315.999368) (xy 36.389564 -315.999368) (xy 36.389564 -317.250572)
			)
		)
	)
	(zone
		(layer "In4.Cu")
		(hatch none 0.5)
		(connect_pads
			(clearance 0)
		)
		(min_thickness 0.25)
		(keepout
			(tracks allowed)
			(vias allowed)
			(pads allowed)
			(copperpour allowed)
			(footprints allowed)
		)
		(placement
			(enabled no)
			(sheetname "")
		)
		(fill
			(thermal_gap 0.5)
			(thermal_bridge_width 0.5)
			(island_removal_mode 0)
		)
		(polygon
			(pts
				(xy 172.54093 -285.957518) (xy 172.54093 -284.602682) (xy 173.018196 -284.602682) (xy 173.018196 -285.957518)
			)
		)
	)
	(zone
		(layer "In4.Cu")
		(hatch none 0.5)
		(connect_pads
			(clearance 0)
		)
		(min_thickness 0.25)
		(keepout
			(tracks allowed)
			(vias allowed)
			(pads allowed)
			(copperpour allowed)
			(footprints allowed)
		)
		(placement
			(enabled no)
			(sheetname "")
		)
		(fill
			(thermal_gap 0.5)
			(thermal_bridge_width 0.5)
			(island_removal_mode 0)
		)
		(polygon
			(pts
				(xy 191.74841 -268.101572) (xy 191.74841 -266.746736) (xy 192.225676 -266.746736) (xy 192.225676 -268.101572)
			)
		)
	)
	(zone
		(layer "In4.Cu")
		(hatch none 0.5)
		(connect_pads
			(clearance 0)
		)
		(min_thickness 0.25)
		(keepout
			(tracks allowed)
			(vias allowed)
			(pads allowed)
			(copperpour allowed)
			(footprints allowed)
		)
		(placement
			(enabled no)
			(sheetname "")
		)
		(fill
			(thermal_gap 0.5)
			(thermal_bridge_width 0.5)
			(island_removal_mode 0)
		)
		(polygon
			(pts
				(xy 35.746182 -208.603596) (xy 35.746182 -207.24876) (xy 36.223448 -207.24876) (xy 36.223448 -208.603596)
			)
		)
	)
	(zone
		(layer "In4.Cu")
		(hatch none 0.5)
		(connect_pads
			(clearance 0)
		)
		(min_thickness 0.25)
		(keepout
			(tracks allowed)
			(vias allowed)
			(pads allowed)
			(copperpour allowed)
			(footprints allowed)
		)
		(placement
			(enabled no)
			(sheetname "")
		)
		(fill
			(thermal_gap 0.5)
			(thermal_bridge_width 0.5)
			(island_removal_mode 0)
		)
		(polygon
			(pts
				(xy 283.693362 -214.561674) (xy 283.693362 -213.206838) (xy 284.170628 -213.206838) (xy 284.170628 -214.561674)
			)
		)
	)
	(zone
		(layer "In4.Cu")
		(hatch none 0.5)
		(connect_pads
			(clearance 0)
		)
		(min_thickness 0.25)
		(keepout
			(tracks allowed)
			(vias allowed)
			(pads allowed)
			(copperpour allowed)
			(footprints allowed)
		)
		(placement
			(enabled no)
			(sheetname "")
		)
		(fill
			(thermal_gap 0.5)
			(thermal_bridge_width 0.5)
			(island_removal_mode 0)
		)
		(polygon
			(pts
				(xy 435.58841 -296.151554) (xy 435.58841 -294.796718) (xy 436.065676 -294.796718) (xy 436.065676 -296.151554)
			)
		)
	)
	(zone
		(layer "In4.Cu")
		(hatch none 0.5)
		(connect_pads
			(clearance 0)
		)
		(min_thickness 0.25)
		(keepout
			(tracks allowed)
			(vias allowed)
			(pads allowed)
			(copperpour allowed)
			(footprints allowed)
		)
		(placement
			(enabled no)
			(sheetname "")
		)
		(fill
			(thermal_gap 0.5)
			(thermal_bridge_width 0.5)
			(island_removal_mode 0)
		)
		(polygon
			(pts
				(xy 49.29886 -11.05916) (xy 49.29886 -9.94918) (xy 55.55234 -9.94918) (xy 55.55234 -11.05916)
			)
		)
	)
	(zone
		(layer "In4.Cu")
		(hatch none 0.5)
		(connect_pads
			(clearance 0)
		)
		(min_thickness 0.25)
		(keepout
			(tracks allowed)
			(vias allowed)
			(pads allowed)
			(copperpour allowed)
			(footprints allowed)
		)
		(placement
			(enabled no)
			(sheetname "")
		)
		(fill
			(thermal_gap 0.5)
			(thermal_bridge_width 0.5)
			(island_removal_mode 0)
		)
		(polygon
			(pts
				(xy 187.648342 -252.801628) (xy 187.648342 -251.446792) (xy 188.125608 -251.446792) (xy 188.125608 -252.801628)
			)
		)
	)
	(zone
		(layer "In4.Cu")
		(hatch none 0.5)
		(connect_pads
			(clearance 0)
		)
		(min_thickness 0.25)
		(keepout
			(tracks allowed)
			(vias allowed)
			(pads allowed)
			(copperpour allowed)
			(footprints allowed)
		)
		(placement
			(enabled no)
			(sheetname "")
		)
		(fill
			(thermal_gap 0.5)
			(thermal_bridge_width 0.5)
			(island_removal_mode 0)
		)
		(polygon
			(pts
				(xy 50.826162 -226.429316) (xy 50.826162 -225.07448) (xy 51.303428 -225.07448) (xy 51.303428 -226.429316)
			)
		)
	)
	(zone
		(layer "In4.Cu")
		(hatch none 0.5)
		(connect_pads
			(clearance 0)
		)
		(min_thickness 0.25)
		(keepout
			(tracks allowed)
			(vias allowed)
			(pads allowed)
			(copperpour allowed)
			(footprints allowed)
		)
		(placement
			(enabled no)
			(sheetname "")
		)
		(fill
			(thermal_gap 0.5)
			(thermal_bridge_width 0.5)
			(island_removal_mode 0)
		)
		(polygon
			(pts
				(xy 50.853594 -282.557474) (xy 50.853594 -281.202638) (xy 51.33086 -281.202638) (xy 51.33086 -282.557474)
			)
		)
	)
	(zone
		(layer "In4.Cu")
		(hatch none 0.5)
		(connect_pads
			(clearance 0)
		)
		(min_thickness 0.25)
		(keepout
			(tracks allowed)
			(vias allowed)
			(pads allowed)
			(copperpour allowed)
			(footprints allowed)
		)
		(placement
			(enabled no)
			(sheetname "")
		)
		(fill
			(thermal_gap 0.5)
			(thermal_bridge_width 0.5)
			(island_removal_mode 0)
		)
		(polygon
			(pts
				(xy 35.745674 -246.024654) (xy 35.745674 -244.669818) (xy 36.22294 -244.669818) (xy 36.22294 -246.024654)
			)
		)
	)
	(zone
		(layer "In4.Cu")
		(hatch none 0.5)
		(connect_pads
			(clearance 0)
		)
		(min_thickness 0.25)
		(keepout
			(tracks allowed)
			(vias allowed)
			(pads allowed)
			(copperpour allowed)
			(footprints allowed)
		)
		(placement
			(enabled no)
			(sheetname "")
		)
		(fill
			(thermal_gap 0.5)
			(thermal_bridge_width 0.5)
			(island_removal_mode 0)
		)
		(polygon
			(pts
				(xy 172.560742 -225.60153) (xy 172.560742 -224.246694) (xy 173.038008 -224.246694) (xy 173.038008 -225.60153)
			)
		)
	)
	(zone
		(layer "In4.Cu")
		(hatch none 0.5)
		(connect_pads
			(clearance 0)
		)
		(min_thickness 0.25)
		(keepout
			(tracks allowed)
			(vias allowed)
			(pads allowed)
			(copperpour allowed)
			(footprints allowed)
		)
		(placement
			(enabled no)
			(sheetname "")
		)
		(fill
			(thermal_gap 0.5)
			(thermal_bridge_width 0.5)
			(island_removal_mode 0)
		)
		(polygon
			(pts
				(xy 28.471622 -129.854706) (xy 28.471622 -128.800606) (xy 28.69438 -128.577848) (xy 29.18206 -128.577848)
				(xy 29.31668 -128.712468) (xy 29.31668 -130.835908) (xy 28.59532 -131.557268) (xy 27.59202 -131.557268)
				(xy 27.53106 -131.496308) (xy 27.53106 -130.795268)
			)
		)
	)
	(zone
		(layer "In4.Cu")
		(hatch none 0.5)
		(connect_pads
			(clearance 0)
		)
		(min_thickness 0.25)
		(keepout
			(tracks allowed)
			(vias allowed)
			(pads allowed)
			(copperpour allowed)
			(footprints allowed)
		)
		(placement
			(enabled no)
			(sheetname "")
		)
		(fill
			(thermal_gap 0.5)
			(thermal_bridge_width 0.5)
			(island_removal_mode 0)
		)
		(polygon
			(pts
				(xy 187.62853 -249.407426) (xy 187.62853 -248.05259) (xy 188.105796 -248.05259) (xy 188.105796 -249.407426)
			)
		)
	)
	(zone
		(layer "In4.Cu")
		(hatch none 0.5)
		(connect_pads
			(clearance 0)
		)
		(min_thickness 0.25)
		(keepout
			(tracks allowed)
			(vias allowed)
			(pads allowed)
			(copperpour allowed)
			(footprints allowed)
		)
		(placement
			(enabled no)
			(sheetname "")
		)
		(fill
			(thermal_gap 0.5)
			(thermal_bridge_width 0.5)
			(island_removal_mode 0)
		)
		(polygon
			(pts
				(xy 420.958264 -300.407578) (xy 420.480998 -300.407578) (xy 420.074852 -300.407578) (xy 420.074852 -299.82033)
				(xy 418.853874 -299.82033) (xy 418.853874 -298.327318) (xy 418.853874 -297.958764) (xy 418.96538 -297.847258)
				(xy 419.917118 -297.847258) (xy 421.185086 -297.847258) (xy 421.185086 -298.194476) (xy 421.185086 -298.684188)
				(xy 421.185086 -300.407578)
			)
		)
	)
	(zone
		(layer "In4.Cu")
		(hatch none 0.5)
		(connect_pads
			(clearance 0)
		)
		(min_thickness 0.25)
		(keepout
			(tracks allowed)
			(vias allowed)
			(pads allowed)
			(copperpour allowed)
			(footprints allowed)
		)
		(placement
			(enabled no)
			(sheetname "")
		)
		(fill
			(thermal_gap 0.5)
			(thermal_bridge_width 0.5)
			(island_removal_mode 0)
		)
		(polygon
			(pts
				(xy 35.741102 -261.316216) (xy 35.741102 -259.96138) (xy 36.218368 -259.96138) (xy 36.218368 -261.316216)
			)
		)
	)
	(zone
		(layer "In4.Cu")
		(hatch none 0.5)
		(connect_pads
			(clearance 0)
		)
		(min_thickness 0.25)
		(keepout
			(tracks allowed)
			(vias allowed)
			(pads allowed)
			(copperpour allowed)
			(footprints allowed)
		)
		(placement
			(enabled no)
			(sheetname "")
		)
		(fill
			(thermal_gap 0.5)
			(thermal_bridge_width 0.5)
			(island_removal_mode 0)
		)
		(polygon
			(pts
				(xy 35.733482 -214.567516) (xy 35.733482 -213.21268) (xy 36.210748 -213.21268) (xy 36.210748 -214.567516)
			)
		)
	)
	(zone
		(layer "In4.Cu")
		(hatch none 0.5)
		(connect_pads
			(clearance 0)
		)
		(min_thickness 0.25)
		(keepout
			(tracks allowed)
			(vias allowed)
			(pads allowed)
			(copperpour allowed)
			(footprints allowed)
		)
		(placement
			(enabled no)
			(sheetname "")
		)
		(fill
			(thermal_gap 0.5)
			(thermal_bridge_width 0.5)
			(island_removal_mode 0)
		)
		(polygon
			(pts
				(xy 283.673042 -315.988954) (xy 283.673042 -314.634118) (xy 284.150308 -314.634118) (xy 284.150308 -315.988954)
			)
		)
	)
	(zone
		(layer "In4.Cu")
		(hatch none 0.5)
		(connect_pads
			(clearance 0)
		)
		(min_thickness 0.25)
		(keepout
			(tracks allowed)
			(vias allowed)
			(pads allowed)
			(copperpour allowed)
			(footprints allowed)
		)
		(placement
			(enabled no)
			(sheetname "")
		)
		(fill
			(thermal_gap 0.5)
			(thermal_bridge_width 0.5)
			(island_removal_mode 0)
		)
		(polygon
			(pts
				(xy 435.568598 -251.107448) (xy 435.568598 -249.752612) (xy 436.045864 -249.752612) (xy 436.045864 -251.107448)
			)
		)
	)
	(zone
		(layer "In4.Cu")
		(hatch none 0.5)
		(connect_pads
			(clearance 0)
		)
		(min_thickness 0.25)
		(keepout
			(tracks allowed)
			(vias allowed)
			(pads allowed)
			(copperpour allowed)
			(footprints allowed)
		)
		(placement
			(enabled no)
			(sheetname "")
		)
		(fill
			(thermal_gap 0.5)
			(thermal_bridge_width 0.5)
			(island_removal_mode 0)
		)
		(polygon
			(pts
				(xy 143.179292 -263.319514) (xy 143.389096 -263.109964) (xy 146.582384 -259.916168) (xy 146.582384 -259.851906)
				(xy 147.161504 -259.272786) (xy 147.161504 -258.863084) (xy 148.924772 -257.099816) (xy 149.143466 -256.881122)
				(xy 149.143466 -252.348492) (xy 148.439886 -251.644912) (xy 148.437346 -251.644912) (xy 148.437346 -251.05106)
				(xy 147.794472 -250.408186) (xy 147.782026 -250.408186) (xy 147.018502 -249.644662) (xy 147.018502 -249.50801)
				(xy 148.092922 -248.43359) (xy 148.443188 -248.43359) (xy 150.429214 -246.447564) (xy 150.201884 -246.220234)
				(xy 150.087584 -246.220234) (xy 149.858984 -245.991634) (xy 148.754084 -245.991634) (xy 147.077684 -244.315234)
				(xy 146.512534 -244.315234) (xy 145.916142 -244.911626) (xy 140.451586 -244.911626) (xy 140.27658 -245.086632)
				(xy 138.056874 -245.086632) (xy 137.954766 -245.18874) (xy 137.954766 -249.521472) (xy 137.498582 -249.977656)
				(xy 129.852928 -249.977656) (xy 129.554478 -250.276106) (xy 129.210308 -250.276106) (xy 129.145538 -250.211336)
				(xy 129.145538 -250.055888) (xy 129.145538 -249.903488) (xy 129.147824 -249.903488) (xy 129.173224 -249.878088)
				(xy 129.173224 -249.65025) (xy 129.04597 -249.522996) (xy 129.042668 -249.526298) (xy 128.211072 -249.526298)
				(xy 128.049528 -249.364754) (xy 127.773938 -249.364754) (xy 127.773938 -250.386088) (xy 127.900938 -250.513088)
				(xy 127.900938 -251.579888) (xy 127.443738 -252.037088) (xy 126.849886 -252.63094) (xy 126.849886 -252.924818)
				(xy 130.523488 -252.924818) (xy 130.821938 -252.924818) (xy 130.88112 -252.924818) (xy 130.95224 -252.995938)
				(xy 130.95224 -253.935738) (xy 131.101846 -254.085344) (xy 136.988296 -254.085344) (xy 137.075672 -254.17272)
				(xy 137.075672 -254.935228) (xy 137.075672 -255.00203) (xy 137.106152 -255.03251) (xy 138.743944 -255.03251)
				(xy 138.848846 -255.137412) (xy 139.711938 -255.137412) (xy 139.8143 -255.239774) (xy 139.8143 -256.09931)
				(xy 139.76223 -256.15138) (xy 137.428986 -256.15138) (xy 137.389362 -256.191004) (xy 137.389362 -257.21564)
				(xy 137.41781 -257.244088) (xy 138.909044 -257.244088) (xy 138.92657 -257.261614) (xy 138.92657 -257.908806)
				(xy 139.044426 -258.026662) (xy 139.565634 -258.026662) (xy 139.641072 -258.1021) (xy 139.641072 -259.754116)
				(xy 139.59332 -259.801868) (xy 139.534138 -259.801868) (xy 138.952986 -259.801868) (xy 138.93927 -259.815584)
				(xy 138.93927 -261.91083) (xy 138.96213 -261.93369) (xy 140.39215 -261.93369) (xy 140.569188 -262.110728)
				(xy 140.569188 -263.319768)
			)
		)
	)
	(zone
		(layer "In4.Cu")
		(hatch none 0.5)
		(connect_pads
			(clearance 0)
		)
		(min_thickness 0.25)
		(keepout
			(tracks allowed)
			(vias allowed)
			(pads allowed)
			(copperpour allowed)
			(footprints allowed)
		)
		(placement
			(enabled no)
			(sheetname "")
		)
		(fill
			(thermal_gap 0.5)
			(thermal_bridge_width 0.5)
			(island_removal_mode 0)
		)
		(polygon
			(pts
				(xy 28.202636 -246.001794) (xy 28.202636 -244.646958) (xy 28.679902 -244.646958) (xy 28.679902 -246.001794)
			)
		)
	)
	(zone
		(layer "In4.Cu")
		(hatch none 0.5)
		(connect_pads
			(clearance 0)
		)
		(min_thickness 0.25)
		(keepout
			(tracks allowed)
			(vias allowed)
			(pads allowed)
			(copperpour allowed)
			(footprints allowed)
		)
		(placement
			(enabled no)
			(sheetname "")
		)
		(fill
			(thermal_gap 0.5)
			(thermal_bridge_width 0.5)
			(island_removal_mode 0)
		)
		(polygon
			(pts
				(xy 283.652722 -291.876734) (xy 283.652722 -290.521898) (xy 284.129988 -290.521898) (xy 284.129988 -291.876734)
			)
		)
	)
	(zone
		(layer "In4.Cu")
		(hatch none 0.5)
		(connect_pads
			(clearance 0)
		)
		(min_thickness 0.25)
		(keepout
			(tracks allowed)
			(vias allowed)
			(pads allowed)
			(copperpour allowed)
			(footprints allowed)
		)
		(placement
			(enabled no)
			(sheetname "")
		)
		(fill
			(thermal_gap 0.5)
			(thermal_bridge_width 0.5)
			(island_removal_mode 0)
		)
		(polygon
			(pts
				(xy 298.77639 -229.017576) (xy 298.77639 -227.66274) (xy 299.253656 -227.66274) (xy 299.253656 -229.017576)
				(xy 299.253656 -231.935274) (xy 298.77639 -231.935274)
			)
		)
	)
	(zone
		(layer "In4.Cu")
		(hatch none 0.5)
		(connect_pads
			(clearance 0)
		)
		(min_thickness 0.25)
		(keepout
			(tracks allowed)
			(vias allowed)
			(pads allowed)
			(copperpour allowed)
			(footprints allowed)
		)
		(placement
			(enabled no)
			(sheetname "")
		)
		(fill
			(thermal_gap 0.5)
			(thermal_bridge_width 0.5)
			(island_removal_mode 0)
		)
		(polygon
			(pts
				(xy 142.995396 -271.467834) (xy 144.106392 -271.467834) (xy 144.893792 -272.255234) (xy 141.134846 -276.014434)
				(xy 140.601446 -276.014688) (xy 139.359386 -274.772882) (xy 139.359386 -274.629372) (xy 139.356592 -274.626578)
				(xy 139.356592 -274.157694) (xy 139.540742 -273.973544) (xy 139.540742 -272.657062) (xy 140.696696 -271.501108)
				(xy 140.696696 -271.400524) (xy 140.468604 -271.172432) (xy 140.468604 -271.139666) (xy 140.468604 -271.134586)
				(xy 141.429232 -270.173958) (xy 141.434312 -270.173958) (xy 142.728188 -271.467834)
			)
		)
	)
	(zone
		(layer "In4.Cu")
		(hatch none 0.5)
		(connect_pads
			(clearance 0)
		)
		(min_thickness 0.25)
		(keepout
			(tracks allowed)
			(vias allowed)
			(pads allowed)
			(copperpour allowed)
			(footprints allowed)
		)
		(placement
			(enabled no)
			(sheetname "")
		)
		(fill
			(thermal_gap 0.5)
			(thermal_bridge_width 0.5)
			(island_removal_mode 0)
		)
		(polygon
			(pts
				(xy 43.339004 -261.227316) (xy 43.339004 -258.273296) (xy 43.694604 -258.273296) (xy 43.694604 -261.227316)
			)
		)
	)
	(zone
		(layer "In4.Cu")
		(hatch none 0.5)
		(connect_pads
			(clearance 0)
		)
		(min_thickness 0.25)
		(keepout
			(tracks allowed)
			(vias allowed)
			(pads allowed)
			(copperpour allowed)
			(footprints allowed)
		)
		(placement
			(enabled no)
			(sheetname "")
		)
		(fill
			(thermal_gap 0.5)
			(thermal_bridge_width 0.5)
			(island_removal_mode 0)
		)
		(polygon
			(pts
				(xy 115.97386 -339.077808) (xy 115.97386 -334.853788) (xy 122.71248 -334.853788) (xy 122.71248 -339.077808)
			)
		)
	)
	(zone
		(layer "In4.Cu")
		(hatch none 0.5)
		(connect_pads
			(clearance 0)
		)
		(min_thickness 0.25)
		(keepout
			(tracks allowed)
			(vias allowed)
			(pads allowed)
			(copperpour allowed)
			(footprints allowed)
		)
		(placement
			(enabled no)
			(sheetname "")
		)
		(fill
			(thermal_gap 0.5)
			(thermal_bridge_width 0.5)
			(island_removal_mode 0)
		)
		(polygon
			(pts
				(xy 143.65732 -10.78738) (xy 143.65732 -9.3345) (xy 142.82674 -9.3345) (xy 142.82674 -10.78738)
			)
		)
	)
	(zone
		(layer "In4.Cu")
		(hatch none 0.5)
		(connect_pads
			(clearance 0)
		)
		(min_thickness 0.25)
		(keepout
			(tracks allowed)
			(vias allowed)
			(pads allowed)
			(copperpour allowed)
			(footprints allowed)
		)
		(placement
			(enabled no)
			(sheetname "")
		)
		(fill
			(thermal_gap 0.5)
			(thermal_bridge_width 0.5)
			(island_removal_mode 0)
		)
		(polygon
			(pts
				(xy 302.229012 -245.060216) (xy 302.229012 -242.903756) (xy 302.767492 -242.903756) (xy 302.767492 -245.060216)
			)
		)
	)
	(zone
		(layer "In4.Cu")
		(hatch none 0.5)
		(connect_pads
			(clearance 0)
		)
		(min_thickness 0.25)
		(keepout
			(tracks allowed)
			(vias allowed)
			(pads allowed)
			(copperpour allowed)
			(footprints allowed)
		)
		(placement
			(enabled no)
			(sheetname "")
		)
		(fill
			(thermal_gap 0.5)
			(thermal_bridge_width 0.5)
			(island_removal_mode 0)
		)
		(polygon
			(pts
				(xy 313.877452 -303.818036) (xy 313.877452 -298.245276) (xy 314.327032 -298.245276) (xy 314.327032 -303.818036)
			)
		)
	)
	(zone
		(layer "In4.Cu")
		(hatch none 0.5)
		(connect_pads
			(clearance 0)
		)
		(min_thickness 0.25)
		(keepout
			(tracks allowed)
			(vias allowed)
			(pads allowed)
			(copperpour allowed)
			(footprints allowed)
		)
		(placement
			(enabled no)
			(sheetname "")
		)
		(fill
			(thermal_gap 0.5)
			(thermal_bridge_width 0.5)
			(island_removal_mode 0)
		)
		(polygon
			(pts
				(xy 311.63768 -244.403118) (xy 311.63768 -241.314478) (xy 312.03138 -241.314478) (xy 312.03138 -244.403118)
			)
		)
	)
	(zone
		(layer "In4.Cu")
		(hatch none 0.5)
		(connect_pads
			(clearance 0)
		)
		(min_thickness 0.25)
		(keepout
			(tracks allowed)
			(vias allowed)
			(pads allowed)
			(copperpour allowed)
			(footprints allowed)
		)
		(placement
			(enabled no)
			(sheetname "")
		)
		(fill
			(thermal_gap 0.5)
			(thermal_bridge_width 0.5)
			(island_removal_mode 0)
		)
		(polygon
			(pts
				(xy 50.853594 -287.688274) (xy 50.853594 -286.333438) (xy 51.33086 -286.333438) (xy 51.33086 -287.688274)
			)
		)
	)
	(zone
		(layer "In4.Cu")
		(hatch none 0.5)
		(connect_pads
			(clearance 0)
		)
		(min_thickness 0.25)
		(keepout
			(tracks allowed)
			(vias allowed)
			(pads allowed)
			(copperpour allowed)
			(footprints allowed)
		)
		(placement
			(enabled no)
			(sheetname "")
		)
		(fill
			(thermal_gap 0.5)
			(thermal_bridge_width 0.5)
			(island_removal_mode 0)
		)
		(polygon
			(pts
				(xy 50.787554 -252.700028) (xy 50.787554 -251.730764) (xy 51.237896 -251.730764) (xy 51.237896 -252.700028)
			)
		)
	)
	(zone
		(layer "In4.Cu")
		(hatch none 0.5)
		(connect_pads
			(clearance 0)
		)
		(min_thickness 0.25)
		(keepout
			(tracks allowed)
			(vias allowed)
			(pads allowed)
			(copperpour allowed)
			(footprints allowed)
		)
		(placement
			(enabled no)
			(sheetname "")
		)
		(fill
			(thermal_gap 0.5)
			(thermal_bridge_width 0.5)
			(island_removal_mode 0)
		)
		(polygon
			(pts
				(xy 294.15994 -300.195488) (xy 294.15994 -298.740068) (xy 295.96588 -298.740068) (xy 295.96588 -300.195488)
			)
		)
	)
	(zone
		(layer "In4.Cu")
		(hatch none 0.5)
		(connect_pads
			(clearance 0)
		)
		(min_thickness 0.25)
		(keepout
			(tracks allowed)
			(vias allowed)
			(pads allowed)
			(copperpour allowed)
			(footprints allowed)
		)
		(placement
			(enabled no)
			(sheetname "")
		)
		(fill
			(thermal_gap 0.5)
			(thermal_bridge_width 0.5)
			(island_removal_mode 0)
		)
		(polygon
			(pts
				(xy 309.74538 -305.543458) (xy 309.74538 -301.598838) (xy 310.26862 -301.598838) (xy 310.26862 -305.543458)
			)
		)
	)
	(zone
		(layer "In4.Cu")
		(hatch none 0.5)
		(connect_pads
			(clearance 0)
		)
		(min_thickness 0.25)
		(keepout
			(tracks allowed)
			(vias allowed)
			(pads allowed)
			(copperpour allowed)
			(footprints allowed)
		)
		(placement
			(enabled no)
			(sheetname "")
		)
		(fill
			(thermal_gap 0.5)
			(thermal_bridge_width 0.5)
			(island_removal_mode 0)
		)
		(polygon
			(pts
				(xy 405.38781 -305.501548) (xy 405.38781 -304.146712) (xy 405.38781 -303.420526) (xy 405.865076 -303.420526)
				(xy 405.865076 -304.146712) (xy 405.865076 -305.501548)
			)
		)
	)
	(zone
		(layer "In4.Cu")
		(hatch none 0.5)
		(connect_pads
			(clearance 0)
		)
		(min_thickness 0.25)
		(keepout
			(tracks allowed)
			(vias allowed)
			(pads allowed)
			(copperpour allowed)
			(footprints allowed)
		)
		(placement
			(enabled no)
			(sheetname "")
		)
		(fill
			(thermal_gap 0.5)
			(thermal_bridge_width 0.5)
			(island_removal_mode 0)
		)
		(polygon
			(pts
				(xy 283.685742 -246.024654) (xy 283.685742 -244.669818) (xy 284.163008 -244.669818) (xy 284.163008 -246.024654)
			)
		)
	)
	(zone
		(layer "In4.Cu")
		(hatch none 0.5)
		(connect_pads
			(clearance 0)
		)
		(min_thickness 0.25)
		(keepout
			(tracks allowed)
			(vias allowed)
			(pads allowed)
			(copperpour allowed)
			(footprints allowed)
		)
		(placement
			(enabled no)
			(sheetname "")
		)
		(fill
			(thermal_gap 0.5)
			(thermal_bridge_width 0.5)
			(island_removal_mode 0)
		)
		(polygon
			(pts
				(xy 435.58841 -234.951524) (xy 435.58841 -233.596688) (xy 436.065676 -233.596688) (xy 436.065676 -234.951524)
			)
		)
	)
	(zone
		(layer "In4.Cu")
		(hatch none 0.5)
		(connect_pads
			(clearance 0)
		)
		(min_thickness 0.25)
		(keepout
			(tracks allowed)
			(vias allowed)
			(pads allowed)
			(copperpour allowed)
			(footprints allowed)
		)
		(placement
			(enabled no)
			(sheetname "")
		)
		(fill
			(thermal_gap 0.5)
			(thermal_bridge_width 0.5)
			(island_removal_mode 0)
		)
		(polygon
			(pts
				(xy 420.50081 -305.501548) (xy 420.50081 -304.146712) (xy 420.978076 -304.146712) (xy 420.978076 -305.501548)
			)
		)
	)
	(zone
		(layer "In4.Cu")
		(hatch none 0.5)
		(connect_pads
			(clearance 0)
		)
		(min_thickness 0.25)
		(keepout
			(tracks allowed)
			(vias allowed)
			(pads allowed)
			(copperpour allowed)
			(footprints allowed)
		)
		(placement
			(enabled no)
			(sheetname "")
		)
		(fill
			(thermal_gap 0.5)
			(thermal_bridge_width 0.5)
			(island_removal_mode 0)
		)
		(polygon
			(pts
				(xy 187.62853 -247.707404) (xy 187.62853 -246.352568) (xy 188.105796 -246.352568) (xy 188.105796 -247.707404)
			)
		)
	)
	(zone
		(layer "In4.Cu")
		(hatch none 0.5)
		(connect_pads
			(clearance 0)
		)
		(min_thickness 0.25)
		(keepout
			(tracks allowed)
			(vias allowed)
			(pads allowed)
			(copperpour allowed)
			(footprints allowed)
		)
		(placement
			(enabled no)
			(sheetname "")
		)
		(fill
			(thermal_gap 0.5)
			(thermal_bridge_width 0.5)
			(island_removal_mode 0)
		)
		(polygon
			(pts
				(xy 46.727364 -259.571236) (xy 46.727364 -258.316476) (xy 47.204884 -258.316476) (xy 47.204884 -259.571236)
			)
		)
	)
	(zone
		(layer "In4.Cu")
		(hatch none 0.5)
		(connect_pads
			(clearance 0)
		)
		(min_thickness 0.25)
		(keepout
			(tracks allowed)
			(vias allowed)
			(pads allowed)
			(copperpour allowed)
			(footprints allowed)
		)
		(placement
			(enabled no)
			(sheetname "")
		)
		(fill
			(thermal_gap 0.5)
			(thermal_bridge_width 0.5)
			(island_removal_mode 0)
		)
		(polygon
			(pts
				(xy 41.080436 -319.101978) (xy 41.080436 -317.747142) (xy 41.557702 -317.747142) (xy 41.557702 -319.101978)
			)
		)
	)
	(zone
		(layer "In4.Cu")
		(hatch none 0.5)
		(connect_pads
			(clearance 0)
		)
		(min_thickness 0.25)
		(keepout
			(tracks allowed)
			(vias allowed)
			(pads allowed)
			(copperpour allowed)
			(footprints allowed)
		)
		(placement
			(enabled no)
			(sheetname "")
		)
		(fill
			(thermal_gap 0.5)
			(thermal_bridge_width 0.5)
			(island_removal_mode 0)
		)
		(polygon
			(pts
				(xy 307.5432 -318.210438) (xy 307.5432 -316.912498) (xy 308.04866 -316.912498) (xy 308.04866 -318.210438)
			)
		)
	)
	(zone
		(layer "In4.Cu")
		(hatch none 0.5)
		(connect_pads
			(clearance 0)
		)
		(min_thickness 0.25)
		(keepout
			(tracks allowed)
			(vias allowed)
			(pads allowed)
			(copperpour allowed)
			(footprints allowed)
		)
		(placement
			(enabled no)
			(sheetname "")
		)
		(fill
			(thermal_gap 0.5)
			(thermal_bridge_width 0.5)
			(island_removal_mode 0)
		)
		(polygon
			(pts
				(xy 291.17798 -317.303658) (xy 291.17798 -316.183518) (xy 291.73932 -316.183518) (xy 291.73932 -317.303658)
			)
		)
	)
	(zone
		(layer "In4.Cu")
		(hatch none 0.5)
		(connect_pads
			(clearance 0)
		)
		(min_thickness 0.25)
		(keepout
			(tracks allowed)
			(vias allowed)
			(pads allowed)
			(copperpour allowed)
			(footprints allowed)
		)
		(placement
			(enabled no)
			(sheetname "")
		)
		(fill
			(thermal_gap 0.5)
			(thermal_bridge_width 0.5)
			(island_removal_mode 0)
		)
		(polygon
			(pts
				(xy 79.24292 -347.917008) (xy 79.24292 -346.413328) (xy 81.18094 -346.413328) (xy 81.18094 -347.917008)
			)
		)
	)
	(zone
		(layer "In4.Cu")
		(hatch none 0.5)
		(connect_pads
			(clearance 0)
		)
		(min_thickness 0.25)
		(keepout
			(tracks allowed)
			(vias allowed)
			(pads allowed)
			(copperpour allowed)
			(footprints allowed)
		)
		(placement
			(enabled no)
			(sheetname "")
		)
		(fill
			(thermal_gap 0.5)
			(thermal_bridge_width 0.5)
			(island_removal_mode 0)
		)
		(polygon
			(pts
				(xy 283.706062 -210.243674) (xy 283.706062 -208.888838) (xy 284.183328 -208.888838) (xy 284.183328 -210.243674)
			)
		)
	)
	(zone
		(layer "In4.Cu")
		(hatch none 0.5)
		(connect_pads
			(clearance 0)
		)
		(min_thickness 0.25)
		(keepout
			(tracks allowed)
			(vias allowed)
			(pads allowed)
			(copperpour allowed)
			(footprints allowed)
		)
		(placement
			(enabled no)
			(sheetname "")
		)
		(fill
			(thermal_gap 0.5)
			(thermal_bridge_width 0.5)
			(island_removal_mode 0)
		)
		(polygon
			(pts
				(xy 283.68625 -211.349336) (xy 283.68625 -209.9945) (xy 284.163516 -209.9945) (xy 284.163516 -211.349336)
			)
		)
	)
	(zone
		(layer "In4.Cu")
		(hatch none 0.5)
		(connect_pads
			(clearance 0)
		)
		(min_thickness 0.25)
		(keepout
			(tracks allowed)
			(vias allowed)
			(pads allowed)
			(copperpour allowed)
			(footprints allowed)
		)
		(placement
			(enabled no)
			(sheetname "")
		)
		(fill
			(thermal_gap 0.5)
			(thermal_bridge_width 0.5)
			(island_removal_mode 0)
		)
		(polygon
			(pts
				(xy 74.825352 -247.848628) (xy 76.404216 -249.427238) (xy 76.404216 -250.152916) (xy 74.923396 -251.633736)
				(xy 74.923396 -252.764036) (xy 75.875642 -253.716282) (xy 75.875642 -254.011176) (xy 75.347068 -254.53975)
				(xy 70.806056 -254.53975) (xy 70.750938 -254.594868) (xy 70.750938 -255.129538) (xy 70.898512 -255.277112)
				(xy 71.188326 -255.277112) (xy 75.620626 -259.709412) (xy 82.404458 -259.709412) (xy 82.733642 -259.380228)
				(xy 83.28279 -259.380228) (xy 83.576414 -259.086604) (xy 83.577938 -259.086604) (xy 84.149692 -258.51485)
				(xy 84.245958 -258.51485) (xy 84.245958 -256.699004) (xy 84.111338 -256.699004) (xy 82.865722 -256.699004)
				(xy 82.230722 -256.699258) (xy 80.274922 -254.743458) (xy 80.274922 -251.949458) (xy 80.948022 -251.276358)
				(xy 80.948022 -249.066558) (xy 81.468722 -248.545858) (xy 82.535522 -248.545604) (xy 82.535522 -247.453404)
				(xy 76.083922 -247.453658) (xy 76.033122 -247.402858) (xy 74.991722 -247.402858) (xy 74.825352 -247.569228)
			)
		)
	)
	(zone
		(layer "In4.Cu")
		(hatch none 0.5)
		(connect_pads
			(clearance 0)
		)
		(min_thickness 0.25)
		(keepout
			(tracks allowed)
			(vias allowed)
			(pads allowed)
			(copperpour allowed)
			(footprints allowed)
		)
		(placement
			(enabled no)
			(sheetname "")
		)
		(fill
			(thermal_gap 0.5)
			(thermal_bridge_width 0.5)
			(island_removal_mode 0)
		)
		(polygon
			(pts
				(xy 31.621222 -267.285216) (xy 31.621222 -265.93038) (xy 32.098488 -265.93038) (xy 32.098488 -267.285216)
			)
		)
	)
	(zone
		(layer "In4.Cu")
		(hatch none 0.5)
		(connect_pads
			(clearance 0)
		)
		(min_thickness 0.25)
		(keepout
			(tracks allowed)
			(vias allowed)
			(pads allowed)
			(copperpour allowed)
			(footprints allowed)
		)
		(placement
			(enabled no)
			(sheetname "")
		)
		(fill
			(thermal_gap 0.5)
			(thermal_bridge_width 0.5)
			(island_removal_mode 0)
		)
		(polygon
			(pts
				(xy 35.745674 -297.040554) (xy 35.745674 -295.685718) (xy 36.22294 -295.685718) (xy 36.22294 -297.040554)
			)
		)
	)
	(zone
		(layer "In4.Cu")
		(hatch none 0.5)
		(connect_pads
			(clearance 0)
		)
		(min_thickness 0.25)
		(keepout
			(tracks allowed)
			(vias allowed)
			(pads allowed)
			(copperpour allowed)
			(footprints allowed)
		)
		(placement
			(enabled no)
			(sheetname "")
		)
		(fill
			(thermal_gap 0.5)
			(thermal_bridge_width 0.5)
			(island_removal_mode 0)
		)
		(polygon
			(pts
				(xy 35.760914 -261.310374) (xy 35.760914 -259.955538) (xy 36.23818 -259.955538) (xy 36.23818 -261.310374)
			)
		)
	)
	(zone
		(layer "In4.Cu")
		(hatch none 0.5)
		(connect_pads
			(clearance 0)
		)
		(min_thickness 0.25)
		(keepout
			(tracks allowed)
			(vias allowed)
			(pads allowed)
			(copperpour allowed)
			(footprints allowed)
		)
		(placement
			(enabled no)
			(sheetname "")
		)
		(fill
			(thermal_gap 0.5)
			(thermal_bridge_width 0.5)
			(island_removal_mode 0)
		)
		(polygon
			(pts
				(xy 283.673042 -298.716954) (xy 283.673042 -297.362118) (xy 284.150308 -297.362118) (xy 284.150308 -298.716954)
			)
		)
	)
	(zone
		(layer "In4.Cu")
		(hatch none 0.5)
		(connect_pads
			(clearance 0)
		)
		(min_thickness 0.25)
		(keepout
			(tracks allowed)
			(vias allowed)
			(pads allowed)
			(copperpour allowed)
			(footprints allowed)
		)
		(placement
			(enabled no)
			(sheetname "")
		)
		(fill
			(thermal_gap 0.5)
			(thermal_bridge_width 0.5)
			(island_removal_mode 0)
		)
		(polygon
			(pts
				(xy 435.58841 -249.401584) (xy 435.58841 -248.046748) (xy 436.065676 -248.046748) (xy 436.065676 -249.401584)
			)
		)
	)
	(zone
		(layer "In4.Cu")
		(hatch none 0.5)
		(connect_pads
			(clearance 0)
		)
		(min_thickness 0.25)
		(keepout
			(tracks allowed)
			(vias allowed)
			(pads allowed)
			(copperpour allowed)
			(footprints allowed)
		)
		(placement
			(enabled no)
			(sheetname "")
		)
		(fill
			(thermal_gap 0.5)
			(thermal_bridge_width 0.5)
			(island_removal_mode 0)
		)
		(polygon
			(pts
				(xy 48.617124 -244.333776) (xy 48.617124 -242.924076) (xy 49.155604 -242.924076) (xy 49.155604 -244.333776)
			)
		)
	)
	(zone
		(layer "In4.Cu")
		(hatch none 0.5)
		(connect_pads
			(clearance 0)
		)
		(min_thickness 0.25)
		(keepout
			(tracks allowed)
			(vias allowed)
			(pads allowed)
			(copperpour allowed)
			(footprints allowed)
		)
		(placement
			(enabled no)
			(sheetname "")
		)
		(fill
			(thermal_gap 0.5)
			(thermal_bridge_width 0.5)
			(island_removal_mode 0)
		)
		(polygon
			(pts
				(xy 435.558692 -308.013862) (xy 435.558692 -306.659026) (xy 436.035958 -306.659026) (xy 436.035958 -308.013862)
			)
		)
	)
	(zone
		(layer "In4.Cu")
		(hatch none 0.5)
		(connect_pads
			(clearance 0)
		)
		(min_thickness 0.25)
		(keepout
			(tracks allowed)
			(vias allowed)
			(pads allowed)
			(copperpour allowed)
			(footprints allowed)
		)
		(placement
			(enabled no)
			(sheetname "")
		)
		(fill
			(thermal_gap 0.5)
			(thermal_bridge_width 0.5)
			(island_removal_mode 0)
		)
		(polygon
			(pts
				(xy 187.648342 -263.851644) (xy 187.648342 -262.496808) (xy 188.125608 -262.496808) (xy 188.125608 -263.851644)
			)
		)
	)
	(zone
		(layer "In4.Cu")
		(hatch none 0.5)
		(connect_pads
			(clearance 0)
		)
		(min_thickness 0.25)
		(keepout
			(tracks allowed)
			(vias allowed)
			(pads allowed)
			(copperpour allowed)
			(footprints allowed)
		)
		(placement
			(enabled no)
			(sheetname "")
		)
		(fill
			(thermal_gap 0.5)
			(thermal_bridge_width 0.5)
			(island_removal_mode 0)
		)
		(polygon
			(pts
				(xy 424.603164 -319.15608) (xy 424.603164 -317.801244) (xy 425.08043 -317.801244) (xy 425.08043 -319.15608)
			)
		)
	)
	(zone
		(layer "In4.Cu")
		(hatch none 0.5)
		(connect_pads
			(clearance 0)
		)
		(min_thickness 0.25)
		(keepout
			(tracks allowed)
			(vias allowed)
			(pads allowed)
			(copperpour allowed)
			(footprints allowed)
		)
		(placement
			(enabled no)
			(sheetname "")
		)
		(fill
			(thermal_gap 0.5)
			(thermal_bridge_width 0.5)
			(island_removal_mode 0)
		)
		(polygon
			(pts
				(xy 420.480998 -243.457476) (xy 420.480998 -242.96116) (xy 420.085012 -242.96116) (xy 420.085012 -242.10264)
				(xy 420.480998 -242.10264) (xy 420.958264 -242.10264) (xy 421.241728 -242.10264) (xy 421.241728 -242.977924)
				(xy 420.958264 -242.977924) (xy 420.958264 -243.457476)
			)
		)
	)
	(zone
		(layer "In4.Cu")
		(hatch none 0.5)
		(connect_pads
			(clearance 0)
		)
		(min_thickness 0.25)
		(keepout
			(tracks allowed)
			(vias allowed)
			(pads allowed)
			(copperpour allowed)
			(footprints allowed)
		)
		(placement
			(enabled no)
			(sheetname "")
		)
		(fill
			(thermal_gap 0.5)
			(thermal_bridge_width 0.5)
			(island_removal_mode 0)
		)
		(polygon
			(pts
				(xy 304.07356 -244.278658) (xy 304.07356 -242.973098) (xy 304.67554 -242.973098) (xy 304.67554 -244.278658)
			)
		)
	)
	(zone
		(layer "In4.Cu")
		(hatch none 0.5)
		(connect_pads
			(clearance 0)
		)
		(min_thickness 0.25)
		(keepout
			(tracks allowed)
			(vias allowed)
			(pads allowed)
			(copperpour allowed)
			(footprints allowed)
		)
		(placement
			(enabled no)
			(sheetname "")
		)
		(fill
			(thermal_gap 0.5)
			(thermal_bridge_width 0.5)
			(island_removal_mode 0)
		)
		(polygon
			(pts
				(xy 35.725862 -297.046396) (xy 35.725862 -295.69156) (xy 36.203128 -295.69156) (xy 36.203128 -297.046396)
			)
		)
	)
	(zone
		(layer "In4.Cu")
		(hatch none 0.5)
		(connect_pads
			(clearance 0)
		)
		(min_thickness 0.25)
		(keepout
			(tracks allowed)
			(vias allowed)
			(pads allowed)
			(copperpour allowed)
			(footprints allowed)
		)
		(placement
			(enabled no)
			(sheetname "")
		)
		(fill
			(thermal_gap 0.5)
			(thermal_bridge_width 0.5)
			(island_removal_mode 0)
		)
		(polygon
			(pts
				(xy 293.24046 -244.112288) (xy 293.24046 -241.798348) (xy 296.6339 -241.798348) (xy 296.6339 -244.112288)
			)
		)
	)
	(zone
		(layer "In4.Cu")
		(hatch none 0.5)
		(connect_pads
			(clearance 0)
		)
		(min_thickness 0.25)
		(keepout
			(tracks allowed)
			(vias allowed)
			(pads allowed)
			(copperpour allowed)
			(footprints allowed)
		)
		(placement
			(enabled no)
			(sheetname "")
		)
		(fill
			(thermal_gap 0.5)
			(thermal_bridge_width 0.5)
			(island_removal_mode 0)
		)
		(polygon
			(pts
				(xy 412.93161 -244.301518) (xy 412.93161 -242.946682) (xy 413.408876 -242.946682) (xy 413.408876 -244.301518)
			)
		)
	)
	(zone
		(layer "In4.Cu")
		(hatch none 0.5)
		(connect_pads
			(clearance 0)
		)
		(min_thickness 0.25)
		(keepout
			(tracks allowed)
			(vias allowed)
			(pads allowed)
			(copperpour allowed)
			(footprints allowed)
		)
		(placement
			(enabled no)
			(sheetname "")
		)
		(fill
			(thermal_gap 0.5)
			(thermal_bridge_width 0.5)
			(island_removal_mode 0)
		)
		(polygon
			(pts
				(xy 172.54093 -228.14534) (xy 172.54093 -225.952558) (xy 173.018196 -225.952558) (xy 173.018196 -228.14534)
			)
		)
	)
	(zone
		(layer "In4.Cu")
		(hatch none 0.5)
		(connect_pads
			(clearance 0)
		)
		(min_thickness 0.25)
		(keepout
			(tracks allowed)
			(vias allowed)
			(pads allowed)
			(copperpour allowed)
			(footprints allowed)
		)
		(placement
			(enabled no)
			(sheetname "")
		)
		(fill
			(thermal_gap 0.5)
			(thermal_bridge_width 0.5)
			(island_removal_mode 0)
		)
		(polygon
			(pts
				(xy 35.725862 -246.030496) (xy 35.725862 -244.67566) (xy 36.203128 -244.67566) (xy 36.203128 -246.030496)
			)
		)
	)
	(zone
		(layer "In4.Cu")
		(hatch none 0.5)
		(connect_pads
			(clearance 0)
		)
		(min_thickness 0.25)
		(keepout
			(tracks allowed)
			(vias allowed)
			(pads allowed)
			(copperpour allowed)
			(footprints allowed)
		)
		(placement
			(enabled no)
			(sheetname "")
		)
		(fill
			(thermal_gap 0.5)
			(thermal_bridge_width 0.5)
			(island_removal_mode 0)
		)
		(polygon
			(pts
				(xy 322.01104 -348.585028) (xy 322.01104 -347.363288) (xy 322.72478 -347.363288) (xy 322.72478 -348.585028)
			)
		)
	)
	(zone
		(layer "In4.Cu")
		(hatch none 0.5)
		(connect_pads
			(clearance 0)
		)
		(min_thickness 0.25)
		(keepout
			(tracks allowed)
			(vias allowed)
			(pads allowed)
			(copperpour allowed)
			(footprints allowed)
		)
		(placement
			(enabled no)
			(sheetname "")
		)
		(fill
			(thermal_gap 0.5)
			(thermal_bridge_width 0.5)
			(island_removal_mode 0)
		)
		(polygon
			(pts
				(xy 283.66593 -297.046396) (xy 283.66593 -295.69156) (xy 284.143196 -295.69156) (xy 284.143196 -297.046396)
			)
		)
	)
	(zone
		(layer "In4.Cu")
		(hatch none 0.5)
		(connect_pads
			(clearance 0)
		)
		(min_thickness 0.25)
		(keepout
			(tracks allowed)
			(vias allowed)
			(pads allowed)
			(copperpour allowed)
			(footprints allowed)
		)
		(placement
			(enabled no)
			(sheetname "")
		)
		(fill
			(thermal_gap 0.5)
			(thermal_bridge_width 0.5)
			(island_removal_mode 0)
		)
		(polygon
			(pts
				(xy 279.576022 -244.315234) (xy 279.576022 -242.960398) (xy 280.053288 -242.960398) (xy 280.053288 -244.315234)
			)
		)
	)
	(zone
		(layer "In4.Cu")
		(hatch none 0.5)
		(connect_pads
			(clearance 0)
		)
		(min_thickness 0.25)
		(keepout
			(tracks allowed)
			(vias allowed)
			(pads allowed)
			(copperpour allowed)
			(footprints allowed)
		)
		(placement
			(enabled no)
			(sheetname "")
		)
		(fill
			(thermal_gap 0.5)
			(thermal_bridge_width 0.5)
			(island_removal_mode 0)
		)
		(polygon
			(pts
				(xy 420.480998 -225.607372) (xy 420.480998 -224.252536) (xy 420.958264 -224.252536) (xy 420.958264 -225.607372)
			)
		)
	)
	(zone
		(layer "In4.Cu")
		(hatch none 0.5)
		(connect_pads
			(clearance 0)
		)
		(min_thickness 0.25)
		(keepout
			(tracks allowed)
			(vias allowed)
			(pads allowed)
			(copperpour allowed)
			(footprints allowed)
		)
		(placement
			(enabled no)
			(sheetname "")
		)
		(fill
			(thermal_gap 0.5)
			(thermal_bridge_width 0.5)
			(island_removal_mode 0)
		)
		(polygon
			(pts
				(xy 420.480998 -281.70759) (xy 420.480998 -280.352754) (xy 420.958264 -280.352754) (xy 420.958264 -281.70759)
			)
		)
	)
	(zone
		(layer "In4.Cu")
		(hatch none 0.5)
		(connect_pads
			(clearance 0)
		)
		(min_thickness 0.25)
		(keepout
			(tracks allowed)
			(vias allowed)
			(pads allowed)
			(copperpour allowed)
			(footprints allowed)
		)
		(placement
			(enabled no)
			(sheetname "")
		)
		(fill
			(thermal_gap 0.5)
			(thermal_bridge_width 0.5)
			(island_removal_mode 0)
		)
		(polygon
			(pts
				(xy 313.897772 -306.695856) (xy 313.897772 -304.996596) (xy 314.281312 -304.996596) (xy 314.281312 -306.695856)
			)
		)
	)
	(zone
		(layer "In4.Cu")
		(hatch none 0.5)
		(connect_pads
			(clearance 0)
		)
		(min_thickness 0.25)
		(keepout
			(tracks allowed)
			(vias allowed)
			(pads allowed)
			(copperpour allowed)
			(footprints allowed)
		)
		(placement
			(enabled no)
			(sheetname "")
		)
		(fill
			(thermal_gap 0.5)
			(thermal_bridge_width 0.5)
			(island_removal_mode 0)
		)
		(polygon
			(pts
				(xy 435.581552 -309.733442) (xy 435.581552 -308.378606) (xy 436.058818 -308.378606) (xy 436.058818 -309.733442)
			)
		)
	)
	(zone
		(layer "In4.Cu")
		(hatch none 0.5)
		(connect_pads
			(clearance 0)
		)
		(min_thickness 0.25)
		(keepout
			(tracks allowed)
			(vias allowed)
			(pads allowed)
			(copperpour allowed)
			(footprints allowed)
		)
		(placement
			(enabled no)
			(sheetname "")
		)
		(fill
			(thermal_gap 0.5)
			(thermal_bridge_width 0.5)
			(island_removal_mode 0)
		)
		(polygon
			(pts
				(xy 187.648342 -234.951524) (xy 187.648342 -233.596688) (xy 188.125608 -233.596688) (xy 188.125608 -234.951524)
			)
		)
	)
	(zone
		(layer "In4.Cu")
		(hatch none 0.5)
		(connect_pads
			(clearance 0)
		)
		(min_thickness 0.25)
		(keepout
			(tracks allowed)
			(vias allowed)
			(pads allowed)
			(copperpour allowed)
			(footprints allowed)
		)
		(placement
			(enabled no)
			(sheetname "")
		)
		(fill
			(thermal_gap 0.5)
			(thermal_bridge_width 0.5)
			(island_removal_mode 0)
		)
		(polygon
			(pts
				(xy 287.39592 -367.668048) (xy 287.39592 -366.189768) (xy 289.11804 -366.189768) (xy 289.11804 -367.668048)
			)
		)
	)
	(zone
		(layer "In4.Cu")
		(hatch none 0.5)
		(connect_pads
			(clearance 0)
		)
		(min_thickness 0.25)
		(keepout
			(tracks allowed)
			(vias allowed)
			(pads allowed)
			(copperpour allowed)
			(footprints allowed)
		)
		(placement
			(enabled no)
			(sheetname "")
		)
		(fill
			(thermal_gap 0.5)
			(thermal_bridge_width 0.5)
			(island_removal_mode 0)
		)
		(polygon
			(pts
				(xy 298.793662 -285.112714) (xy 298.793662 -283.757878) (xy 299.270928 -283.757878) (xy 299.270928 -285.112714)
			)
		)
	)
	(zone
		(layer "In4.Cu")
		(hatch none 0.5)
		(connect_pads
			(clearance 0)
		)
		(min_thickness 0.25)
		(keepout
			(tracks allowed)
			(vias allowed)
			(pads allowed)
			(copperpour allowed)
			(footprints allowed)
		)
		(placement
			(enabled no)
			(sheetname "")
		)
		(fill
			(thermal_gap 0.5)
			(thermal_bridge_width 0.5)
			(island_removal_mode 0)
		)
		(polygon
			(pts
				(xy 187.618624 -316.693042) (xy 187.618624 -315.338206) (xy 188.09589 -315.338206) (xy 188.09589 -316.693042)
			)
		)
	)
	(zone
		(layer "In4.Cu")
		(hatch none 0.5)
		(connect_pads
			(clearance 0)
		)
		(min_thickness 0.25)
		(keepout
			(tracks allowed)
			(vias allowed)
			(pads allowed)
			(copperpour allowed)
			(footprints allowed)
		)
		(placement
			(enabled no)
			(sheetname "")
		)
		(fill
			(thermal_gap 0.5)
			(thermal_bridge_width 0.5)
			(island_removal_mode 0)
		)
		(polygon
			(pts
				(xy 420.480998 -229.857554) (xy 420.480998 -228.502718) (xy 420.958264 -228.502718) (xy 420.958264 -229.857554)
			)
		)
	)
	(zone
		(layer "In4.Cu")
		(hatch none 0.5)
		(connect_pads
			(clearance 0)
		)
		(min_thickness 0.25)
		(keepout
			(tracks allowed)
			(vias allowed)
			(pads allowed)
			(copperpour allowed)
			(footprints allowed)
		)
		(placement
			(enabled no)
			(sheetname "")
		)
		(fill
			(thermal_gap 0.5)
			(thermal_bridge_width 0.5)
			(island_removal_mode 0)
		)
		(polygon
			(pts
				(xy 435.568598 -244.30736) (xy 435.568598 -242.952524) (xy 436.045864 -242.952524) (xy 436.045864 -244.30736)
			)
		)
	)
	(zone
		(layer "In4.Cu")
		(hatch none 0.5)
		(connect_pads
			(clearance 0)
		)
		(min_thickness 0.25)
		(keepout
			(tracks allowed)
			(vias allowed)
			(pads allowed)
			(copperpour allowed)
			(footprints allowed)
		)
		(placement
			(enabled no)
			(sheetname "")
		)
		(fill
			(thermal_gap 0.5)
			(thermal_bridge_width 0.5)
			(island_removal_mode 0)
		)
		(polygon
			(pts
				(xy 297.25112 -288.846768) (xy 297.25112 -285.918148) (xy 300.8757 -285.918148) (xy 300.8757 -288.846768)
			)
		)
	)
	(zone
		(layer "In4.Cu")
		(hatch none 0.5)
		(connect_pads
			(clearance 0)
		)
		(min_thickness 0.25)
		(keepout
			(tracks allowed)
			(vias allowed)
			(pads allowed)
			(copperpour allowed)
			(footprints allowed)
		)
		(placement
			(enabled no)
			(sheetname "")
		)
		(fill
			(thermal_gap 0.5)
			(thermal_bridge_width 0.5)
			(island_removal_mode 0)
		)
		(polygon
			(pts
				(xy 296.544492 -319.957704) (xy 296.544492 -318.602868) (xy 297.021758 -318.602868) (xy 297.021758 -319.957704)
			)
		)
	)
	(zone
		(layer "In4.Cu")
		(hatch none 0.5)
		(connect_pads
			(clearance 0)
		)
		(min_thickness 0.25)
		(keepout
			(tracks allowed)
			(vias allowed)
			(pads allowed)
			(copperpour allowed)
			(footprints allowed)
		)
		(placement
			(enabled no)
			(sheetname "")
		)
		(fill
			(thermal_gap 0.5)
			(thermal_bridge_width 0.5)
			(island_removal_mode 0)
		)
		(polygon
			(pts
				(xy 35.725862 -314.574936) (xy 35.725862 -313.2201) (xy 36.203128 -313.2201) (xy 36.203128 -314.574936)
			)
		)
	)
	(zone
		(layer "In4.Cu")
		(hatch none 0.5)
		(connect_pads
			(clearance 0)
		)
		(min_thickness 0.25)
		(keepout
			(tracks allowed)
			(vias allowed)
			(pads allowed)
			(copperpour allowed)
			(footprints allowed)
		)
		(placement
			(enabled no)
			(sheetname "")
		)
		(fill
			(thermal_gap 0.5)
			(thermal_bridge_width 0.5)
			(island_removal_mode 0)
		)
		(polygon
			(pts
				(xy 298.75607 -224.742756) (xy 298.75607 -223.38792) (xy 299.233336 -223.38792) (xy 299.233336 -224.742756)
			)
		)
	)
	(zone
		(layer "In4.Cu")
		(hatch none 0.5)
		(connect_pads
			(clearance 0)
		)
		(min_thickness 0.25)
		(keepout
			(tracks allowed)
			(vias allowed)
			(pads allowed)
			(copperpour allowed)
			(footprints allowed)
		)
		(placement
			(enabled no)
			(sheetname "")
		)
		(fill
			(thermal_gap 0.5)
			(thermal_bridge_width 0.5)
			(island_removal_mode 0)
		)
		(polygon
			(pts
				(xy 93.12656 -338.384388) (xy 93.12656 -335.234788) (xy 97.53854 -335.234788) (xy 97.53854 -338.384388)
			)
		)
	)
	(zone
		(layer "In4.Cu")
		(hatch none 0.5)
		(connect_pads
			(clearance 0)
		)
		(min_thickness 0.25)
		(keepout
			(tracks allowed)
			(vias allowed)
			(pads allowed)
			(copperpour allowed)
			(footprints allowed)
		)
		(placement
			(enabled no)
			(sheetname "")
		)
		(fill
			(thermal_gap 0.5)
			(thermal_bridge_width 0.5)
			(island_removal_mode 0)
		)
		(polygon
			(pts
				(xy 173.038008 -300.401736) (xy 172.560742 -300.401736) (xy 172.154596 -300.401736) (xy 172.154596 -299.814488)
				(xy 170.933618 -299.814488) (xy 170.933618 -298.321476) (xy 170.933618 -297.952922) (xy 171.045124 -297.841416)
				(xy 171.996862 -297.841416) (xy 173.26483 -297.841416) (xy 173.26483 -298.188634) (xy 173.26483 -298.678346)
				(xy 173.26483 -300.401736)
			)
		)
	)
	(zone
		(layer "In4.Cu")
		(hatch none 0.5)
		(connect_pads
			(clearance 0)
		)
		(min_thickness 0.25)
		(keepout
			(tracks allowed)
			(vias allowed)
			(pads allowed)
			(copperpour allowed)
			(footprints allowed)
		)
		(placement
			(enabled no)
			(sheetname "")
		)
		(fill
			(thermal_gap 0.5)
			(thermal_bridge_width 0.5)
			(island_removal_mode 0)
		)
		(polygon
			(pts
				(xy 52.060094 -318.943736) (xy 52.060094 -317.5889) (xy 52.53736 -317.5889) (xy 52.53736 -318.943736)
			)
		)
	)
	(zone
		(layer "In4.Cu")
		(hatch none 0.5)
		(connect_pads
			(clearance 0)
		)
		(min_thickness 0.25)
		(keepout
			(tracks allowed)
			(vias allowed)
			(pads allowed)
			(copperpour allowed)
			(footprints allowed)
		)
		(placement
			(enabled no)
			(sheetname "")
		)
		(fill
			(thermal_gap 0.5)
			(thermal_bridge_width 0.5)
			(island_removal_mode 0)
		)
		(polygon
			(pts
				(xy 50.835814 -300.619414) (xy 50.835814 -299.264578) (xy 51.31308 -299.264578) (xy 51.31308 -300.619414)
			)
		)
	)
	(zone
		(layer "In4.Cu")
		(hatch none 0.5)
		(connect_pads
			(clearance 0)
		)
		(min_thickness 0.25)
		(keepout
			(tracks allowed)
			(vias allowed)
			(pads allowed)
			(copperpour allowed)
			(footprints allowed)
		)
		(placement
			(enabled no)
			(sheetname "")
		)
		(fill
			(thermal_gap 0.5)
			(thermal_bridge_width 0.5)
			(island_removal_mode 0)
		)
		(polygon
			(pts
				(xy 435.558692 -314.970922) (xy 435.558692 -313.616086) (xy 436.035958 -313.616086) (xy 436.035958 -314.970922)
			)
		)
	)
	(zone
		(layer "In4.Cu")
		(hatch none 0.5)
		(connect_pads
			(clearance 0)
		)
		(min_thickness 0.25)
		(keepout
			(tracks allowed)
			(vias allowed)
			(pads allowed)
			(copperpour allowed)
			(footprints allowed)
		)
		(placement
			(enabled no)
			(sheetname "")
		)
		(fill
			(thermal_gap 0.5)
			(thermal_bridge_width 0.5)
			(island_removal_mode 0)
		)
		(polygon
			(pts
				(xy 31.635954 -244.315234) (xy 31.635954 -242.960398) (xy 32.11322 -242.960398) (xy 32.11322 -244.315234)
			)
		)
	)
	(zone
		(layer "In4.Cu")
		(hatch none 0.5)
		(connect_pads
			(clearance 0)
		)
		(min_thickness 0.25)
		(keepout
			(tracks allowed)
			(vias allowed)
			(pads allowed)
			(copperpour allowed)
			(footprints allowed)
		)
		(placement
			(enabled no)
			(sheetname "")
		)
		(fill
			(thermal_gap 0.5)
			(thermal_bridge_width 0.5)
			(island_removal_mode 0)
		)
		(polygon
			(pts
				(xy 43.169332 -244.235478) (xy 43.169332 -242.909598) (xy 43.707812 -242.909598) (xy 43.707812 -244.235478)
			)
		)
	)
	(zone
		(layer "In4.Cu")
		(hatch none 0.5)
		(connect_pads
			(clearance 0)
		)
		(min_thickness 0.25)
		(keepout
			(tracks allowed)
			(vias allowed)
			(pads allowed)
			(copperpour allowed)
			(footprints allowed)
		)
		(placement
			(enabled no)
			(sheetname "")
		)
		(fill
			(thermal_gap 0.5)
			(thermal_bridge_width 0.5)
			(island_removal_mode 0)
		)
		(polygon
			(pts
				(xy 439.688478 -268.101572) (xy 439.688478 -266.746736) (xy 440.165744 -266.746736) (xy 440.165744 -268.101572)
			)
		)
	)
	(zone
		(layer "In4.Cu")
		(hatch none 0.5)
		(connect_pads
			(clearance 0)
		)
		(min_thickness 0.25)
		(keepout
			(tracks allowed)
			(vias allowed)
			(pads allowed)
			(copperpour allowed)
			(footprints allowed)
		)
		(placement
			(enabled no)
			(sheetname "")
		)
		(fill
			(thermal_gap 0.5)
			(thermal_bridge_width 0.5)
			(island_removal_mode 0)
		)
		(polygon
			(pts
				(xy 35.732974 -248.636536) (xy 35.732974 -248.01195) (xy 36.21024 -248.01195) (xy 36.51631 -248.01195)
				(xy 36.588192 -248.083832) (xy 36.588192 -248.550938) (xy 36.502594 -248.636536) (xy 36.21024 -248.636536)
			)
		)
	)
	(zone
		(layer "In4.Cu")
		(hatch none 0.5)
		(connect_pads
			(clearance 0)
		)
		(min_thickness 0.25)
		(keepout
			(tracks allowed)
			(vias allowed)
			(pads allowed)
			(copperpour allowed)
			(footprints allowed)
		)
		(placement
			(enabled no)
			(sheetname "")
		)
		(fill
			(thermal_gap 0.5)
			(thermal_bridge_width 0.5)
			(island_removal_mode 0)
		)
		(polygon
			(pts
				(xy 172.560742 -204.351636) (xy 172.560742 -202.9968) (xy 173.038008 -202.9968) (xy 173.038008 -204.351636)
			)
		)
	)
	(zone
		(layer "In4.Cu")
		(hatch none 0.5)
		(connect_pads
			(clearance 0)
		)
		(min_thickness 0.25)
		(keepout
			(tracks allowed)
			(vias allowed)
			(pads allowed)
			(copperpour allowed)
			(footprints allowed)
		)
		(placement
			(enabled no)
			(sheetname "")
		)
		(fill
			(thermal_gap 0.5)
			(thermal_bridge_width 0.5)
			(island_removal_mode 0)
		)
		(polygon
			(pts
				(xy 420.480998 -206.0575) (xy 420.480998 -204.702664) (xy 420.958264 -204.702664) (xy 420.958264 -206.0575)
				(xy 420.958264 -206.547212) (xy 420.480998 -206.547212)
			)
		)
	)
	(zone
		(layer "In4.Cu")
		(hatch none 0.5)
		(connect_pads
			(clearance 0)
		)
		(min_thickness 0.25)
		(keepout
			(tracks allowed)
			(vias allowed)
			(pads allowed)
			(copperpour allowed)
			(footprints allowed)
		)
		(placement
			(enabled no)
			(sheetname "")
		)
		(fill
			(thermal_gap 0.5)
			(thermal_bridge_width 0.5)
			(island_removal_mode 0)
		)
		(polygon
			(pts
				(xy 294.65778 -318.313054) (xy 294.65778 -316.051438) (xy 295.1988 -316.051438) (xy 295.1988 -318.313054)
			)
		)
	)
	(zone
		(layer "In4.Cu")
		(hatch none 0.5)
		(connect_pads
			(clearance 0)
		)
		(min_thickness 0.25)
		(keepout
			(tracks allowed)
			(vias allowed)
			(pads allowed)
			(copperpour allowed)
			(footprints allowed)
		)
		(placement
			(enabled no)
			(sheetname "")
		)
		(fill
			(thermal_gap 0.5)
			(thermal_bridge_width 0.5)
			(island_removal_mode 0)
		)
		(polygon
			(pts
				(xy 283.65323 -315.994796) (xy 283.65323 -314.63996) (xy 284.130496 -314.63996) (xy 284.130496 -315.994796)
			)
		)
	)
	(zone
		(layer "In4.Cu")
		(hatch none 0.5)
		(connect_pads
			(clearance 0)
		)
		(min_thickness 0.25)
		(keepout
			(tracks allowed)
			(vias allowed)
			(pads allowed)
			(copperpour allowed)
			(footprints allowed)
		)
		(placement
			(enabled no)
			(sheetname "")
		)
		(fill
			(thermal_gap 0.5)
			(thermal_bridge_width 0.5)
			(island_removal_mode 0)
		)
		(polygon
			(pts
				(xy 35.713162 -239.340136) (xy 35.713162 -237.9853) (xy 36.190428 -237.9853) (xy 36.190428 -239.340136)
			)
		)
	)
	(zone
		(layer "In4.Cu")
		(hatch none 0.5)
		(connect_pads
			(clearance 0)
		)
		(min_thickness 0.25)
		(keepout
			(tracks allowed)
			(vias allowed)
			(pads allowed)
			(copperpour allowed)
			(footprints allowed)
		)
		(placement
			(enabled no)
			(sheetname "")
		)
		(fill
			(thermal_gap 0.5)
			(thermal_bridge_width 0.5)
			(island_removal_mode 0)
		)
		(polygon
			(pts
				(xy 187.648342 -246.00154) (xy 187.648342 -244.646704) (xy 188.125608 -244.646704) (xy 188.125608 -246.00154)
			)
		)
	)
	(zone
		(layer "In4.Cu")
		(hatch none 0.5)
		(connect_pads
			(clearance 0)
		)
		(min_thickness 0.25)
		(keepout
			(tracks allowed)
			(vias allowed)
			(pads allowed)
			(copperpour allowed)
			(footprints allowed)
		)
		(placement
			(enabled no)
			(sheetname "")
		)
		(fill
			(thermal_gap 0.5)
			(thermal_bridge_width 0.5)
			(island_removal_mode 0)
		)
		(polygon
			(pts
				(xy 50.835814 -205.186534) (xy 50.835814 -203.831698) (xy 51.31308 -203.831698) (xy 51.31308 -205.186534)
			)
		)
	)
	(zone
		(layer "In4.Cu")
		(hatch none 0.5)
		(connect_pads
			(clearance 0)
		)
		(min_thickness 0.25)
		(keepout
			(tracks allowed)
			(vias allowed)
			(pads allowed)
			(copperpour allowed)
			(footprints allowed)
		)
		(placement
			(enabled no)
			(sheetname "")
		)
		(fill
			(thermal_gap 0.5)
			(thermal_bridge_width 0.5)
			(island_removal_mode 0)
		)
		(polygon
			(pts
				(xy 435.568598 -247.707404) (xy 435.568598 -246.352568) (xy 436.045864 -246.352568) (xy 436.045864 -247.707404)
			)
		)
	)
	(zone
		(layer "In4.Cu")
		(hatch none 0.5)
		(connect_pads
			(clearance 0)
		)
		(min_thickness 0.25)
		(keepout
			(tracks allowed)
			(vias allowed)
			(pads allowed)
			(copperpour allowed)
			(footprints allowed)
		)
		(placement
			(enabled no)
			(sheetname "")
		)
		(fill
			(thermal_gap 0.5)
			(thermal_bridge_width 0.5)
			(island_removal_mode 0)
		)
		(polygon
			(pts
				(xy 435.601364 -309.7276) (xy 435.601364 -308.372764) (xy 436.07863 -308.372764) (xy 436.07863 -309.7276)
			)
		)
	)
	(zone
		(layer "In4.Cu")
		(hatch none 0.5)
		(connect_pads
			(clearance 0)
		)
		(min_thickness 0.25)
		(keepout
			(tracks allowed)
			(vias allowed)
			(pads allowed)
			(copperpour allowed)
			(footprints allowed)
		)
		(placement
			(enabled no)
			(sheetname "")
		)
		(fill
			(thermal_gap 0.5)
			(thermal_bridge_width 0.5)
			(island_removal_mode 0)
		)
		(polygon
			(pts
				(xy 112.820958 -357.879904) (xy 112.820958 -356.198424) (xy 113.979706 -356.198424) (xy 113.979706 -357.879904)
			)
		)
	)
	(zone
		(layer "In4.Cu")
		(hatch none 0.5)
		(connect_pads
			(clearance 0)
		)
		(min_thickness 0.25)
		(keepout
			(tracks allowed)
			(vias allowed)
			(pads allowed)
			(copperpour allowed)
			(footprints allowed)
		)
		(placement
			(enabled no)
			(sheetname "")
		)
		(fill
			(thermal_gap 0.5)
			(thermal_bridge_width 0.5)
			(island_removal_mode 0)
		)
		(polygon
			(pts
				(xy 43.319192 -261.233158) (xy 43.319192 -258.279138) (xy 43.674792 -258.279138) (xy 43.674792 -261.233158)
			)
		)
	)
	(zone
		(layer "In4.Cu")
		(hatch none 0.5)
		(connect_pads
			(clearance 0)
		)
		(min_thickness 0.25)
		(keepout
			(tracks allowed)
			(vias allowed)
			(pads allowed)
			(copperpour allowed)
			(footprints allowed)
		)
		(placement
			(enabled no)
			(sheetname "")
		)
		(fill
			(thermal_gap 0.5)
			(thermal_bridge_width 0.5)
			(island_removal_mode 0)
		)
		(polygon
			(pts
				(xy 35.713162 -298.722796) (xy 35.713162 -297.36796) (xy 36.190428 -297.36796) (xy 36.190428 -298.722796)
			)
		)
	)
	(zone
		(layer "In4.Cu")
		(hatch none 0.5)
		(connect_pads
			(clearance 0)
		)
		(min_thickness 0.25)
		(keepout
			(tracks allowed)
			(vias allowed)
			(pads allowed)
			(copperpour allowed)
			(footprints allowed)
		)
		(placement
			(enabled no)
			(sheetname "")
		)
		(fill
			(thermal_gap 0.5)
			(thermal_bridge_width 0.5)
			(island_removal_mode 0)
		)
		(polygon
			(pts
				(xy 283.685742 -295.564814) (xy 283.685742 -294.209978) (xy 284.163008 -294.209978) (xy 284.163008 -295.564814)
			)
		)
	)
	(zone
		(layer "In4.Cu")
		(hatch none 0.5)
		(connect_pads
			(clearance 0)
		)
		(min_thickness 0.25)
		(keepout
			(tracks allowed)
			(vias allowed)
			(pads allowed)
			(copperpour allowed)
			(footprints allowed)
		)
		(placement
			(enabled no)
			(sheetname "")
		)
		(fill
			(thermal_gap 0.5)
			(thermal_bridge_width 0.5)
			(island_removal_mode 0)
		)
		(polygon
			(pts
				(xy 283.67355 -212.835236) (xy 283.67355 -211.4804) (xy 284.150816 -211.4804) (xy 284.150816 -212.835236)
			)
		)
	)
	(zone
		(layer "In4.Cu")
		(hatch none 0.5)
		(connect_pads
			(clearance 0)
		)
		(min_thickness 0.25)
		(keepout
			(tracks allowed)
			(vias allowed)
			(pads allowed)
			(copperpour allowed)
			(footprints allowed)
		)
		(placement
			(enabled no)
			(sheetname "")
		)
		(fill
			(thermal_gap 0.5)
			(thermal_bridge_width 0.5)
			(island_removal_mode 0)
		)
		(polygon
			(pts
				(xy 435.58841 -267.251688) (xy 435.58841 -265.896852) (xy 436.065676 -265.896852) (xy 436.065676 -267.251688)
			)
		)
	)
	(zone
		(layer "In4.Cu")
		(hatch none 0.5)
		(connect_pads
			(clearance 0)
		)
		(min_thickness 0.25)
		(keepout
			(tracks allowed)
			(vias allowed)
			(pads allowed)
			(copperpour allowed)
			(footprints allowed)
		)
		(placement
			(enabled no)
			(sheetname "")
		)
		(fill
			(thermal_gap 0.5)
			(thermal_bridge_width 0.5)
			(island_removal_mode 0)
		)
		(polygon
			(pts
				(xy 435.568598 -252.80747) (xy 435.568598 -251.452634) (xy 436.045864 -251.452634) (xy 436.045864 -252.80747)
			)
		)
	)
	(zone
		(layer "In4.Cu")
		(hatch none 0.5)
		(connect_pads
			(clearance 0)
		)
		(min_thickness 0.25)
		(keepout
			(tracks allowed)
			(vias allowed)
			(pads allowed)
			(copperpour allowed)
			(footprints allowed)
		)
		(placement
			(enabled no)
			(sheetname "")
		)
		(fill
			(thermal_gap 0.5)
			(thermal_bridge_width 0.5)
			(island_removal_mode 0)
		)
		(polygon
			(pts
				(xy 59.622944 -318.204596) (xy 59.622944 -316.906656) (xy 60.128404 -316.906656) (xy 60.128404 -318.204596)
			)
		)
	)
	(zone
		(layer "In4.Cu")
		(hatch none 0.5)
		(connect_pads
			(clearance 0)
		)
		(min_thickness 0.25)
		(keepout
			(tracks allowed)
			(vias allowed)
			(pads allowed)
			(copperpour allowed)
			(footprints allowed)
		)
		(placement
			(enabled no)
			(sheetname "")
		)
		(fill
			(thermal_gap 0.5)
			(thermal_bridge_width 0.5)
			(island_removal_mode 0)
		)
		(polygon
			(pts
				(xy 172.54093 -272.357596) (xy 172.54093 -271.00276) (xy 173.018196 -271.00276) (xy 173.018196 -272.357596)
			)
		)
	)
	(zone
		(layer "In4.Cu")
		(hatch none 0.5)
		(connect_pads
			(clearance 0)
		)
		(min_thickness 0.25)
		(keepout
			(tracks allowed)
			(vias allowed)
			(pads allowed)
			(copperpour allowed)
			(footprints allowed)
		)
		(placement
			(enabled no)
			(sheetname "")
		)
		(fill
			(thermal_gap 0.5)
			(thermal_bridge_width 0.5)
			(island_removal_mode 0)
		)
		(polygon
			(pts
				(xy 187.648342 -265.551666) (xy 187.648342 -264.19683) (xy 188.125608 -264.19683) (xy 188.125608 -265.551666)
			)
		)
	)
	(zone
		(layer "In4.Cu")
		(hatch none 0.5)
		(connect_pads
			(clearance 0)
		)
		(min_thickness 0.25)
		(keepout
			(tracks allowed)
			(vias allowed)
			(pads allowed)
			(copperpour allowed)
			(footprints allowed)
		)
		(placement
			(enabled no)
			(sheetname "")
		)
		(fill
			(thermal_gap 0.5)
			(thermal_bridge_width 0.5)
			(island_removal_mode 0)
		)
		(polygon
			(pts
				(xy 283.65323 -248.642378) (xy 283.65323 -248.017792) (xy 284.130496 -248.017792) (xy 284.436566 -248.017792)
				(xy 284.508448 -248.089674) (xy 284.508448 -248.55678) (xy 284.42285 -248.642378) (xy 284.130496 -248.642378)
			)
		)
	)
	(zone
		(layer "In4.Cu")
		(hatch none 0.5)
		(connect_pads
			(clearance 0)
		)
		(min_thickness 0.25)
		(keepout
			(tracks allowed)
			(vias allowed)
			(pads allowed)
			(copperpour allowed)
			(footprints allowed)
		)
		(placement
			(enabled no)
			(sheetname "")
		)
		(fill
			(thermal_gap 0.5)
			(thermal_bridge_width 0.5)
			(island_removal_mode 0)
		)
		(polygon
			(pts
				(xy 435.578504 -314.96508) (xy 435.578504 -313.610244) (xy 436.05577 -313.610244) (xy 436.05577 -314.96508)
			)
		)
	)
	(zone
		(layer "In4.Cu")
		(hatch none 0.5)
		(connect_pads
			(clearance 0)
		)
		(min_thickness 0.25)
		(keepout
			(tracks allowed)
			(vias allowed)
			(pads allowed)
			(copperpour allowed)
			(footprints allowed)
		)
		(placement
			(enabled no)
			(sheetname "")
		)
		(fill
			(thermal_gap 0.5)
			(thermal_bridge_width 0.5)
			(island_removal_mode 0)
		)
		(polygon
			(pts
				(xy 439.688478 -246.00154) (xy 439.688478 -244.646704) (xy 440.165744 -244.646704) (xy 440.165744 -246.00154)
			)
		)
	)
	(zone
		(layer "In4.Cu")
		(hatch none 0.5)
		(connect_pads
			(clearance 0)
		)
		(min_thickness 0.25)
		(keepout
			(tracks allowed)
			(vias allowed)
			(pads allowed)
			(copperpour allowed)
			(footprints allowed)
		)
		(placement
			(enabled no)
			(sheetname "")
		)
		(fill
			(thermal_gap 0.5)
			(thermal_bridge_width 0.5)
			(island_removal_mode 0)
		)
		(polygon
			(pts
				(xy 435.58841 -246.00154) (xy 435.58841 -244.646704) (xy 436.065676 -244.646704) (xy 436.065676 -246.00154)
			)
		)
	)
	(zone
		(layer "In4.Cu")
		(hatch none 0.5)
		(connect_pads
			(clearance 0)
		)
		(min_thickness 0.25)
		(keepout
			(tracks allowed)
			(vias allowed)
			(pads allowed)
			(copperpour allowed)
			(footprints allowed)
		)
		(placement
			(enabled no)
			(sheetname "")
		)
		(fill
			(thermal_gap 0.5)
			(thermal_bridge_width 0.5)
			(island_removal_mode 0)
		)
		(polygon
			(pts
				(xy 50.835814 -200.977754) (xy 50.835814 -199.622918) (xy 51.31308 -199.622918) (xy 51.31308 -200.977754)
				(xy 51.31308 -201.878692) (xy 50.835814 -201.878692)
			)
		)
	)
	(zone
		(layer "In4.Cu")
		(hatch none 0.5)
		(connect_pads
			(clearance 0)
		)
		(min_thickness 0.25)
		(keepout
			(tracks allowed)
			(vias allowed)
			(pads allowed)
			(copperpour allowed)
			(footprints allowed)
		)
		(placement
			(enabled no)
			(sheetname "")
		)
		(fill
			(thermal_gap 0.5)
			(thermal_bridge_width 0.5)
			(island_removal_mode 0)
		)
		(polygon
			(pts
				(xy 180.4543 -358.206548) (xy 180.4543 -356.931468) (xy 182.08244 -356.931468) (xy 182.08244 -358.206548)
			)
		)
	)
	(zone
		(layer "In4.Cu")
		(hatch none 0.5)
		(connect_pads
			(clearance 0)
		)
		(min_thickness 0.25)
		(keepout
			(tracks allowed)
			(vias allowed)
			(pads allowed)
			(copperpour allowed)
			(footprints allowed)
		)
		(placement
			(enabled no)
			(sheetname "")
		)
		(fill
			(thermal_gap 0.5)
			(thermal_bridge_width 0.5)
			(island_removal_mode 0)
		)
		(polygon
			(pts
				(xy 313.87796 -306.701698) (xy 313.87796 -305.002438) (xy 314.2615 -305.002438) (xy 314.2615 -306.701698)
			)
		)
	)
	(zone
		(layer "In4.Cu")
		(hatch none 0.5)
		(connect_pads
			(clearance 0)
		)
		(min_thickness 0.25)
		(keepout
			(tracks allowed)
			(vias allowed)
			(pads allowed)
			(copperpour allowed)
			(footprints allowed)
		)
		(placement
			(enabled no)
			(sheetname "")
		)
		(fill
			(thermal_gap 0.5)
			(thermal_bridge_width 0.5)
			(island_removal_mode 0)
		)
		(polygon
			(pts
				(xy 435.601872 -311.465722) (xy 435.601872 -310.110886) (xy 436.079138 -310.110886) (xy 436.079138 -311.465722)
			)
		)
	)
	(zone
		(layer "In4.Cu")
		(hatch none 0.5)
		(connect_pads
			(clearance 0)
		)
		(min_thickness 0.25)
		(keepout
			(tracks allowed)
			(vias allowed)
			(pads allowed)
			(copperpour allowed)
			(footprints allowed)
		)
		(placement
			(enabled no)
			(sheetname "")
		)
		(fill
			(thermal_gap 0.5)
			(thermal_bridge_width 0.5)
			(island_removal_mode 0)
		)
		(polygon
			(pts
				(xy 297.48226 -232.463848) (xy 297.48226 -229.611428) (xy 301.879 -229.611428) (xy 301.879 -232.463848)
			)
		)
	)
	(zone
		(layer "In4.Cu")
		(hatch none 0.5)
		(connect_pads
			(clearance 0)
		)
		(min_thickness 0.25)
		(keepout
			(tracks allowed)
			(vias allowed)
			(pads allowed)
			(copperpour allowed)
			(footprints allowed)
		)
		(placement
			(enabled no)
			(sheetname "")
		)
		(fill
			(thermal_gap 0.5)
			(thermal_bridge_width 0.5)
			(island_removal_mode 0)
		)
		(polygon
			(pts
				(xy 157.447742 -305.501548) (xy 157.447742 -304.146712) (xy 157.447742 -303.420526) (xy 157.925008 -303.420526)
				(xy 157.925008 -304.146712) (xy 157.925008 -305.501548)
			)
		)
	)
	(zone
		(layer "In4.Cu")
		(hatch none 0.5)
		(connect_pads
			(clearance 0)
		)
		(min_thickness 0.25)
		(keepout
			(tracks allowed)
			(vias allowed)
			(pads allowed)
			(copperpour allowed)
			(footprints allowed)
		)
		(placement
			(enabled no)
			(sheetname "")
		)
		(fill
			(thermal_gap 0.5)
			(thermal_bridge_width 0.5)
			(island_removal_mode 0)
		)
		(polygon
			(pts
				(xy 153.25344 -10.94994) (xy 153.25344 -9.68756) (xy 154.08402 -9.68756) (xy 154.08402 -10.94994)
			)
		)
	)
	(zone
		(layer "In4.Cu")
		(hatch none 0.5)
		(connect_pads
			(clearance 0)
		)
		(min_thickness 0.25)
		(keepout
			(tracks allowed)
			(vias allowed)
			(pads allowed)
			(copperpour allowed)
			(footprints allowed)
		)
		(placement
			(enabled no)
			(sheetname "")
		)
		(fill
			(thermal_gap 0.5)
			(thermal_bridge_width 0.5)
			(island_removal_mode 0)
		)
		(polygon
			(pts
				(xy 283.685742 -313.156854) (xy 283.685742 -311.802018) (xy 284.163008 -311.802018) (xy 284.163008 -313.156854)
			)
		)
	)
	(zone
		(layer "In4.Cu")
		(hatch none 0.5)
		(connect_pads
			(clearance 0)
		)
		(min_thickness 0.25)
		(keepout
			(tracks allowed)
			(vias allowed)
			(pads allowed)
			(copperpour allowed)
			(footprints allowed)
		)
		(placement
			(enabled no)
			(sheetname "")
		)
		(fill
			(thermal_gap 0.5)
			(thermal_bridge_width 0.5)
			(island_removal_mode 0)
		)
		(polygon
			(pts
				(xy 435.58841 -237.491778) (xy 435.58841 -235.29671) (xy 436.065676 -235.29671) (xy 436.065676 -237.491778)
			)
		)
	)
	(zone
		(layer "In4.Cu")
		(hatch none 0.5)
		(connect_pads
			(clearance 0)
		)
		(min_thickness 0.25)
		(keepout
			(tracks allowed)
			(vias allowed)
			(pads allowed)
			(copperpour allowed)
			(footprints allowed)
		)
		(placement
			(enabled no)
			(sheetname "")
		)
		(fill
			(thermal_gap 0.5)
			(thermal_bridge_width 0.5)
			(island_removal_mode 0)
		)
		(polygon
			(pts
				(xy 177.138076 -287.147) (xy 177.138076 -288.501836) (xy 176.66081 -288.501836) (xy 176.493424 -288.501836)
				(xy 176.001172 -288.501836) (xy 176.001172 -286.813498) (xy 177.138076 -286.813498)
			)
		)
	)
	(zone
		(layer "In4.Cu")
		(hatch none 0.5)
		(connect_pads
			(clearance 0)
		)
		(min_thickness 0.25)
		(keepout
			(tracks allowed)
			(vias allowed)
			(pads allowed)
			(copperpour allowed)
			(footprints allowed)
		)
		(placement
			(enabled no)
			(sheetname "")
		)
		(fill
			(thermal_gap 0.5)
			(thermal_bridge_width 0.5)
			(island_removal_mode 0)
		)
		(polygon
			(pts
				(xy 50.727864 -317.419736) (xy 50.727864 -316.111636) (xy 51.327304 -316.111636) (xy 51.327304 -317.419736)
			)
		)
	)
	(zone
		(layer "In4.Cu")
		(hatch none 0.5)
		(connect_pads
			(clearance 0)
		)
		(min_thickness 0.25)
		(keepout
			(tracks allowed)
			(vias allowed)
			(pads allowed)
			(copperpour allowed)
			(footprints allowed)
		)
		(placement
			(enabled no)
			(sheetname "")
		)
		(fill
			(thermal_gap 0.5)
			(thermal_bridge_width 0.5)
			(island_removal_mode 0)
		)
		(polygon
			(pts
				(xy 284.875224 -319.10782) (xy 284.875224 -317.752984) (xy 285.35249 -317.752984) (xy 285.35249 -319.10782)
			)
		)
	)
	(zone
		(layer "In4.Cu")
		(hatch none 0.5)
		(connect_pads
			(clearance 0)
		)
		(min_thickness 0.25)
		(keepout
			(tracks allowed)
			(vias allowed)
			(pads allowed)
			(copperpour allowed)
			(footprints allowed)
		)
		(placement
			(enabled no)
			(sheetname "")
		)
		(fill
			(thermal_gap 0.5)
			(thermal_bridge_width 0.5)
			(island_removal_mode 0)
		)
		(polygon
			(pts
				(xy 63.697612 -244.403118) (xy 63.697612 -241.314478) (xy 64.091312 -241.314478) (xy 64.091312 -244.403118)
			)
		)
	)
	(zone
		(layer "In4.Cu")
		(hatch none 0.5)
		(connect_pads
			(clearance 0)
		)
		(min_thickness 0.25)
		(keepout
			(tracks allowed)
			(vias allowed)
			(pads allowed)
			(copperpour allowed)
			(footprints allowed)
		)
		(placement
			(enabled no)
			(sheetname "")
		)
		(fill
			(thermal_gap 0.5)
			(thermal_bridge_width 0.5)
			(island_removal_mode 0)
		)
		(polygon
			(pts
				(xy 435.58841 -209.451702) (xy 435.58841 -207.291178) (xy 436.065676 -207.291178) (xy 436.065676 -209.451702)
			)
		)
	)
	(zone
		(layer "In4.Cu")
		(hatch none 0.5)
		(connect_pads
			(clearance 0)
		)
		(min_thickness 0.25)
		(keepout
			(tracks allowed)
			(vias allowed)
			(pads allowed)
			(copperpour allowed)
			(footprints allowed)
		)
		(placement
			(enabled no)
			(sheetname "")
		)
		(fill
			(thermal_gap 0.5)
			(thermal_bridge_width 0.5)
			(island_removal_mode 0)
		)
		(polygon
			(pts
				(xy 187.62853 -206.907384) (xy 187.62853 -205.552548) (xy 188.105796 -205.552548) (xy 188.105796 -206.907384)
			)
		)
	)
	(zone
		(layer "In4.Cu")
		(hatch none 0.5)
		(connect_pads
			(clearance 0)
		)
		(min_thickness 0.25)
		(keepout
			(tracks allowed)
			(vias allowed)
			(pads allowed)
			(copperpour allowed)
			(footprints allowed)
		)
		(placement
			(enabled no)
			(sheetname "")
		)
		(fill
			(thermal_gap 0.5)
			(thermal_bridge_width 0.5)
			(island_removal_mode 0)
		)
		(polygon
			(pts
				(xy 172.560742 -284.251654) (xy 172.560742 -282.086558) (xy 173.038008 -282.086558) (xy 173.038008 -284.251654)
			)
		)
	)
	(zone
		(layer "In4.Cu")
		(hatch none 0.5)
		(connect_pads
			(clearance 0)
		)
		(min_thickness 0.25)
		(keepout
			(tracks allowed)
			(vias allowed)
			(pads allowed)
			(copperpour allowed)
			(footprints allowed)
		)
		(placement
			(enabled no)
			(sheetname "")
		)
		(fill
			(thermal_gap 0.5)
			(thermal_bridge_width 0.5)
			(island_removal_mode 0)
		)
		(polygon
			(pts
				(xy 187.62853 -211.157566) (xy 187.62853 -209.80273) (xy 188.105796 -209.80273) (xy 188.105796 -211.157566)
			)
		)
	)
	(zone
		(layer "In4.Cu")
		(hatch none 0.5)
		(connect_pads
			(clearance 0)
		)
		(min_thickness 0.25)
		(keepout
			(tracks allowed)
			(vias allowed)
			(pads allowed)
			(copperpour allowed)
			(footprints allowed)
		)
		(placement
			(enabled no)
			(sheetname "")
		)
		(fill
			(thermal_gap 0.5)
			(thermal_bridge_width 0.5)
			(island_removal_mode 0)
		)
		(polygon
			(pts
				(xy 35.732974 -298.716954) (xy 35.732974 -297.362118) (xy 36.21024 -297.362118) (xy 36.21024 -298.716954)
			)
		)
	)
	(zone
		(layer "In4.Cu")
		(hatch none 0.5)
		(connect_pads
			(clearance 0)
		)
		(min_thickness 0.25)
		(keepout
			(tracks allowed)
			(vias allowed)
			(pads allowed)
			(copperpour allowed)
			(footprints allowed)
		)
		(placement
			(enabled no)
			(sheetname "")
		)
		(fill
			(thermal_gap 0.5)
			(thermal_bridge_width 0.5)
			(island_removal_mode 0)
		)
		(polygon
			(pts
				(xy 285.48838 -27.83078) (xy 285.48838 -26.20518) (xy 284.25902 -26.20518) (xy 284.25902 -27.83078)
			)
		)
	)
	(zone
		(layer "In4.Cu")
		(hatch none 0.5)
		(connect_pads
			(clearance 0)
		)
		(min_thickness 0.25)
		(keepout
			(tracks allowed)
			(vias allowed)
			(pads allowed)
			(copperpour allowed)
			(footprints allowed)
		)
		(placement
			(enabled no)
			(sheetname "")
		)
		(fill
			(thermal_gap 0.5)
			(thermal_bridge_width 0.5)
			(island_removal_mode 0)
		)
		(polygon
			(pts
				(xy 435.568598 -234.957366) (xy 435.568598 -233.60253) (xy 436.045864 -233.60253) (xy 436.045864 -234.957366)
			)
		)
	)
	(zone
		(layer "In4.Cu")
		(hatch none 0.5)
		(connect_pads
			(clearance 0)
		)
		(min_thickness 0.25)
		(keepout
			(tracks allowed)
			(vias allowed)
			(pads allowed)
			(copperpour allowed)
			(footprints allowed)
		)
		(placement
			(enabled no)
			(sheetname "")
		)
		(fill
			(thermal_gap 0.5)
			(thermal_bridge_width 0.5)
			(island_removal_mode 0)
		)
		(polygon
			(pts
				(xy 435.58841 -247.701562) (xy 435.58841 -246.346726) (xy 436.065676 -246.346726) (xy 436.065676 -247.701562)
			)
		)
	)
	(zone
		(layer "In4.Cu")
		(hatch none 0.5)
		(connect_pads
			(clearance 0)
		)
		(min_thickness 0.25)
		(keepout
			(tracks allowed)
			(vias allowed)
			(pads allowed)
			(copperpour allowed)
			(footprints allowed)
		)
		(placement
			(enabled no)
			(sheetname "")
		)
		(fill
			(thermal_gap 0.5)
			(thermal_bridge_width 0.5)
			(island_removal_mode 0)
		)
		(polygon
			(pts
				(xy 35.682682 -290.216336) (xy 35.682682 -288.8615) (xy 36.159948 -288.8615) (xy 36.159948 -290.216336)
			)
		)
	)
	(zone
		(layer "In4.Cu")
		(hatch none 0.5)
		(connect_pads
			(clearance 0)
		)
		(min_thickness 0.25)
		(keepout
			(tracks allowed)
			(vias allowed)
			(pads allowed)
			(copperpour allowed)
			(footprints allowed)
		)
		(placement
			(enabled no)
			(sheetname "")
		)
		(fill
			(thermal_gap 0.5)
			(thermal_bridge_width 0.5)
			(island_removal_mode 0)
		)
		(polygon
			(pts
				(xy 187.681616 -311.45988) (xy 187.681616 -310.105044) (xy 188.158882 -310.105044) (xy 188.158882 -311.45988)
			)
		)
	)
	(zone
		(layer "In4.Cu")
		(hatch none 0.5)
		(connect_pads
			(clearance 0)
		)
		(min_thickness 0.25)
		(keepout
			(tracks allowed)
			(vias allowed)
			(pads allowed)
			(copperpour allowed)
			(footprints allowed)
		)
		(placement
			(enabled no)
			(sheetname "")
		)
		(fill
			(thermal_gap 0.5)
			(thermal_bridge_width 0.5)
			(island_removal_mode 0)
		)
		(polygon
			(pts
				(xy 50.793142 -203.546456) (xy 50.793142 -202.98791) (xy 51.270408 -202.98791) (xy 51.683666 -202.98791)
				(xy 51.753262 -203.057506) (xy 51.753262 -203.473558) (xy 51.680364 -203.546456) (xy 51.270408 -203.546456)
			)
		)
	)
	(zone
		(layer "In4.Cu")
		(hatch none 0.5)
		(connect_pads
			(clearance 0)
		)
		(min_thickness 0.25)
		(keepout
			(tracks allowed)
			(vias allowed)
			(pads allowed)
			(copperpour allowed)
			(footprints allowed)
		)
		(placement
			(enabled no)
			(sheetname "")
		)
		(fill
			(thermal_gap 0.5)
			(thermal_bridge_width 0.5)
			(island_removal_mode 0)
		)
		(polygon
			(pts
				(xy 35.745674 -313.156854) (xy 35.745674 -311.802018) (xy 36.22294 -311.802018) (xy 36.22294 -313.156854)
			)
		)
	)
	(zone
		(layer "In4.Cu")
		(hatch none 0.5)
		(connect_pads
			(clearance 0)
		)
		(min_thickness 0.25)
		(keepout
			(tracks allowed)
			(vias allowed)
			(pads allowed)
			(copperpour allowed)
			(footprints allowed)
		)
		(placement
			(enabled no)
			(sheetname "")
		)
		(fill
			(thermal_gap 0.5)
			(thermal_bridge_width 0.5)
			(island_removal_mode 0)
		)
		(polygon
			(pts
				(xy 187.648342 -297.851576) (xy 187.648342 -296.49674) (xy 188.125608 -296.49674) (xy 188.125608 -297.851576)
			)
		)
	)
	(zone
		(layer "In4.Cu")
		(hatch none 0.5)
		(connect_pads
			(clearance 0)
		)
		(min_thickness 0.25)
		(keepout
			(tracks allowed)
			(vias allowed)
			(pads allowed)
			(copperpour allowed)
			(footprints allowed)
		)
		(placement
			(enabled no)
			(sheetname "")
		)
		(fill
			(thermal_gap 0.5)
			(thermal_bridge_width 0.5)
			(island_removal_mode 0)
		)
		(polygon
			(pts
				(xy 161.517076 -306.73548) (xy 161.517076 -305.380644) (xy 161.994342 -305.380644) (xy 161.994342 -306.73548)
			)
		)
	)
	(zone
		(layer "In4.Cu")
		(hatch none 0.5)
		(connect_pads
			(clearance 0)
		)
		(min_thickness 0.25)
		(keepout
			(tracks allowed)
			(vias allowed)
			(pads allowed)
			(copperpour allowed)
			(footprints allowed)
		)
		(placement
			(enabled no)
			(sheetname "")
		)
		(fill
			(thermal_gap 0.5)
			(thermal_bridge_width 0.5)
			(island_removal_mode 0)
		)
		(polygon
			(pts
				(xy 279.55621 -244.321076) (xy 279.55621 -242.96624) (xy 280.033476 -242.96624) (xy 280.033476 -244.321076)
			)
		)
	)
	(zone
		(layer "In4.Cu")
		(hatch none 0.5)
		(connect_pads
			(clearance 0)
		)
		(min_thickness 0.25)
		(keepout
			(tracks allowed)
			(vias allowed)
			(pads allowed)
			(copperpour allowed)
			(footprints allowed)
		)
		(placement
			(enabled no)
			(sheetname "")
		)
		(fill
			(thermal_gap 0.5)
			(thermal_bridge_width 0.5)
			(island_removal_mode 0)
		)
		(polygon
			(pts
				(xy 420.50081 -284.251654) (xy 420.50081 -282.086558) (xy 420.978076 -282.086558) (xy 420.978076 -284.251654)
			)
		)
	)
	(zone
		(layer "In4.Cu")
		(hatch none 0.5)
		(connect_pads
			(clearance 0)
		)
		(min_thickness 0.25)
		(keepout
			(tracks allowed)
			(vias allowed)
			(pads allowed)
			(copperpour allowed)
			(footprints allowed)
		)
		(placement
			(enabled no)
			(sheetname "")
		)
		(fill
			(thermal_gap 0.5)
			(thermal_bridge_width 0.5)
			(island_removal_mode 0)
		)
		(polygon
			(pts
				(xy 420.480998 -202.657456) (xy 420.480998 -200.41616) (xy 420.958264 -200.41616) (xy 420.958264 -202.657456)
			)
		)
	)
	(zone
		(layer "In4.Cu")
		(hatch none 0.5)
		(connect_pads
			(clearance 0)
		)
		(min_thickness 0.25)
		(keepout
			(tracks allowed)
			(vias allowed)
			(pads allowed)
			(copperpour allowed)
			(footprints allowed)
		)
		(placement
			(enabled no)
			(sheetname "")
		)
		(fill
			(thermal_gap 0.5)
			(thermal_bridge_width 0.5)
			(island_removal_mode 0)
		)
		(polygon
			(pts
				(xy 298.64812 -317.425578) (xy 298.64812 -316.117478) (xy 299.24756 -316.117478) (xy 299.24756 -317.425578)
			)
		)
	)
	(zone
		(layer "In4.Cu")
		(hatch none 0.5)
		(connect_pads
			(clearance 0)
		)
		(min_thickness 0.25)
		(keepout
			(tracks allowed)
			(vias allowed)
			(pads allowed)
			(copperpour allowed)
			(footprints allowed)
		)
		(placement
			(enabled no)
			(sheetname "")
		)
		(fill
			(thermal_gap 0.5)
			(thermal_bridge_width 0.5)
			(island_removal_mode 0)
		)
		(polygon
			(pts
				(xy 298.722542 -197.576694) (xy 298.722542 -196.221858) (xy 299.199808 -196.221858) (xy 299.199808 -197.576694)
			)
		)
	)
	(zone
		(layer "In4.Cu")
		(hatch none 0.5)
		(connect_pads
			(clearance 0)
		)
		(min_thickness 0.25)
		(keepout
			(tracks allowed)
			(vias allowed)
			(pads allowed)
			(copperpour allowed)
			(footprints allowed)
		)
		(placement
			(enabled no)
			(sheetname "")
		)
		(fill
			(thermal_gap 0.5)
			(thermal_bridge_width 0.5)
			(island_removal_mode 0)
		)
		(polygon
			(pts
				(xy 291.197792 -317.297816) (xy 291.197792 -316.177676) (xy 291.759132 -316.177676) (xy 291.759132 -317.297816)
			)
		)
	)
	(zone
		(layer "In4.Cu")
		(hatch none 0.5)
		(connect_pads
			(clearance 0)
		)
		(min_thickness 0.25)
		(keepout
			(tracks allowed)
			(vias allowed)
			(pads allowed)
			(copperpour allowed)
			(footprints allowed)
		)
		(placement
			(enabled no)
			(sheetname "")
		)
		(fill
			(thermal_gap 0.5)
			(thermal_bridge_width 0.5)
			(island_removal_mode 0)
		)
		(polygon
			(pts
				(xy 172.54093 -307.207412) (xy 172.54093 -305.852576) (xy 173.018196 -305.852576) (xy 173.018196 -307.207412)
			)
		)
	)
	(zone
		(layer "In4.Cu")
		(hatch none 0.5)
		(connect_pads
			(clearance 0)
		)
		(min_thickness 0.25)
		(keepout
			(tracks allowed)
			(vias allowed)
			(pads allowed)
			(copperpour allowed)
			(footprints allowed)
		)
		(placement
			(enabled no)
			(sheetname "")
		)
		(fill
			(thermal_gap 0.5)
			(thermal_bridge_width 0.5)
			(island_removal_mode 0)
		)
		(polygon
			(pts
				(xy 439.688478 -250.251722) (xy 439.688478 -248.896886) (xy 440.165744 -248.896886) (xy 440.165744 -250.251722)
			)
		)
	)
	(zone
		(layer "In4.Cu")
		(hatch none 0.5)
		(connect_pads
			(clearance 0)
		)
		(min_thickness 0.25)
		(keepout
			(tracks allowed)
			(vias allowed)
			(pads allowed)
			(copperpour allowed)
			(footprints allowed)
		)
		(placement
			(enabled no)
			(sheetname "")
		)
		(fill
			(thermal_gap 0.5)
			(thermal_bridge_width 0.5)
			(island_removal_mode 0)
		)
		(polygon
			(pts
				(xy 172.560742 -231.551734) (xy 172.560742 -230.196898) (xy 173.038008 -230.196898) (xy 173.038008 -231.551734)
				(xy 173.038008 -232.495852) (xy 172.240448 -232.495852) (xy 172.240448 -231.551734)
			)
		)
	)
	(zone
		(layer "In4.Cu")
		(hatch none 0.5)
		(connect_pads
			(clearance 0)
		)
		(min_thickness 0.25)
		(keepout
			(tracks allowed)
			(vias allowed)
			(pads allowed)
			(copperpour allowed)
			(footprints allowed)
		)
		(placement
			(enabled no)
			(sheetname "")
		)
		(fill
			(thermal_gap 0.5)
			(thermal_bridge_width 0.5)
			(island_removal_mode 0)
		)
		(polygon
			(pts
				(xy 340.78164 -338.287868) (xy 340.78164 -335.422748) (xy 353.18192 -335.422748) (xy 353.18192 -338.287868)
			)
		)
	)
	(zone
		(layer "In4.Cu")
		(hatch none 0.5)
		(connect_pads
			(clearance 0)
		)
		(min_thickness 0.25)
		(keepout
			(tracks allowed)
			(vias allowed)
			(pads allowed)
			(copperpour allowed)
			(footprints allowed)
		)
		(placement
			(enabled no)
			(sheetname "")
		)
		(fill
			(thermal_gap 0.5)
			(thermal_bridge_width 0.5)
			(island_removal_mode 0)
		)
		(polygon
			(pts
				(xy 35.722814 -264.686034) (xy 35.722814 -263.331198) (xy 36.20008 -263.331198) (xy 36.20008 -264.686034)
			)
		)
	)
	(zone
		(layer "In4.Cu")
		(hatch none 0.5)
		(connect_pads
			(clearance 0)
		)
		(min_thickness 0.25)
		(keepout
			(tracks allowed)
			(vias allowed)
			(pads allowed)
			(copperpour allowed)
			(footprints allowed)
		)
		(placement
			(enabled no)
			(sheetname "")
		)
		(fill
			(thermal_gap 0.5)
			(thermal_bridge_width 0.5)
			(island_removal_mode 0)
		)
		(polygon
			(pts
				(xy 50.853594 -285.112714) (xy 50.853594 -283.757878) (xy 51.33086 -283.757878) (xy 51.33086 -285.112714)
			)
		)
	)
	(zone
		(layer "In4.Cu")
		(hatch none 0.5)
		(connect_pads
			(clearance 0)
		)
		(min_thickness 0.25)
		(keepout
			(tracks allowed)
			(vias allowed)
			(pads allowed)
			(copperpour allowed)
			(footprints allowed)
		)
		(placement
			(enabled no)
			(sheetname "")
		)
		(fill
			(thermal_gap 0.5)
			(thermal_bridge_width 0.5)
			(island_removal_mode 0)
		)
		(polygon
			(pts
				(xy 439.599832 -268.841982) (xy 439.599832 -267.487146) (xy 440.077098 -267.487146) (xy 440.077098 -268.841982)
			)
		)
	)
	(zone
		(layer "In4.Cu")
		(hatch none 0.5)
		(connect_pads
			(clearance 0)
		)
		(min_thickness 0.25)
		(keepout
			(tracks allowed)
			(vias allowed)
			(pads allowed)
			(copperpour allowed)
			(footprints allowed)
		)
		(placement
			(enabled no)
			(sheetname "")
		)
		(fill
			(thermal_gap 0.5)
			(thermal_bridge_width 0.5)
			(island_removal_mode 0)
		)
		(polygon
			(pts
				(xy 439.688478 -248.5517) (xy 439.688478 -247.196864) (xy 440.165744 -247.196864) (xy 440.165744 -248.5517)
			)
		)
	)
	(zone
		(layer "In4.Cu")
		(hatch none 0.5)
		(connect_pads
			(clearance 0)
		)
		(min_thickness 0.25)
		(keepout
			(tracks allowed)
			(vias allowed)
			(pads allowed)
			(copperpour allowed)
			(footprints allowed)
		)
		(placement
			(enabled no)
			(sheetname "")
		)
		(fill
			(thermal_gap 0.5)
			(thermal_bridge_width 0.5)
			(island_removal_mode 0)
		)
		(polygon
			(pts
				(xy 50.853594 -286.433514) (xy 50.853594 -285.078678) (xy 51.33086 -285.078678) (xy 51.33086 -286.433514)
			)
		)
	)
	(zone
		(layer "In4.Cu")
		(hatch none 0.5)
		(connect_pads
			(clearance 0)
		)
		(min_thickness 0.25)
		(keepout
			(tracks allowed)
			(vias allowed)
			(pads allowed)
			(copperpour allowed)
			(footprints allowed)
		)
		(placement
			(enabled no)
			(sheetname "")
		)
		(fill
			(thermal_gap 0.5)
			(thermal_bridge_width 0.5)
			(island_removal_mode 0)
		)
		(polygon
			(pts
				(xy 50.767742 -252.70587) (xy 50.767742 -251.736606) (xy 51.218084 -251.736606) (xy 51.218084 -252.70587)
			)
		)
	)
	(zone
		(layer "In4.Cu")
		(hatch none 0.5)
		(connect_pads
			(clearance 0)
		)
		(min_thickness 0.25)
		(keepout
			(tracks allowed)
			(vias allowed)
			(pads allowed)
			(copperpour allowed)
			(footprints allowed)
		)
		(placement
			(enabled no)
			(sheetname "")
		)
		(fill
			(thermal_gap 0.5)
			(thermal_bridge_width 0.5)
			(island_removal_mode 0)
		)
		(polygon
			(pts
				(xy 116.09578 -354.848668) (xy 116.09578 -353.581208) (xy 117.61216 -353.581208) (xy 117.61216 -354.848668)
			)
		)
	)
	(zone
		(layer "In4.Cu")
		(hatch none 0.5)
		(connect_pads
			(clearance 0)
		)
		(min_thickness 0.25)
		(keepout
			(tracks allowed)
			(vias allowed)
			(pads allowed)
			(copperpour allowed)
			(footprints allowed)
		)
		(placement
			(enabled no)
			(sheetname "")
		)
		(fill
			(thermal_gap 0.5)
			(thermal_bridge_width 0.5)
			(island_removal_mode 0)
		)
		(polygon
			(pts
				(xy 187.648342 -249.401584) (xy 187.648342 -248.046748) (xy 188.125608 -248.046748) (xy 188.125608 -249.401584)
			)
		)
	)
	(zone
		(layer "In4.Cu")
		(hatch none 0.5)
		(connect_pads
			(clearance 0)
		)
		(min_thickness 0.25)
		(keepout
			(tracks allowed)
			(vias allowed)
			(pads allowed)
			(copperpour allowed)
			(footprints allowed)
		)
		(placement
			(enabled no)
			(sheetname "")
		)
		(fill
			(thermal_gap 0.5)
			(thermal_bridge_width 0.5)
			(island_removal_mode 0)
		)
		(polygon
			(pts
				(xy 298.70781 -252.70587) (xy 298.70781 -251.736606) (xy 299.158152 -251.736606) (xy 299.158152 -252.70587)
			)
		)
	)
	(zone
		(layer "In4.Cu")
		(hatch none 0.5)
		(connect_pads
			(clearance 0)
		)
		(min_thickness 0.25)
		(keepout
			(tracks allowed)
			(vias allowed)
			(pads allowed)
			(copperpour allowed)
			(footprints allowed)
		)
		(placement
			(enabled no)
			(sheetname "")
		)
		(fill
			(thermal_gap 0.5)
			(thermal_bridge_width 0.5)
			(island_removal_mode 0)
		)
		(polygon
			(pts
				(xy 298.77385 -287.694116) (xy 298.77385 -286.33928) (xy 299.251116 -286.33928) (xy 299.251116 -287.694116)
			)
		)
	)
	(zone
		(layer "In4.Cu")
		(hatch none 0.5)
		(connect_pads
			(clearance 0)
		)
		(min_thickness 0.25)
		(keepout
			(tracks allowed)
			(vias allowed)
			(pads allowed)
			(copperpour allowed)
			(footprints allowed)
		)
		(placement
			(enabled no)
			(sheetname "")
		)
		(fill
			(thermal_gap 0.5)
			(thermal_bridge_width 0.5)
			(island_removal_mode 0)
		)
		(polygon
			(pts
				(xy 309.729632 -245.100856) (xy 309.729632 -242.924076) (xy 310.351932 -242.924076) (xy 310.351932 -245.100856)
			)
		)
	)
	(zone
		(layer "In4.Cu")
		(hatch none 0.5)
		(connect_pads
			(clearance 0)
		)
		(min_thickness 0.25)
		(keepout
			(tracks allowed)
			(vias allowed)
			(pads allowed)
			(copperpour allowed)
			(footprints allowed)
		)
		(placement
			(enabled no)
			(sheetname "")
		)
		(fill
			(thermal_gap 0.5)
			(thermal_bridge_width 0.5)
			(island_removal_mode 0)
		)
		(polygon
			(pts
				(xy 52.000404 -287.630616) (xy 52.000404 -285.433516) (xy 52.607464 -285.433516) (xy 52.607464 -287.630616)
			)
		)
	)
	(zone
		(layer "In4.Cu")
		(hatch none 0.5)
		(connect_pads
			(clearance 0)
		)
		(min_thickness 0.25)
		(keepout
			(tracks allowed)
			(vias allowed)
			(pads allowed)
			(copperpour allowed)
			(footprints allowed)
		)
		(placement
			(enabled no)
			(sheetname "")
		)
		(fill
			(thermal_gap 0.5)
			(thermal_bridge_width 0.5)
			(island_removal_mode 0)
		)
		(polygon
			(pts
				(xy 35.722814 -311.437274) (xy 35.722814 -310.082438) (xy 36.20008 -310.082438) (xy 36.20008 -311.437274)
			)
		)
	)
	(zone
		(layer "In4.Cu")
		(hatch none 0.5)
		(connect_pads
			(clearance 0)
		)
		(min_thickness 0.25)
		(keepout
			(tracks allowed)
			(vias allowed)
			(pads allowed)
			(copperpour allowed)
			(footprints allowed)
		)
		(placement
			(enabled no)
			(sheetname "")
		)
		(fill
			(thermal_gap 0.5)
			(thermal_bridge_width 0.5)
			(island_removal_mode 0)
		)
		(polygon
			(pts
				(xy 304.093372 -244.272816) (xy 304.093372 -242.967256) (xy 304.695352 -242.967256) (xy 304.695352 -244.272816)
			)
		)
	)
	(zone
		(layer "In4.Cu")
		(hatch none 0.5)
		(connect_pads
			(clearance 0)
		)
		(min_thickness 0.25)
		(keepout
			(tracks allowed)
			(vias allowed)
			(pads allowed)
			(copperpour allowed)
			(footprints allowed)
		)
		(placement
			(enabled no)
			(sheetname "")
		)
		(fill
			(thermal_gap 0.5)
			(thermal_bridge_width 0.5)
			(island_removal_mode 0)
		)
		(polygon
			(pts
				(xy 435.568598 -211.157566) (xy 435.568598 -209.80273) (xy 436.045864 -209.80273) (xy 436.045864 -211.157566)
			)
		)
	)
	(zone
		(layer "In4.Cu")
		(hatch none 0.5)
		(connect_pads
			(clearance 0)
		)
		(min_thickness 0.25)
		(keepout
			(tracks allowed)
			(vias allowed)
			(pads allowed)
			(copperpour allowed)
			(footprints allowed)
		)
		(placement
			(enabled no)
			(sheetname "")
		)
		(fill
			(thermal_gap 0.5)
			(thermal_bridge_width 0.5)
			(island_removal_mode 0)
		)
		(polygon
			(pts
				(xy 35.703002 -311.443116) (xy 35.703002 -310.08828) (xy 36.180268 -310.08828) (xy 36.180268 -311.443116)
			)
		)
	)
	(zone
		(layer "In4.Cu")
		(hatch none 0.5)
		(connect_pads
			(clearance 0)
		)
		(min_thickness 0.25)
		(keepout
			(tracks allowed)
			(vias allowed)
			(pads allowed)
			(copperpour allowed)
			(footprints allowed)
		)
		(placement
			(enabled no)
			(sheetname "")
		)
		(fill
			(thermal_gap 0.5)
			(thermal_bridge_width 0.5)
			(island_removal_mode 0)
		)
		(polygon
			(pts
				(xy 298.798742 -288.473134) (xy 298.798742 -287.118298) (xy 299.276008 -287.118298) (xy 299.276008 -288.473134)
			)
		)
	)
	(zone
		(layer "In4.Cu")
		(hatch none 0.5)
		(connect_pads
			(clearance 0)
		)
		(min_thickness 0.25)
		(keepout
			(tracks allowed)
			(vias allowed)
			(pads allowed)
			(copperpour allowed)
			(footprints allowed)
		)
		(placement
			(enabled no)
			(sheetname "")
		)
		(fill
			(thermal_gap 0.5)
			(thermal_bridge_width 0.5)
			(island_removal_mode 0)
		)
		(polygon
			(pts
				(xy 283.64307 -264.691876) (xy 283.64307 -263.33704) (xy 284.120336 -263.33704) (xy 284.120336 -264.691876)
			)
		)
	)
	(zone
		(layer "In4.Cu")
		(hatch none 0.5)
		(connect_pads
			(clearance 0)
		)
		(min_thickness 0.25)
		(keepout
			(tracks allowed)
			(vias allowed)
			(pads allowed)
			(copperpour allowed)
			(footprints allowed)
		)
		(placement
			(enabled no)
			(sheetname "")
		)
		(fill
			(thermal_gap 0.5)
			(thermal_bridge_width 0.5)
			(island_removal_mode 0)
		)
		(polygon
			(pts
				(xy 341.87384 -46.200568) (xy 341.87384 -45.413168) (xy 343.21242 -45.413168) (xy 343.21242 -46.200568)
			)
		)
	)
	(zone
		(layer "In4.Cu")
		(hatch none 0.5)
		(connect_pads
			(clearance 0)
		)
		(min_thickness 0.25)
		(keepout
			(tracks allowed)
			(vias allowed)
			(pads allowed)
			(copperpour allowed)
			(footprints allowed)
		)
		(placement
			(enabled no)
			(sheetname "")
		)
		(fill
			(thermal_gap 0.5)
			(thermal_bridge_width 0.5)
			(island_removal_mode 0)
		)
		(polygon
			(pts
				(xy 283.662882 -264.686034) (xy 283.662882 -263.331198) (xy 284.140148 -263.331198) (xy 284.140148 -264.686034)
			)
		)
	)
	(zone
		(layer "In4.Cu")
		(hatch none 0.5)
		(connect_pads
			(clearance 0)
		)
		(min_thickness 0.25)
		(keepout
			(tracks allowed)
			(vias allowed)
			(pads allowed)
			(copperpour allowed)
			(footprints allowed)
		)
		(placement
			(enabled no)
			(sheetname "")
		)
		(fill
			(thermal_gap 0.5)
			(thermal_bridge_width 0.5)
			(island_removal_mode 0)
		)
		(polygon
			(pts
				(xy 46.717712 -318.313054) (xy 46.717712 -316.051438) (xy 47.258732 -316.051438) (xy 47.258732 -318.313054)
			)
		)
	)
	(zone
		(layer "In4.Cu")
		(hatch none 0.5)
		(connect_pads
			(clearance 0)
		)
		(min_thickness 0.25)
		(keepout
			(tracks allowed)
			(vias allowed)
			(pads allowed)
			(copperpour allowed)
			(footprints allowed)
		)
		(placement
			(enabled no)
			(sheetname "")
		)
		(fill
			(thermal_gap 0.5)
			(thermal_bridge_width 0.5)
			(island_removal_mode 0)
		)
		(polygon
			(pts
				(xy 443.13221 -245.151656) (xy 443.13221 -243.79682) (xy 443.609476 -243.79682) (xy 443.609476 -245.151656)
			)
		)
	)
	(zone
		(layer "In4.Cu")
		(hatch none 0.5)
		(connect_pads
			(clearance 0)
		)
		(min_thickness 0.25)
		(keepout
			(tracks allowed)
			(vias allowed)
			(pads allowed)
			(copperpour allowed)
			(footprints allowed)
		)
		(placement
			(enabled no)
			(sheetname "")
		)
		(fill
			(thermal_gap 0.5)
			(thermal_bridge_width 0.5)
			(island_removal_mode 0)
		)
		(polygon
			(pts
				(xy 35.692842 -291.882576) (xy 35.692842 -290.52774) (xy 36.170108 -290.52774) (xy 36.170108 -291.882576)
			)
		)
	)
	(zone
		(layer "In4.Cu")
		(hatch none 0.5)
		(connect_pads
			(clearance 0)
		)
		(min_thickness 0.25)
		(keepout
			(tracks allowed)
			(vias allowed)
			(pads allowed)
			(copperpour allowed)
			(footprints allowed)
		)
		(placement
			(enabled no)
			(sheetname "")
		)
		(fill
			(thermal_gap 0.5)
			(thermal_bridge_width 0.5)
			(island_removal_mode 0)
		)
		(polygon
			(pts
				(xy 50.835814 -224.736914) (xy 50.835814 -223.382078) (xy 51.31308 -223.382078) (xy 51.31308 -224.736914)
			)
		)
	)
	(zone
		(layer "In4.Cu")
		(hatch none 0.5)
		(connect_pads
			(clearance 0)
		)
		(min_thickness 0.25)
		(keepout
			(tracks allowed)
			(vias allowed)
			(pads allowed)
			(copperpour allowed)
			(footprints allowed)
		)
		(placement
			(enabled no)
			(sheetname "")
		)
		(fill
			(thermal_gap 0.5)
			(thermal_bridge_width 0.5)
			(island_removal_mode 0)
		)
		(polygon
			(pts
				(xy 86.891876 -290.964366) (xy 103.719884 -290.964112) (xy 103.71836 -212.967062) (xy 86.076536 -212.967316)
				(xy 85.938106 -213.105746) (xy 85.93836 -219.768674) (xy 85.745066 -219.961968) (xy 82.694526 -219.961968)
				(xy 82.591656 -220.064838) (xy 82.591656 -236.296962) (xy 82.625692 -236.330998) (xy 82.688684 -236.330998)
				(xy 82.838798 -236.330998) (xy 82.88782 -236.38002) (xy 82.88782 -236.480604) (xy 82.88782 -248.44756)
				(xy 82.960464 -248.520204) (xy 83.044538 -248.520204) (xy 84.418932 -248.520204) (xy 85.993732 -250.095004)
				(xy 86.218522 -250.095004) (xy 94.00159 -250.095004) (xy 94.884494 -250.977908) (xy 94.884494 -252.907546)
				(xy 91.841066 -252.907546) (xy 91.68511 -252.75159) (xy 84.363814 -252.75159) (xy 84.245958 -252.869446)
				(xy 84.245958 -258.947158) (xy 84.34705 -259.04825) (xy 84.415122 -259.04825) (xy 88.022938 -259.04825)
				(xy 88.403938 -259.42925) (xy 88.403938 -259.73405) (xy 88.530938 -259.86105) (xy 94.449138 -259.86105)
				(xy 94.703138 -259.60705) (xy 94.703138 -259.25145) (xy 95.160338 -258.79425) (xy 95.160338 -258.46405)
				(xy 95.414338 -258.21005) (xy 96.100138 -258.21005) (xy 96.150938 -258.26085) (xy 96.430338 -258.26085)
				(xy 96.531938 -258.15925) (xy 96.811338 -258.15925) (xy 96.912938 -258.26085) (xy 97.344738 -258.260596)
				(xy 97.420938 -258.184396) (xy 97.878138 -258.184396) (xy 97.979738 -258.285996) (xy 98.259138 -258.285996)
				(xy 98.335338 -258.209796) (xy 98.817938 -258.209796) (xy 98.894138 -258.285996) (xy 99.097338 -258.285996)
				(xy 99.402138 -257.981196) (xy 99.402138 -257.701796) (xy 99.808538 -257.295396) (xy 99.808538 -256.888996)
				(xy 100.341938 -256.355596) (xy 100.341938 -255.949196) (xy 101.027738 -255.263396) (xy 101.586538 -255.263396)
				(xy 101.662738 -255.339596) (xy 101.662738 -255.847596) (xy 101.484938 -256.025396) (xy 100.875338 -256.025396)
				(xy 100.646738 -256.253996) (xy 100.646738 -256.711196) (xy 100.468938 -256.888996) (xy 100.316538 -256.888996)
				(xy 100.113338 -257.092196) (xy 100.113338 -257.396996) (xy 99.630738 -257.879596) (xy 99.630738 -258.387596)
				(xy 99.427538 -258.590796) (xy 98.716338 -258.590796) (xy 98.690938 -258.565396) (xy 95.617538 -258.56565)
				(xy 95.388938 -258.79425) (xy 95.388938 -259.14985) (xy 94.957138 -259.58165) (xy 94.957138 -260.03885)
				(xy 94.855538 -260.14045) (xy 94.677738 -260.14045) (xy 94.550738 -260.26745) (xy 94.118938 -260.26745)
				(xy 94.017338 -260.16585) (xy 93.610938 -260.16585) (xy 93.483938 -260.29285) (xy 93.204538 -260.29285)
				(xy 93.077538 -260.16585) (xy 92.772738 -260.16585) (xy 92.696538 -260.24205) (xy 92.239338 -260.24205)
				(xy 92.163138 -260.16585) (xy 91.782138 -260.16585) (xy 91.680538 -260.26745) (xy 91.299538 -260.26745)
				(xy 91.147138 -260.11505) (xy 90.918538 -260.11505) (xy 90.766138 -260.26745) (xy 90.435938 -260.26745)
				(xy 90.359738 -260.19125) (xy 88.378538 -260.19125) (xy 88.073738 -259.88645) (xy 88.073738 -259.58165)
				(xy 87.819738 -259.32765) (xy 87.540338 -259.32765) (xy 87.413338 -259.45465) (xy 87.006938 -259.45465)
				(xy 86.879938 -259.32765) (xy 86.651338 -259.32765) (xy 86.524338 -259.45465) (xy 86.041738 -259.45465)
				(xy 85.914738 -259.32765) (xy 85.711538 -259.32765) (xy 85.559138 -259.48005) (xy 85.051138 -259.48005)
				(xy 84.924138 -259.35305) (xy 84.847938 -259.35305) (xy 84.543138 -259.65785) (xy 84.43976 -259.761228)
				(xy 82.844386 -259.761228) (xy 82.764122 -259.841492) (xy 82.671666 -259.933948) (xy 82.671666 -268.164818)
				(xy 82.726784 -268.219936) (xy 83.251548 -268.219936) (xy 83.350354 -268.318742) (xy 83.350354 -268.952218)
				(xy 83.207606 -269.094966) (xy 83.207606 -271.420336) (xy 83.40725 -271.61998) (xy 83.40725 -271.77746)
				(xy 83.487514 -271.857724) (xy 83.861656 -271.857724) (xy 84.4169 -271.30248) (xy 84.692744 -271.30248)
				(xy 85.094064 -271.7038) (xy 85.094064 -271.739868) (xy 83.783932 -273.05) (xy 83.783932 -273.137884)
				(xy 84.518754 -273.872706) (xy 84.518754 -273.876516) (xy 83.646772 -274.748498) (xy 83.646772 -276.786848)
				(xy 83.58124 -276.85238) (xy 82.965798 -277.467822) (xy 82.965798 -277.815802) (xy 82.965798 -278.011128)
				(xy 85.094572 -280.139902) (xy 85.094572 -281.538934) (xy 84.086446 -282.54706) (xy 84.086446 -282.64358)
				(xy 84.313268 -282.870402) (xy 84.313268 -282.993846) (xy 84.104226 -283.202888) (xy 84.104226 -283.30144)
				(xy 84.722462 -283.919676) (xy 84.722462 -283.955744) (xy 84.21878 -284.459426) (xy 84.21878 -284.66669)
				(xy 84.758276 -285.206186) (xy 84.758276 -285.28518) (xy 84.558124 -285.485332) (xy 84.558124 -285.66364)
				(xy 85.16239 -286.267906) (xy 85.16239 -286.353504) (xy 84.804758 -286.711136) (xy 84.804758 -287.307528)
				(xy 84.9503 -287.45307) (xy 84.9503 -287.693608) (xy 84.995512 -287.73882) (xy 86.04377 -287.73882)
				(xy 86.04377 -288.620708) (xy 86.169246 -288.620708) (xy 86.693756 -288.620708) (xy 86.693756 -289.235896)
				(xy 86.738206 -289.280346) (xy 86.73846 -290.81095)
			)
		)
	)
	(zone
		(layer "In4.Cu")
		(hatch none 0.5)
		(connect_pads
			(clearance 0)
		)
		(min_thickness 0.25)
		(keepout
			(tracks allowed)
			(vias allowed)
			(pads allowed)
			(copperpour allowed)
			(footprints allowed)
		)
		(placement
			(enabled no)
			(sheetname "")
		)
		(fill
			(thermal_gap 0.5)
			(thermal_bridge_width 0.5)
			(island_removal_mode 0)
		)
		(polygon
			(pts
				(xy 187.618624 -308.013862) (xy 187.618624 -306.659026) (xy 188.09589 -306.659026) (xy 188.09589 -308.013862)
			)
		)
	)
	(zone
		(layer "In4.Cu")
		(hatch none 0.5)
		(connect_pads
			(clearance 0)
		)
		(min_thickness 0.25)
		(keepout
			(tracks allowed)
			(vias allowed)
			(pads allowed)
			(copperpour allowed)
			(footprints allowed)
		)
		(placement
			(enabled no)
			(sheetname "")
		)
		(fill
			(thermal_gap 0.5)
			(thermal_bridge_width 0.5)
			(island_removal_mode 0)
		)
		(polygon
			(pts
				(xy 298.753022 -203.540614) (xy 298.753022 -202.982068) (xy 299.230288 -202.982068) (xy 299.643546 -202.982068)
				(xy 299.713142 -203.051664) (xy 299.713142 -203.467716) (xy 299.640244 -203.540614) (xy 299.230288 -203.540614)
			)
		)
	)
	(zone
		(layer "In4.Cu")
		(hatch none 0.5)
		(connect_pads
			(clearance 0)
		)
		(min_thickness 0.25)
		(keepout
			(tracks allowed)
			(vias allowed)
			(pads allowed)
			(copperpour allowed)
			(footprints allowed)
		)
		(placement
			(enabled no)
			(sheetname "")
		)
		(fill
			(thermal_gap 0.5)
			(thermal_bridge_width 0.5)
			(island_removal_mode 0)
		)
		(polygon
			(pts
				(xy 58.09742 -12.43076) (xy 58.09742 -11.00582) (xy 59.22772 -11.00582) (xy 59.22772 -12.43076)
			)
		)
	)
	(zone
		(layer "In4.Cu")
		(hatch none 0.5)
		(connect_pads
			(clearance 0)
		)
		(min_thickness 0.25)
		(keepout
			(tracks allowed)
			(vias allowed)
			(pads allowed)
			(copperpour allowed)
			(footprints allowed)
		)
		(placement
			(enabled no)
			(sheetname "")
		)
		(fill
			(thermal_gap 0.5)
			(thermal_bridge_width 0.5)
			(island_removal_mode 0)
		)
		(polygon
			(pts
				(xy 309.70728 -307.169058) (xy 309.70728 -305.749198) (xy 310.19496 -305.749198) (xy 310.19496 -307.169058)
			)
		)
	)
	(zone
		(layer "In4.Cu")
		(hatch none 0.5)
		(connect_pads
			(clearance 0)
		)
		(min_thickness 0.25)
		(keepout
			(tracks allowed)
			(vias allowed)
			(pads allowed)
			(copperpour allowed)
			(footprints allowed)
		)
		(placement
			(enabled no)
			(sheetname "")
		)
		(fill
			(thermal_gap 0.5)
			(thermal_bridge_width 0.5)
			(island_removal_mode 0)
		)
		(polygon
			(pts
				(xy 435.58841 -291.051742) (xy 435.58841 -289.696906) (xy 436.065676 -289.696906) (xy 436.065676 -291.051742)
			)
		)
	)
	(zone
		(layer "In4.Cu")
		(hatch none 0.5)
		(connect_pads
			(clearance 0)
		)
		(min_thickness 0.25)
		(keepout
			(tracks allowed)
			(vias allowed)
			(pads allowed)
			(copperpour allowed)
			(footprints allowed)
		)
		(placement
			(enabled no)
			(sheetname "")
		)
		(fill
			(thermal_gap 0.5)
			(thermal_bridge_width 0.5)
			(island_removal_mode 0)
		)
		(polygon
			(pts
				(xy 48.698404 -261.252716) (xy 48.698404 -258.298696) (xy 49.054004 -258.298696) (xy 49.054004 -261.252716)
			)
		)
	)
	(zone
		(layer "In4.Cu")
		(hatch none 0.5)
		(connect_pads
			(clearance 0)
		)
		(min_thickness 0.25)
		(keepout
			(tracks allowed)
			(vias allowed)
			(pads allowed)
			(copperpour allowed)
			(footprints allowed)
		)
		(placement
			(enabled no)
			(sheetname "")
		)
		(fill
			(thermal_gap 0.5)
			(thermal_bridge_width 0.5)
			(island_removal_mode 0)
		)
		(polygon
			(pts
				(xy 65.937892 -306.701698) (xy 65.937892 -305.002438) (xy 66.321432 -305.002438) (xy 66.321432 -306.701698)
			)
		)
	)
	(zone
		(layer "In4.Cu")
		(hatch none 0.5)
		(connect_pads
			(clearance 0)
		)
		(min_thickness 0.25)
		(keepout
			(tracks allowed)
			(vias allowed)
			(pads allowed)
			(copperpour allowed)
			(footprints allowed)
		)
		(placement
			(enabled no)
			(sheetname "")
		)
		(fill
			(thermal_gap 0.5)
			(thermal_bridge_width 0.5)
			(island_removal_mode 0)
		)
		(polygon
			(pts
				(xy 35.733482 -212.835236) (xy 35.733482 -211.4804) (xy 36.210748 -211.4804) (xy 36.210748 -212.835236)
			)
		)
	)
	(zone
		(layer "In4.Cu")
		(hatch none 0.5)
		(connect_pads
			(clearance 0)
		)
		(min_thickness 0.25)
		(keepout
			(tracks allowed)
			(vias allowed)
			(pads allowed)
			(copperpour allowed)
			(footprints allowed)
		)
		(placement
			(enabled no)
			(sheetname "")
		)
		(fill
			(thermal_gap 0.5)
			(thermal_bridge_width 0.5)
			(island_removal_mode 0)
		)
		(polygon
			(pts
				(xy 172.54093 -204.357478) (xy 172.54093 -203.002642) (xy 173.018196 -203.002642) (xy 173.018196 -204.357478)
			)
		)
	)
	(zone
		(layer "In4.Cu")
		(hatch none 0.5)
		(connect_pads
			(clearance 0)
		)
		(min_thickness 0.25)
		(keepout
			(tracks allowed)
			(vias allowed)
			(pads allowed)
			(copperpour allowed)
			(footprints allowed)
		)
		(placement
			(enabled no)
			(sheetname "")
		)
		(fill
			(thermal_gap 0.5)
			(thermal_bridge_width 0.5)
			(island_removal_mode 0)
		)
		(polygon
			(pts
				(xy 439.668666 -268.107414) (xy 439.668666 -266.752578) (xy 440.145932 -266.752578) (xy 440.145932 -268.107414)
			)
		)
	)
	(zone
		(layer "In4.Cu")
		(hatch none 0.5)
		(connect_pads
			(clearance 0)
		)
		(min_thickness 0.25)
		(keepout
			(tracks allowed)
			(vias allowed)
			(pads allowed)
			(copperpour allowed)
			(footprints allowed)
		)
		(placement
			(enabled no)
			(sheetname "")
		)
		(fill
			(thermal_gap 0.5)
			(thermal_bridge_width 0.5)
			(island_removal_mode 0)
		)
		(polygon
			(pts
				(xy 50.782474 -197.576694) (xy 50.782474 -196.221858) (xy 51.25974 -196.221858) (xy 51.25974 -197.576694)
			)
		)
	)
	(zone
		(layer "In4.Cu")
		(hatch none 0.5)
		(connect_pads
			(clearance 0)
		)
		(min_thickness 0.25)
		(keepout
			(tracks allowed)
			(vias allowed)
			(pads allowed)
			(copperpour allowed)
			(footprints allowed)
		)
		(placement
			(enabled no)
			(sheetname "")
		)
		(fill
			(thermal_gap 0.5)
			(thermal_bridge_width 0.5)
			(island_removal_mode 0)
		)
		(polygon
			(pts
				(xy 439.668666 -250.257564) (xy 439.668666 -248.902728) (xy 440.145932 -248.902728) (xy 440.145932 -250.257564)
			)
		)
	)
	(zone
		(layer "In4.Cu")
		(hatch none 0.5)
		(connect_pads
			(clearance 0)
		)
		(min_thickness 0.25)
		(keepout
			(tracks allowed)
			(vias allowed)
			(pads allowed)
			(copperpour allowed)
			(footprints allowed)
		)
		(placement
			(enabled no)
			(sheetname "")
		)
		(fill
			(thermal_gap 0.5)
			(thermal_bridge_width 0.5)
			(island_removal_mode 0)
		)
		(polygon
			(pts
				(xy 50.816002 -300.625256) (xy 50.816002 -299.27042) (xy 51.293268 -299.27042) (xy 51.293268 -300.625256)
			)
		)
	)
	(zone
		(layer "In4.Cu")
		(hatch none 0.5)
		(connect_pads
			(clearance 0)
		)
		(min_thickness 0.25)
		(keepout
			(tracks allowed)
			(vias allowed)
			(pads allowed)
			(copperpour allowed)
			(footprints allowed)
		)
		(placement
			(enabled no)
			(sheetname "")
		)
		(fill
			(thermal_gap 0.5)
			(thermal_bridge_width 0.5)
			(island_removal_mode 0)
		)
		(polygon
			(pts
				(xy 35.708082 -235.819696) (xy 35.708082 -234.46486) (xy 36.185348 -234.46486) (xy 36.185348 -235.819696)
			)
		)
	)
	(zone
		(layer "In4.Cu")
		(hatch none 0.5)
		(connect_pads
			(clearance 0)
		)
		(min_thickness 0.25)
		(keepout
			(tracks allowed)
			(vias allowed)
			(pads allowed)
			(copperpour allowed)
			(footprints allowed)
		)
		(placement
			(enabled no)
			(sheetname "")
		)
		(fill
			(thermal_gap 0.5)
			(thermal_bridge_width 0.5)
			(island_removal_mode 0)
		)
		(polygon
			(pts
				(xy 187.648342 -251.101606) (xy 187.648342 -249.74677) (xy 188.125608 -249.74677) (xy 188.125608 -251.101606)
			)
		)
	)
	(zone
		(layer "In4.Cu")
		(hatch none 0.5)
		(connect_pads
			(clearance 0)
		)
		(min_thickness 0.25)
		(keepout
			(tracks allowed)
			(vias allowed)
			(pads allowed)
			(copperpour allowed)
			(footprints allowed)
		)
		(placement
			(enabled no)
			(sheetname "")
		)
		(fill
			(thermal_gap 0.5)
			(thermal_bridge_width 0.5)
			(island_removal_mode 0)
		)
		(polygon
			(pts
				(xy 35.723322 -251.534676) (xy 35.723322 -250.17984) (xy 36.200588 -250.17984) (xy 36.200588 -251.534676)
			)
		)
	)
	(zone
		(layer "In4.Cu")
		(hatch none 0.5)
		(connect_pads
			(clearance 0)
		)
		(min_thickness 0.25)
		(keepout
			(tracks allowed)
			(vias allowed)
			(pads allowed)
			(copperpour allowed)
			(footprints allowed)
		)
		(placement
			(enabled no)
			(sheetname "")
		)
		(fill
			(thermal_gap 0.5)
			(thermal_bridge_width 0.5)
			(island_removal_mode 0)
		)
		(polygon
			(pts
				(xy 48.70196 -12.68222) (xy 48.70196 -11.50112) (xy 50.01006 -11.50112) (xy 50.01006 -12.68222)
			)
		)
	)
	(zone
		(layer "In4.Cu")
		(hatch none 0.5)
		(connect_pads
			(clearance 0)
		)
		(min_thickness 0.25)
		(keepout
			(tracks allowed)
			(vias allowed)
			(pads allowed)
			(copperpour allowed)
			(footprints allowed)
		)
		(placement
			(enabled no)
			(sheetname "")
		)
		(fill
			(thermal_gap 0.5)
			(thermal_bridge_width 0.5)
			(island_removal_mode 0)
		)
		(polygon
			(pts
				(xy 65.937384 -303.818036) (xy 65.937384 -298.245276) (xy 66.386964 -298.245276) (xy 66.386964 -303.818036)
			)
		)
	)
	(zone
		(layer "In4.Cu")
		(hatch none 0.5)
		(connect_pads
			(clearance 0)
		)
		(min_thickness 0.25)
		(keepout
			(tracks allowed)
			(vias allowed)
			(pads allowed)
			(copperpour allowed)
			(footprints allowed)
		)
		(placement
			(enabled no)
			(sheetname "")
		)
		(fill
			(thermal_gap 0.5)
			(thermal_bridge_width 0.5)
			(island_removal_mode 0)
		)
		(polygon
			(pts
				(xy 435.568598 -296.157396) (xy 435.568598 -294.80256) (xy 436.045864 -294.80256) (xy 436.045864 -296.157396)
			)
		)
	)
	(zone
		(layer "In4.Cu")
		(hatch none 0.5)
		(connect_pads
			(clearance 0)
		)
		(min_thickness 0.25)
		(keepout
			(tracks allowed)
			(vias allowed)
			(pads allowed)
			(copperpour allowed)
			(footprints allowed)
		)
		(placement
			(enabled no)
			(sheetname "")
		)
		(fill
			(thermal_gap 0.5)
			(thermal_bridge_width 0.5)
			(island_removal_mode 0)
		)
		(polygon
			(pts
				(xy 283.685742 -314.569094) (xy 283.685742 -313.214258) (xy 284.163008 -313.214258) (xy 284.163008 -314.569094)
			)
		)
	)
	(zone
		(layer "In4.Cu")
		(hatch none 0.5)
		(connect_pads
			(clearance 0)
		)
		(min_thickness 0.25)
		(keepout
			(tracks allowed)
			(vias allowed)
			(pads allowed)
			(copperpour allowed)
			(footprints allowed)
		)
		(placement
			(enabled no)
			(sheetname "")
		)
		(fill
			(thermal_gap 0.5)
			(thermal_bridge_width 0.5)
			(island_removal_mode 0)
		)
		(polygon
			(pts
				(xy 323.77634 -16.11376) (xy 323.77634 -14.4526) (xy 338.50834 -14.4526) (xy 338.50834 -16.11376)
			)
		)
	)
	(zone
		(layer "In4.Cu")
		(hatch none 0.5)
		(connect_pads
			(clearance 0)
		)
		(min_thickness 0.25)
		(keepout
			(tracks allowed)
			(vias allowed)
			(pads allowed)
			(copperpour allowed)
			(footprints allowed)
		)
		(placement
			(enabled no)
			(sheetname "")
		)
		(fill
			(thermal_gap 0.5)
			(thermal_bridge_width 0.5)
			(island_removal_mode 0)
		)
		(polygon
			(pts
				(xy 187.62853 -209.457544) (xy 187.62853 -207.29702) (xy 188.105796 -207.29702) (xy 188.105796 -209.457544)
			)
		)
	)
	(zone
		(layer "In4.Cu")
		(hatch none 0.5)
		(connect_pads
			(clearance 0)
		)
		(min_thickness 0.25)
		(keepout
			(tracks allowed)
			(vias allowed)
			(pads allowed)
			(copperpour allowed)
			(footprints allowed)
		)
		(placement
			(enabled no)
			(sheetname "")
		)
		(fill
			(thermal_gap 0.5)
			(thermal_bridge_width 0.5)
			(island_removal_mode 0)
		)
		(polygon
			(pts
				(xy 40.2336 -358.435148) (xy 40.2336 -357.035608) (xy 42.36974 -357.035608) (xy 42.36974 -358.435148)
			)
		)
	)
	(zone
		(layer "In4.Cu")
		(hatch none 0.5)
		(connect_pads
			(clearance 0)
		)
		(min_thickness 0.25)
		(keepout
			(tracks allowed)
			(vias allowed)
			(pads allowed)
			(copperpour allowed)
			(footprints allowed)
		)
		(placement
			(enabled no)
			(sheetname "")
		)
		(fill
			(thermal_gap 0.5)
			(thermal_bridge_width 0.5)
			(island_removal_mode 0)
		)
		(polygon
			(pts
				(xy 195.17233 -245.157498) (xy 195.17233 -243.802662) (xy 195.649596 -243.802662) (xy 195.649596 -245.157498)
			)
		)
	)
	(zone
		(layer "In4.Cu")
		(hatch none 0.5)
		(connect_pads
			(clearance 0)
		)
		(min_thickness 0.25)
		(keepout
			(tracks allowed)
			(vias allowed)
			(pads allowed)
			(copperpour allowed)
			(footprints allowed)
		)
		(placement
			(enabled no)
			(sheetname "")
		)
		(fill
			(thermal_gap 0.5)
			(thermal_bridge_width 0.5)
			(island_removal_mode 0)
		)
		(polygon
			(pts
				(xy 311.657492 -244.397276) (xy 311.657492 -241.308636) (xy 312.051192 -241.308636) (xy 312.051192 -244.397276)
			)
		)
	)
	(zone
		(layer "In4.Cu")
		(hatch none 0.5)
		(connect_pads
			(clearance 0)
		)
		(min_thickness 0.25)
		(keepout
			(tracks allowed)
			(vias allowed)
			(pads allowed)
			(copperpour allowed)
			(footprints allowed)
		)
		(placement
			(enabled no)
			(sheetname "")
		)
		(fill
			(thermal_gap 0.5)
			(thermal_bridge_width 0.5)
			(island_removal_mode 0)
		)
		(polygon
			(pts
				(xy 420.480998 -204.357478) (xy 420.480998 -203.002642) (xy 420.958264 -203.002642) (xy 420.958264 -204.357478)
			)
		)
	)
	(zone
		(layer "In4.Cu")
		(hatch none 0.5)
		(connect_pads
			(clearance 0)
		)
		(min_thickness 0.25)
		(keepout
			(tracks allowed)
			(vias allowed)
			(pads allowed)
			(copperpour allowed)
			(footprints allowed)
		)
		(placement
			(enabled no)
			(sheetname "")
		)
		(fill
			(thermal_gap 0.5)
			(thermal_bridge_width 0.5)
			(island_removal_mode 0)
		)
		(polygon
			(pts
				(xy 351.659952 -290.964112) (xy 355.451918 -290.964112) (xy 358.791256 -290.964112) (xy 365.24946 -290.963858)
				(xy 365.24946 -292.269672) (xy 365.52886 -292.549072) (xy 367.10366 -292.549072) (xy 367.53546 -292.980872)
				(xy 374.57126 -292.980618) (xy 375.13006 -292.421818) (xy 379.47346 -292.421818) (xy 380.00686 -291.888418)
				(xy 384.22326 -291.888418) (xy 384.60426 -291.507418) (xy 384.60426 -290.963604) (xy 386.607812 -290.963604)
				(xy 386.738114 -290.833302) (xy 386.73786 -281.940762) (xy 387.014974 -281.663648) (xy 387.014974 -281.44343)
				(xy 387.760464 -280.69794) (xy 387.760464 -280.625804) (xy 387.759956 -280.625804) (xy 387.343396 -280.209244)
				(xy 387.343396 -280.186384) (xy 388.775956 -278.753824) (xy 388.775956 -278.632666) (xy 388.746746 -278.603456)
				(xy 387.506972 -277.363682) (xy 387.506972 -277.346156) (xy 387.909054 -276.944074) (xy 387.909054 -276.91461)
				(xy 387.187948 -276.193504) (xy 387.187948 -276.149054) (xy 387.200902 -276.1361) (xy 387.81736 -275.519388)
				(xy 387.29666 -274.998688) (xy 387.29666 -274.157694) (xy 387.48081 -273.973544) (xy 387.48081 -272.657062)
				(xy 388.636764 -271.501108) (xy 388.636764 -271.400524) (xy 388.408672 -271.172432) (xy 388.408672 -271.135094)
				(xy 389.492998 -270.050768) (xy 389.492998 -269.825216) (xy 387.562852 -267.89507) (xy 387.562852 -267.10386)
				(xy 387.513576 -267.054584) (xy 386.68833 -267.054584) (xy 386.679948 -267.046202) (xy 386.679948 -263.399524)
				(xy 386.735574 -263.343898) (xy 388.428484 -263.343898) (xy 388.509256 -263.263126) (xy 388.509256 -262.110728)
				(xy 388.332218 -261.93369) (xy 386.902198 -261.93369) (xy 386.879338 -261.91083) (xy 386.879338 -259.815584)
				(xy 386.893054 -259.801868) (xy 387.474206 -259.801868) (xy 387.533388 -259.801868) (xy 387.58114 -259.754116)
				(xy 387.58114 -258.1021) (xy 387.505702 -258.026662) (xy 386.984494 -258.026662) (xy 386.866638 -257.908806)
				(xy 386.866638 -257.261614) (xy 386.849112 -257.244088) (xy 385.357878 -257.244088) (xy 385.32943 -257.21564)
				(xy 385.32943 -256.191004) (xy 385.369054 -256.15138) (xy 387.702298 -256.15138) (xy 387.754368 -256.09931)
				(xy 387.754368 -255.239774) (xy 387.652006 -255.137412) (xy 386.788914 -255.137412) (xy 386.684012 -255.03251)
				(xy 385.04622 -255.03251) (xy 385.01574 -255.00203) (xy 385.01574 -254.935228) (xy 385.01574 -254.17272)
				(xy 384.928364 -254.085344) (xy 379.041914 -254.085344) (xy 378.892308 -253.935738) (xy 378.892308 -252.995938)
				(xy 378.793248 -252.896878) (xy 374.451372 -252.896878) (xy 373.326914 -251.77242) (xy 373.067072 -251.512578)
				(xy 373.067072 -250.561856) (xy 373.10314 -250.525788) (xy 373.326914 -250.525788) (xy 373.9896 -250.525788)
				(xy 374.037098 -250.47829) (xy 374.037098 -250.045474) (xy 373.834406 -249.842782) (xy 373.834406 -249.548142)
				(xy 374.01754 -249.365008) (xy 375.510298 -249.364754) (xy 375.98985 -249.364754) (xy 376.151648 -249.526552)
				(xy 376.982482 -249.526552) (xy 376.982736 -249.526298) (xy 377.113292 -249.656854) (xy 377.113292 -249.878088)
				(xy 377.085606 -249.905774) (xy 377.085606 -250.055888) (xy 377.085606 -250.211336) (xy 377.150376 -250.276106)
				(xy 377.494546 -250.276106) (xy 377.792996 -249.977656) (xy 385.43865 -249.977656) (xy 385.894834 -249.521472)
				(xy 385.894834 -245.18874) (xy 386.05587 -245.027704) (xy 388.233666 -245.027704) (xy 388.361428 -244.899942)
				(xy 388.361428 -239.2045) (xy 388.38632 -239.179608) (xy 389.027162 -239.179608) (xy 389.099552 -239.107218)
				(xy 389.099552 -234.80014) (xy 388.901686 -234.602274) (xy 388.639304 -234.602274) (xy 388.570724 -234.533694)
				(xy 388.570724 -232.471976) (xy 388.966202 -232.076498) (xy 388.966202 -231.608376) (xy 388.338568 -230.980742)
				(xy 388.338568 -230.80218) (xy 388.67715 -230.463598) (xy 388.67715 -230.372412) (xy 388.106666 -229.801928)
				(xy 388.106666 -229.33787) (xy 388.867396 -228.57714) (xy 388.867396 -224.412302) (xy 388.66953 -224.214436)
				(xy 387.985 -224.214436) (xy 387.836664 -224.0661) (xy 387.836664 -219.57792) (xy 387.619748 -219.361004)
				(xy 387.619748 -217.885518) (xy 387.490462 -217.756232) (xy 387.473698 -217.756232) (xy 387.473444 -214.824564)
				(xy 385.615434 -212.966554) (xy 358.789732 -212.967062) (xy 355.450394 -212.967062) (xy 351.658428 -212.967062)
			)
		)
	)
	(zone
		(layer "In4.Cu")
		(hatch none 0.5)
		(connect_pads
			(clearance 0)
		)
		(min_thickness 0.25)
		(keepout
			(tracks allowed)
			(vias allowed)
			(pads allowed)
			(copperpour allowed)
			(footprints allowed)
		)
		(placement
			(enabled no)
			(sheetname "")
		)
		(fill
			(thermal_gap 0.5)
			(thermal_bridge_width 0.5)
			(island_removal_mode 0)
		)
		(polygon
			(pts
				(xy 298.76623 -226.429316) (xy 298.76623 -225.07448) (xy 299.243496 -225.07448) (xy 299.243496 -226.429316)
			)
		)
	)
	(zone
		(layer "In4.Cu")
		(hatch none 0.5)
		(connect_pads
			(clearance 0)
		)
		(min_thickness 0.25)
		(keepout
			(tracks allowed)
			(vias allowed)
			(pads allowed)
			(copperpour allowed)
			(footprints allowed)
		)
		(placement
			(enabled no)
			(sheetname "")
		)
		(fill
			(thermal_gap 0.5)
			(thermal_bridge_width 0.5)
			(island_removal_mode 0)
		)
		(polygon
			(pts
				(xy 356.09022 -338.272628) (xy 356.09022 -335.112868) (xy 369.92814 -335.112868) (xy 369.92814 -338.272628)
			)
		)
	)
	(zone
		(layer "In4.Cu")
		(hatch none 0.5)
		(connect_pads
			(clearance 0)
		)
		(min_thickness 0.25)
		(keepout
			(tracks allowed)
			(vias allowed)
			(pads allowed)
			(copperpour allowed)
			(footprints allowed)
		)
		(placement
			(enabled no)
			(sheetname "")
		)
		(fill
			(thermal_gap 0.5)
			(thermal_bridge_width 0.5)
			(island_removal_mode 0)
		)
		(polygon
			(pts
				(xy 424.583352 -319.161922) (xy 424.583352 -317.807086) (xy 425.060618 -317.807086) (xy 425.060618 -319.161922)
			)
		)
	)
	(zone
		(layer "In4.Cu")
		(hatch none 0.5)
		(connect_pads
			(clearance 0)
		)
		(min_thickness 0.25)
		(keepout
			(tracks allowed)
			(vias allowed)
			(pads allowed)
			(copperpour allowed)
			(footprints allowed)
		)
		(placement
			(enabled no)
			(sheetname "")
		)
		(fill
			(thermal_gap 0.5)
			(thermal_bridge_width 0.5)
			(island_removal_mode 0)
		)
		(polygon
			(pts
				(xy 35.727894 -240.916714) (xy 35.727894 -239.561878) (xy 36.20516 -239.561878) (xy 36.20516 -240.916714)
			)
		)
	)
	(zone
		(layer "In4.Cu")
		(hatch none 0.5)
		(connect_pads
			(clearance 0)
		)
		(min_thickness 0.25)
		(keepout
			(tracks allowed)
			(vias allowed)
			(pads allowed)
			(copperpour allowed)
			(footprints allowed)
		)
		(placement
			(enabled no)
			(sheetname "")
		)
		(fill
			(thermal_gap 0.5)
			(thermal_bridge_width 0.5)
			(island_removal_mode 0)
		)
		(polygon
			(pts
				(xy 35.753294 -214.561674) (xy 35.753294 -213.206838) (xy 36.23056 -213.206838) (xy 36.23056 -214.561674)
			)
		)
	)
	(zone
		(layer "In4.Cu")
		(hatch none 0.5)
		(connect_pads
			(clearance 0)
		)
		(min_thickness 0.25)
		(keepout
			(tracks allowed)
			(vias allowed)
			(pads allowed)
			(copperpour allowed)
			(footprints allowed)
		)
		(placement
			(enabled no)
			(sheetname "")
		)
		(fill
			(thermal_gap 0.5)
			(thermal_bridge_width 0.5)
			(island_removal_mode 0)
		)
		(polygon
			(pts
				(xy 412.911798 -244.30736) (xy 412.911798 -242.952524) (xy 413.389064 -242.952524) (xy 413.389064 -244.30736)
			)
		)
	)
	(zone
		(layer "In4.Cu")
		(hatch none 0.5)
		(connect_pads
			(clearance 0)
		)
		(min_thickness 0.25)
		(keepout
			(tracks allowed)
			(vias allowed)
			(pads allowed)
			(copperpour allowed)
			(footprints allowed)
		)
		(placement
			(enabled no)
			(sheetname "")
		)
		(fill
			(thermal_gap 0.5)
			(thermal_bridge_width 0.5)
			(island_removal_mode 0)
		)
		(polygon
			(pts
				(xy 298.775882 -300.619414) (xy 298.775882 -299.264578) (xy 299.253148 -299.264578) (xy 299.253148 -300.619414)
			)
		)
	)
	(zone
		(layer "In4.Cu")
		(hatch none 0.5)
		(connect_pads
			(clearance 0)
		)
		(min_thickness 0.25)
		(keepout
			(tracks allowed)
			(vias allowed)
			(pads allowed)
			(copperpour allowed)
			(footprints allowed)
		)
		(placement
			(enabled no)
			(sheetname "")
		)
		(fill
			(thermal_gap 0.5)
			(thermal_bridge_width 0.5)
			(island_removal_mode 0)
		)
		(polygon
			(pts
				(xy 187.648342 -205.20152) (xy 187.648342 -203.846684) (xy 188.125608 -203.846684) (xy 188.125608 -205.20152)
			)
		)
	)
	(zone
		(layer "In4.Cu")
		(hatch none 0.5)
		(connect_pads
			(clearance 0)
		)
		(min_thickness 0.25)
		(keepout
			(tracks allowed)
			(vias allowed)
			(pads allowed)
			(copperpour allowed)
			(footprints allowed)
		)
		(placement
			(enabled no)
			(sheetname "")
		)
		(fill
			(thermal_gap 0.5)
			(thermal_bridge_width 0.5)
			(island_removal_mode 0)
		)
		(polygon
			(pts
				(xy 420.50081 -223.901508) (xy 420.50081 -222.546672) (xy 420.978076 -222.546672) (xy 420.978076 -223.901508)
			)
		)
	)
	(zone
		(layer "In4.Cu")
		(hatch none 0.5)
		(connect_pads
			(clearance 0)
		)
		(min_thickness 0.25)
		(keepout
			(tracks allowed)
			(vias allowed)
			(pads allowed)
			(copperpour allowed)
			(footprints allowed)
		)
		(placement
			(enabled no)
			(sheetname "")
		)
		(fill
			(thermal_gap 0.5)
			(thermal_bridge_width 0.5)
			(island_removal_mode 0)
		)
		(polygon
			(pts
				(xy 99.54768 -338.953348) (xy 99.54768 -335.448148) (xy 114.48034 -335.448148) (xy 114.48034 -338.953348)
			)
		)
	)
	(zone
		(layer "In4.Cu")
		(hatch none 0.5)
		(connect_pads
			(clearance 0)
		)
		(min_thickness 0.25)
		(keepout
			(tracks allowed)
			(vias allowed)
			(pads allowed)
			(copperpour allowed)
			(footprints allowed)
		)
		(placement
			(enabled no)
			(sheetname "")
		)
		(fill
			(thermal_gap 0.5)
			(thermal_bridge_width 0.5)
			(island_removal_mode 0)
		)
		(polygon
			(pts
				(xy 187.648342 -247.701562) (xy 187.648342 -246.346726) (xy 188.125608 -246.346726) (xy 188.125608 -247.701562)
			)
		)
	)
	(zone
		(layer "In4.Cu")
		(hatch none 0.5)
		(connect_pads
			(clearance 0)
		)
		(min_thickness 0.25)
		(keepout
			(tracks allowed)
			(vias allowed)
			(pads allowed)
			(copperpour allowed)
			(footprints allowed)
		)
		(placement
			(enabled no)
			(sheetname "")
		)
		(fill
			(thermal_gap 0.5)
			(thermal_bridge_width 0.5)
			(island_removal_mode 0)
		)
		(polygon
			(pts
				(xy 355.2952 -367.370868) (xy 355.2952 -366.446308) (xy 356.8573 -366.446308) (xy 356.8573 -367.370868)
			)
		)
	)
	(zone
		(layer "In4.Cu")
		(hatch none 0.5)
		(connect_pads
			(clearance 0)
		)
		(min_thickness 0.25)
		(keepout
			(tracks allowed)
			(vias allowed)
			(pads allowed)
			(copperpour allowed)
			(footprints allowed)
		)
		(placement
			(enabled no)
			(sheetname "")
		)
		(fill
			(thermal_gap 0.5)
			(thermal_bridge_width 0.5)
			(island_removal_mode 0)
		)
		(polygon
			(pts
				(xy 164.97173 -244.30736) (xy 164.97173 -242.952524) (xy 165.448996 -242.952524) (xy 165.448996 -244.30736)
			)
		)
	)
	(zone
		(layer "In4.Cu")
		(hatch none 0.5)
		(connect_pads
			(clearance 0)
		)
		(min_thickness 0.25)
		(keepout
			(tracks allowed)
			(vias allowed)
			(pads allowed)
			(copperpour allowed)
			(footprints allowed)
		)
		(placement
			(enabled no)
			(sheetname "")
		)
		(fill
			(thermal_gap 0.5)
			(thermal_bridge_width 0.5)
			(island_removal_mode 0)
		)
		(polygon
			(pts
				(xy 283.693362 -212.829394) (xy 283.693362 -211.474558) (xy 284.170628 -211.474558) (xy 284.170628 -212.829394)
			)
		)
	)
	(zone
		(layer "In4.Cu")
		(hatch none 0.5)
		(connect_pads
			(clearance 0)
		)
		(min_thickness 0.25)
		(keepout
			(tracks allowed)
			(vias allowed)
			(pads allowed)
			(copperpour allowed)
			(footprints allowed)
		)
		(placement
			(enabled no)
			(sheetname "")
		)
		(fill
			(thermal_gap 0.5)
			(thermal_bridge_width 0.5)
			(island_removal_mode 0)
		)
		(polygon
			(pts
				(xy 283.700982 -262.598154) (xy 283.700982 -261.243318) (xy 284.178248 -261.243318) (xy 284.178248 -262.598154)
			)
		)
	)
	(zone
		(layer "In4.Cu")
		(hatch none 0.5)
		(connect_pads
			(clearance 0)
		)
		(min_thickness 0.25)
		(keepout
			(tracks allowed)
			(vias allowed)
			(pads allowed)
			(copperpour allowed)
			(footprints allowed)
		)
		(placement
			(enabled no)
			(sheetname "")
		)
		(fill
			(thermal_gap 0.5)
			(thermal_bridge_width 0.5)
			(island_removal_mode 0)
		)
		(polygon
			(pts
				(xy 435.558692 -316.693042) (xy 435.558692 -315.338206) (xy 436.035958 -315.338206) (xy 436.035958 -316.693042)
			)
		)
	)
	(zone
		(layer "In4.Cu")
		(hatch none 0.5)
		(connect_pads
			(clearance 0)
		)
		(min_thickness 0.25)
		(keepout
			(tracks allowed)
			(vias allowed)
			(pads allowed)
			(copperpour allowed)
			(footprints allowed)
		)
		(placement
			(enabled no)
			(sheetname "")
		)
		(fill
			(thermal_gap 0.5)
			(thermal_bridge_width 0.5)
			(island_removal_mode 0)
		)
		(polygon
			(pts
				(xy 296.49928 -268.083538) (xy 296.49928 -265.952478) (xy 297.01236 -265.952478) (xy 297.01236 -268.083538)
			)
		)
	)
	(zone
		(layers "In4.Cu" "In6.Cu")
		(hatch none 0.5)
		(connect_pads
			(clearance 0)
		)
		(min_thickness 0.25)
		(keepout
			(tracks not_allowed)
			(vias allowed)
			(pads allowed)
			(copperpour not_allowed)
			(footprints allowed)
		)
		(placement
			(enabled no)
			(sheetname "")
		)
		(fill yes
			(thermal_gap 0.5)
			(thermal_bridge_width 0.5)
			(island_removal_mode 0)
		)
		(polygon
			(pts
				(xy 89.125806 -359.741978) (xy 95.464122 -359.741978) (xy 96.136206 -359.069894) (xy 96.136206 -355.740208)
				(xy 95.937832 -355.541834) (xy 89.278714 -355.541834) (xy 88.927432 -355.893116) (xy 88.927432 -359.543604)
			)
		)
	)
	(zone
		(layers "In4.Cu" "In6.Cu" "In11.Cu")
		(hatch none 0.5)
		(connect_pads
			(clearance 0)
		)
		(min_thickness 0.25)
		(keepout
			(tracks not_allowed)
			(vias allowed)
			(pads allowed)
			(copperpour not_allowed)
			(footprints allowed)
		)
		(placement
			(enabled no)
			(sheetname "")
		)
		(fill yes
			(thermal_gap 0.5)
			(thermal_bridge_width 0.5)
			(island_removal_mode 0)
		)
		(polygon
			(pts
				(arc
					(start 298.820332 -435.600094)
					(mid 288.279332 -435.600094)
					(end 298.820332 -435.600094)
				)
			)
		)
	)
	(zone
		(layers "In5.Cu" "In7.Cu")
		(hatch none 0.5)
		(connect_pads
			(clearance 0)
		)
		(min_thickness 0.25)
		(keepout
			(tracks not_allowed)
			(vias allowed)
			(pads allowed)
			(copperpour not_allowed)
			(footprints allowed)
		)
		(placement
			(enabled no)
			(sheetname "")
		)
		(fill yes
			(thermal_gap 0.5)
			(thermal_bridge_width 0.5)
			(island_removal_mode 0)
		)
		(polygon
			(pts
				(arc
					(start 75.14209 -427.960536)
					(mid 75.164408 -428.014418)
					(end 75.21829 -428.036736)
				)
				(arc
					(start 76.15809 -428.036736)
					(mid 76.211972 -428.014418)
					(end 76.23429 -427.960536)
				)
				(arc
					(start 76.23429 -425.419012)
					(mid 76.211972 -425.36513)
					(end 76.15809 -425.342812)
				)
				(arc
					(start 75.21829 -425.342812)
					(mid 75.164408 -425.36513)
					(end 75.14209 -425.419012)
				)
				(arc
					(start 75.14209 -426.146468)
					(mid 75.144089 -426.163809)
					(end 75.149964 -426.18025)
				)
				(arc
					(start 75.38339 -426.6565)
					(mid 75.391173 -426.690028)
					(end 75.38339 -426.723556)
				)
				(arc
					(start 75.149964 -427.199806)
					(mid 75.144069 -427.216242)
					(end 75.14209 -427.233588)
				)
			)
		)
	)
	(zone
		(layers "In5.Cu" "In7.Cu")
		(hatch none 0.5)
		(connect_pads
			(clearance 0)
		)
		(min_thickness 0.25)
		(keepout
			(tracks not_allowed)
			(vias allowed)
			(pads allowed)
			(copperpour not_allowed)
			(footprints allowed)
		)
		(placement
			(enabled no)
			(sheetname "")
		)
		(fill yes
			(thermal_gap 0.5)
			(thermal_bridge_width 0.5)
			(island_removal_mode 0)
		)
		(polygon
			(pts
				(arc
					(start 129.242058 -431.560478)
					(mid 129.264376 -431.61436)
					(end 129.318258 -431.636678)
				)
				(arc
					(start 130.258058 -431.636678)
					(mid 130.31194 -431.61436)
					(end 130.334258 -431.560478)
				)
				(arc
					(start 130.334258 -429.018954)
					(mid 130.31194 -428.965072)
					(end 130.258058 -428.942754)
				)
				(arc
					(start 129.318258 -428.942754)
					(mid 129.264376 -428.965072)
					(end 129.242058 -429.018954)
				)
				(arc
					(start 129.242058 -429.74641)
					(mid 129.244057 -429.763751)
					(end 129.249932 -429.780192)
				)
				(arc
					(start 129.483358 -430.256442)
					(mid 129.491141 -430.28997)
					(end 129.483358 -430.323498)
				)
				(arc
					(start 129.249932 -430.799748)
					(mid 129.244037 -430.816184)
					(end 129.242058 -430.83353)
				)
			)
		)
	)
	(zone
		(layers "In5.Cu" "In7.Cu")
		(hatch none 0.5)
		(connect_pads
			(clearance 0)
		)
		(min_thickness 0.25)
		(keepout
			(tracks not_allowed)
			(vias allowed)
			(pads allowed)
			(copperpour not_allowed)
			(footprints allowed)
		)
		(placement
			(enabled no)
			(sheetname "")
		)
		(fill yes
			(thermal_gap 0.5)
			(thermal_bridge_width 0.5)
			(island_removal_mode 0)
		)
		(polygon
			(pts
				(arc
					(start 87.142066 -427.960536)
					(mid 87.164384 -428.014418)
					(end 87.218266 -428.036736)
				)
				(arc
					(start 88.158066 -428.036736)
					(mid 88.211948 -428.014418)
					(end 88.234266 -427.960536)
				)
				(arc
					(start 88.234266 -425.419012)
					(mid 88.211948 -425.36513)
					(end 88.158066 -425.342812)
				)
				(arc
					(start 87.218266 -425.342812)
					(mid 87.164384 -425.36513)
					(end 87.142066 -425.419012)
				)
				(arc
					(start 87.142066 -426.146468)
					(mid 87.144065 -426.163809)
					(end 87.14994 -426.18025)
				)
				(arc
					(start 87.383366 -426.6565)
					(mid 87.391149 -426.690028)
					(end 87.383366 -426.723556)
				)
				(arc
					(start 87.14994 -427.199806)
					(mid 87.144045 -427.216242)
					(end 87.142066 -427.233588)
				)
			)
		)
	)
	(zone
		(layers "In5.Cu" "In7.Cu")
		(hatch none 0.5)
		(connect_pads
			(clearance 0)
		)
		(min_thickness 0.25)
		(keepout
			(tracks not_allowed)
			(vias allowed)
			(pads allowed)
			(copperpour not_allowed)
			(footprints allowed)
		)
		(placement
			(enabled no)
			(sheetname "")
		)
		(fill yes
			(thermal_gap 0.5)
			(thermal_bridge_width 0.5)
			(island_removal_mode 0)
		)
		(polygon
			(pts
				(arc
					(start 154.242008 -431.560478)
					(mid 154.264326 -431.61436)
					(end 154.318208 -431.636678)
				)
				(arc
					(start 155.258008 -431.636678)
					(mid 155.31189 -431.61436)
					(end 155.334208 -431.560478)
				)
				(arc
					(start 155.334208 -429.018954)
					(mid 155.31189 -428.965072)
					(end 155.258008 -428.942754)
				)
				(arc
					(start 154.318208 -428.942754)
					(mid 154.264326 -428.965072)
					(end 154.242008 -429.018954)
				)
				(arc
					(start 154.242008 -429.74641)
					(mid 154.244007 -429.763751)
					(end 154.249882 -429.780192)
				)
				(arc
					(start 154.483308 -430.256442)
					(mid 154.491091 -430.28997)
					(end 154.483308 -430.323498)
				)
				(arc
					(start 154.249882 -430.799748)
					(mid 154.243987 -430.816184)
					(end 154.242008 -430.83353)
				)
			)
		)
	)
	(zone
		(layers "In5.Cu" "In7.Cu")
		(hatch none 0.5)
		(connect_pads
			(clearance 0)
		)
		(min_thickness 0.25)
		(keepout
			(tracks not_allowed)
			(vias allowed)
			(pads allowed)
			(copperpour not_allowed)
			(footprints allowed)
		)
		(placement
			(enabled no)
			(sheetname "")
		)
		(fill yes
			(thermal_gap 0.5)
			(thermal_bridge_width 0.5)
			(island_removal_mode 0)
		)
		(polygon
			(pts
				(arc
					(start 85.14207 -428.960534)
					(mid 85.164388 -429.014416)
					(end 85.21827 -429.036734)
				)
				(arc
					(start 86.15807 -429.036734)
					(mid 86.211952 -429.014416)
					(end 86.23427 -428.960534)
				)
				(arc
					(start 86.23427 -426.41901)
					(mid 86.211952 -426.365128)
					(end 86.15807 -426.34281)
				)
				(arc
					(start 85.21827 -426.34281)
					(mid 85.164388 -426.365128)
					(end 85.14207 -426.41901)
				)
				(arc
					(start 85.14207 -427.146466)
					(mid 85.144069 -427.163807)
					(end 85.149944 -427.180248)
				)
				(arc
					(start 85.38337 -427.656498)
					(mid 85.391153 -427.690026)
					(end 85.38337 -427.723554)
				)
				(arc
					(start 85.149944 -428.199804)
					(mid 85.144049 -428.21624)
					(end 85.14207 -428.233586)
				)
			)
		)
	)
	(zone
		(layers "In5.Cu" "In7.Cu")
		(hatch none 0.5)
		(connect_pads
			(clearance 0)
		)
		(min_thickness 0.25)
		(keepout
			(tracks not_allowed)
			(vias allowed)
			(pads allowed)
			(copperpour not_allowed)
			(footprints allowed)
		)
		(placement
			(enabled no)
			(sheetname "")
		)
		(fill yes
			(thermal_gap 0.5)
			(thermal_bridge_width 0.5)
			(island_removal_mode 0)
		)
		(polygon
			(pts
				(arc
					(start 395.242034 -432.560476)
					(mid 395.264352 -432.614358)
					(end 395.318234 -432.636676)
				)
				(arc
					(start 396.258034 -432.636676)
					(mid 396.311916 -432.614358)
					(end 396.334234 -432.560476)
				)
				(arc
					(start 396.334234 -430.018952)
					(mid 396.311916 -429.96507)
					(end 396.258034 -429.942752)
				)
				(arc
					(start 395.318234 -429.942752)
					(mid 395.264352 -429.96507)
					(end 395.242034 -430.018952)
				)
				(arc
					(start 395.242034 -430.746408)
					(mid 395.244033 -430.763749)
					(end 395.249908 -430.78019)
				)
				(arc
					(start 395.483334 -431.25644)
					(mid 395.491117 -431.289968)
					(end 395.483334 -431.323496)
				)
				(arc
					(start 395.249908 -431.799746)
					(mid 395.244013 -431.816182)
					(end 395.242034 -431.833528)
				)
			)
		)
	)
	(zone
		(layers "In5.Cu" "In7.Cu")
		(hatch none 0.5)
		(connect_pads
			(clearance 0)
		)
		(min_thickness 0.25)
		(keepout
			(tracks not_allowed)
			(vias allowed)
			(pads allowed)
			(copperpour not_allowed)
			(footprints allowed)
		)
		(placement
			(enabled no)
			(sheetname "")
		)
		(fill yes
			(thermal_gap 0.5)
			(thermal_bridge_width 0.5)
			(island_removal_mode 0)
		)
		(polygon
			(pts
				(arc
					(start 127.242062 -432.560476)
					(mid 127.26438 -432.614358)
					(end 127.318262 -432.636676)
				)
				(arc
					(start 128.258062 -432.636676)
					(mid 128.311944 -432.614358)
					(end 128.334262 -432.560476)
				)
				(arc
					(start 128.334262 -430.018952)
					(mid 128.311944 -429.96507)
					(end 128.258062 -429.942752)
				)
				(arc
					(start 127.318262 -429.942752)
					(mid 127.26438 -429.96507)
					(end 127.242062 -430.018952)
				)
				(arc
					(start 127.242062 -430.746408)
					(mid 127.244061 -430.763749)
					(end 127.249936 -430.78019)
				)
				(arc
					(start 127.483362 -431.25644)
					(mid 127.491145 -431.289968)
					(end 127.483362 -431.323496)
				)
				(arc
					(start 127.249936 -431.799746)
					(mid 127.244041 -431.816182)
					(end 127.242062 -431.833528)
				)
			)
		)
	)
	(zone
		(layers "In5.Cu" "In7.Cu")
		(hatch none 0.5)
		(connect_pads
			(clearance 0)
		)
		(min_thickness 0.25)
		(keepout
			(tracks not_allowed)
			(vias allowed)
			(pads allowed)
			(copperpour not_allowed)
			(footprints allowed)
		)
		(placement
			(enabled no)
			(sheetname "")
		)
		(fill yes
			(thermal_gap 0.5)
			(thermal_bridge_width 0.5)
			(island_removal_mode 0)
		)
		(polygon
			(pts
				(arc
					(start 381.242062 -431.560478)
					(mid 381.26438 -431.61436)
					(end 381.318262 -431.636678)
				)
				(arc
					(start 382.258062 -431.636678)
					(mid 382.311944 -431.61436)
					(end 382.334262 -431.560478)
				)
				(arc
					(start 382.334262 -429.018954)
					(mid 382.311944 -428.965072)
					(end 382.258062 -428.942754)
				)
				(arc
					(start 381.318262 -428.942754)
					(mid 381.26438 -428.965072)
					(end 381.242062 -429.018954)
				)
				(arc
					(start 381.242062 -429.74641)
					(mid 381.244061 -429.763751)
					(end 381.249936 -429.780192)
				)
				(arc
					(start 381.483362 -430.256442)
					(mid 381.491145 -430.28997)
					(end 381.483362 -430.323498)
				)
				(arc
					(start 381.249936 -430.799748)
					(mid 381.244041 -430.816184)
					(end 381.242062 -430.83353)
				)
			)
		)
	)
	(zone
		(layers "In5.Cu" "In7.Cu")
		(hatch none 0.5)
		(connect_pads
			(clearance 0)
		)
		(min_thickness 0.25)
		(keepout
			(tracks not_allowed)
			(vias allowed)
			(pads allowed)
			(copperpour not_allowed)
			(footprints allowed)
		)
		(placement
			(enabled no)
			(sheetname "")
		)
		(fill yes
			(thermal_gap 0.5)
			(thermal_bridge_width 0.5)
			(island_removal_mode 0)
		)
		(polygon
			(pts
				(arc
					(start 393.242038 -431.560478)
					(mid 393.264356 -431.61436)
					(end 393.318238 -431.636678)
				)
				(arc
					(start 394.258038 -431.636678)
					(mid 394.31192 -431.61436)
					(end 394.334238 -431.560478)
				)
				(arc
					(start 394.334238 -429.018954)
					(mid 394.31192 -428.965072)
					(end 394.258038 -428.942754)
				)
				(arc
					(start 393.318238 -428.942754)
					(mid 393.264356 -428.965072)
					(end 393.242038 -429.018954)
				)
				(arc
					(start 393.242038 -429.74641)
					(mid 393.244037 -429.763751)
					(end 393.249912 -429.780192)
				)
				(arc
					(start 393.483338 -430.256442)
					(mid 393.491121 -430.28997)
					(end 393.483338 -430.323498)
				)
				(arc
					(start 393.249912 -430.799748)
					(mid 393.244017 -430.816184)
					(end 393.242038 -430.83353)
				)
			)
		)
	)
	(zone
		(layers "In5.Cu" "In7.Cu")
		(hatch none 0.5)
		(connect_pads
			(clearance 0)
		)
		(min_thickness 0.25)
		(keepout
			(tracks not_allowed)
			(vias allowed)
			(pads allowed)
			(copperpour not_allowed)
			(footprints allowed)
		)
		(placement
			(enabled no)
			(sheetname "")
		)
		(fill yes
			(thermal_gap 0.5)
			(thermal_bridge_width 0.5)
			(island_removal_mode 0)
		)
		(polygon
			(pts
				(arc
					(start 389.242046 -431.560478)
					(mid 389.264364 -431.61436)
					(end 389.318246 -431.636678)
				)
				(arc
					(start 390.258046 -431.636678)
					(mid 390.311928 -431.61436)
					(end 390.334246 -431.560478)
				)
				(arc
					(start 390.334246 -429.018954)
					(mid 390.311928 -428.965072)
					(end 390.258046 -428.942754)
				)
				(arc
					(start 389.318246 -428.942754)
					(mid 389.264364 -428.965072)
					(end 389.242046 -429.018954)
				)
				(arc
					(start 389.242046 -429.74641)
					(mid 389.244045 -429.763751)
					(end 389.24992 -429.780192)
				)
				(arc
					(start 389.483346 -430.256442)
					(mid 389.491129 -430.28997)
					(end 389.483346 -430.323498)
				)
				(arc
					(start 389.24992 -430.799748)
					(mid 389.244025 -430.816184)
					(end 389.242046 -430.83353)
				)
			)
		)
	)
	(zone
		(layers "In5.Cu" "In7.Cu")
		(hatch none 0.5)
		(connect_pads
			(clearance 0)
		)
		(min_thickness 0.25)
		(keepout
			(tracks not_allowed)
			(vias allowed)
			(pads allowed)
			(copperpour not_allowed)
			(footprints allowed)
		)
		(placement
			(enabled no)
			(sheetname "")
		)
		(fill yes
			(thermal_gap 0.5)
			(thermal_bridge_width 0.5)
			(island_removal_mode 0)
		)
		(polygon
			(pts
				(arc
					(start 412.242 -432.560476)
					(mid 412.264318 -432.614358)
					(end 412.3182 -432.636676)
				)
				(arc
					(start 413.258 -432.636676)
					(mid 413.311882 -432.614358)
					(end 413.3342 -432.560476)
				)
				(arc
					(start 413.3342 -430.018952)
					(mid 413.311882 -429.96507)
					(end 413.258 -429.942752)
				)
				(arc
					(start 412.3182 -429.942752)
					(mid 412.264318 -429.96507)
					(end 412.242 -430.018952)
				)
				(arc
					(start 412.242 -430.746408)
					(mid 412.243999 -430.763749)
					(end 412.249874 -430.78019)
				)
				(arc
					(start 412.4833 -431.25644)
					(mid 412.491083 -431.289968)
					(end 412.4833 -431.323496)
				)
				(arc
					(start 412.249874 -431.799746)
					(mid 412.243979 -431.816182)
					(end 412.242 -431.833528)
				)
			)
		)
	)
	(zone
		(layers "In5.Cu" "In7.Cu")
		(hatch none 0.5)
		(connect_pads
			(clearance 0)
		)
		(min_thickness 0.25)
		(keepout
			(tracks not_allowed)
			(vias allowed)
			(pads allowed)
			(copperpour not_allowed)
			(footprints allowed)
		)
		(placement
			(enabled no)
			(sheetname "")
		)
		(fill yes
			(thermal_gap 0.5)
			(thermal_bridge_width 0.5)
			(island_removal_mode 0)
		)
		(polygon
			(pts
				(arc
					(start 404.242016 -432.560476)
					(mid 404.264334 -432.614358)
					(end 404.318216 -432.636676)
				)
				(arc
					(start 405.258016 -432.636676)
					(mid 405.311898 -432.614358)
					(end 405.334216 -432.560476)
				)
				(arc
					(start 405.334216 -430.018952)
					(mid 405.311898 -429.96507)
					(end 405.258016 -429.942752)
				)
				(arc
					(start 404.318216 -429.942752)
					(mid 404.264334 -429.96507)
					(end 404.242016 -430.018952)
				)
				(arc
					(start 404.242016 -430.746408)
					(mid 404.244015 -430.763749)
					(end 404.24989 -430.78019)
				)
				(arc
					(start 404.483316 -431.25644)
					(mid 404.491099 -431.289968)
					(end 404.483316 -431.323496)
				)
				(arc
					(start 404.24989 -431.799746)
					(mid 404.243995 -431.816182)
					(end 404.242016 -431.833528)
				)
			)
		)
	)
	(zone
		(layers "In5.Cu" "In7.Cu")
		(hatch none 0.5)
		(connect_pads
			(clearance 0)
		)
		(min_thickness 0.25)
		(keepout
			(tracks not_allowed)
			(vias allowed)
			(pads allowed)
			(copperpour not_allowed)
			(footprints allowed)
		)
		(placement
			(enabled no)
			(sheetname "")
		)
		(fill yes
			(thermal_gap 0.5)
			(thermal_bridge_width 0.5)
			(island_removal_mode 0)
		)
		(polygon
			(pts
				(arc
					(start 60.14212 -428.960534)
					(mid 60.164438 -429.014416)
					(end 60.21832 -429.036734)
				)
				(arc
					(start 61.15812 -429.036734)
					(mid 61.212002 -429.014416)
					(end 61.23432 -428.960534)
				)
				(arc
					(start 61.23432 -426.41901)
					(mid 61.212002 -426.365128)
					(end 61.15812 -426.34281)
				)
				(arc
					(start 60.21832 -426.34281)
					(mid 60.164438 -426.365128)
					(end 60.14212 -426.41901)
				)
				(arc
					(start 60.14212 -427.146466)
					(mid 60.144119 -427.163807)
					(end 60.149994 -427.180248)
				)
				(arc
					(start 60.38342 -427.656498)
					(mid 60.391203 -427.690026)
					(end 60.38342 -427.723554)
				)
				(arc
					(start 60.149994 -428.199804)
					(mid 60.144099 -428.21624)
					(end 60.14212 -428.233586)
				)
			)
		)
	)
	(zone
		(layers "In5.Cu" "In7.Cu")
		(hatch none 0.5)
		(connect_pads
			(clearance 0)
		)
		(min_thickness 0.25)
		(keepout
			(tracks not_allowed)
			(vias allowed)
			(pads allowed)
			(copperpour not_allowed)
			(footprints allowed)
		)
		(placement
			(enabled no)
			(sheetname "")
		)
		(fill yes
			(thermal_gap 0.5)
			(thermal_bridge_width 0.5)
			(island_removal_mode 0)
		)
		(polygon
			(pts
				(arc
					(start 148.24202 -432.560476)
					(mid 148.264338 -432.614358)
					(end 148.31822 -432.636676)
				)
				(arc
					(start 149.25802 -432.636676)
					(mid 149.311902 -432.614358)
					(end 149.33422 -432.560476)
				)
				(arc
					(start 149.33422 -430.018952)
					(mid 149.311902 -429.96507)
					(end 149.25802 -429.942752)
				)
				(arc
					(start 148.31822 -429.942752)
					(mid 148.264338 -429.96507)
					(end 148.24202 -430.018952)
				)
				(arc
					(start 148.24202 -430.746408)
					(mid 148.244019 -430.763749)
					(end 148.249894 -430.78019)
				)
				(arc
					(start 148.48332 -431.25644)
					(mid 148.491103 -431.289968)
					(end 148.48332 -431.323496)
				)
				(arc
					(start 148.249894 -431.799746)
					(mid 148.243999 -431.816182)
					(end 148.24202 -431.833528)
				)
			)
		)
	)
	(zone
		(layers "In5.Cu" "In7.Cu")
		(hatch none 0.5)
		(connect_pads
			(clearance 0)
		)
		(min_thickness 0.25)
		(keepout
			(tracks not_allowed)
			(vias allowed)
			(pads allowed)
			(copperpour not_allowed)
			(footprints allowed)
		)
		(placement
			(enabled no)
			(sheetname "")
		)
		(fill yes
			(thermal_gap 0.5)
			(thermal_bridge_width 0.5)
			(island_removal_mode 0)
		)
		(polygon
			(pts
				(arc
					(start 152.242012 -432.560476)
					(mid 152.26433 -432.614358)
					(end 152.318212 -432.636676)
				)
				(arc
					(start 153.258012 -432.636676)
					(mid 153.311894 -432.614358)
					(end 153.334212 -432.560476)
				)
				(arc
					(start 153.334212 -430.018952)
					(mid 153.311894 -429.96507)
					(end 153.258012 -429.942752)
				)
				(arc
					(start 152.318212 -429.942752)
					(mid 152.26433 -429.96507)
					(end 152.242012 -430.018952)
				)
				(arc
					(start 152.242012 -430.746408)
					(mid 152.244011 -430.763749)
					(end 152.249886 -430.78019)
				)
				(arc
					(start 152.483312 -431.25644)
					(mid 152.491095 -431.289968)
					(end 152.483312 -431.323496)
				)
				(arc
					(start 152.249886 -431.799746)
					(mid 152.243991 -431.816182)
					(end 152.242012 -431.833528)
				)
			)
		)
	)
	(zone
		(layers "In5.Cu" "In7.Cu")
		(hatch none 0.5)
		(connect_pads
			(clearance 0)
		)
		(min_thickness 0.25)
		(keepout
			(tracks not_allowed)
			(vias allowed)
			(pads allowed)
			(copperpour not_allowed)
			(footprints allowed)
		)
		(placement
			(enabled no)
			(sheetname "")
		)
		(fill yes
			(thermal_gap 0.5)
			(thermal_bridge_width 0.5)
			(island_removal_mode 0)
		)
		(polygon
			(pts
				(arc
					(start 341.142066 -428.96028)
					(mid 341.164384 -429.014162)
					(end 341.218266 -429.03648)
				)
				(arc
					(start 342.158066 -429.03648)
					(mid 342.211948 -429.014162)
					(end 342.234266 -428.96028)
				)
				(arc
					(start 342.234266 -426.418756)
					(mid 342.211948 -426.364874)
					(end 342.158066 -426.342556)
				)
				(arc
					(start 341.218266 -426.342556)
					(mid 341.164384 -426.364874)
					(end 341.142066 -426.418756)
				)
				(arc
					(start 341.142066 -427.146212)
					(mid 341.144065 -427.163553)
					(end 341.14994 -427.179994)
				)
				(arc
					(start 341.383366 -427.656244)
					(mid 341.391149 -427.689772)
					(end 341.383366 -427.7233)
				)
				(arc
					(start 341.14994 -428.19955)
					(mid 341.144045 -428.215986)
					(end 341.142066 -428.233332)
				)
			)
		)
	)
	(zone
		(layers "In5.Cu" "In7.Cu")
		(hatch none 0.5)
		(connect_pads
			(clearance 0)
		)
		(min_thickness 0.25)
		(keepout
			(tracks not_allowed)
			(vias allowed)
			(pads allowed)
			(copperpour not_allowed)
			(footprints allowed)
		)
		(placement
			(enabled no)
			(sheetname "")
		)
		(fill yes
			(thermal_gap 0.5)
			(thermal_bridge_width 0.5)
			(island_removal_mode 0)
		)
		(polygon
			(pts
				(arc
					(start 142.242032 -431.560478)
					(mid 142.26435 -431.61436)
					(end 142.318232 -431.636678)
				)
				(arc
					(start 143.258032 -431.636678)
					(mid 143.311914 -431.61436)
					(end 143.334232 -431.560478)
				)
				(arc
					(start 143.334232 -429.018954)
					(mid 143.311914 -428.965072)
					(end 143.258032 -428.942754)
				)
				(arc
					(start 142.318232 -428.942754)
					(mid 142.26435 -428.965072)
					(end 142.242032 -429.018954)
				)
				(arc
					(start 142.242032 -429.74641)
					(mid 142.244031 -429.763751)
					(end 142.249906 -429.780192)
				)
				(arc
					(start 142.483332 -430.256442)
					(mid 142.491115 -430.28997)
					(end 142.483332 -430.323498)
				)
				(arc
					(start 142.249906 -430.799748)
					(mid 142.244011 -430.816184)
					(end 142.242032 -430.83353)
				)
			)
		)
	)
	(zone
		(layers "In5.Cu" "In7.Cu")
		(hatch none 0.5)
		(connect_pads
			(clearance 0)
		)
		(min_thickness 0.25)
		(keepout
			(tracks not_allowed)
			(vias allowed)
			(pads allowed)
			(copperpour not_allowed)
			(footprints allowed)
		)
		(placement
			(enabled no)
			(sheetname "")
		)
		(fill yes
			(thermal_gap 0.5)
			(thermal_bridge_width 0.5)
			(island_removal_mode 0)
		)
		(polygon
			(pts
				(arc
					(start 387.24205 -432.560476)
					(mid 387.264368 -432.614358)
					(end 387.31825 -432.636676)
				)
				(arc
					(start 388.25805 -432.636676)
					(mid 388.311932 -432.614358)
					(end 388.33425 -432.560476)
				)
				(arc
					(start 388.33425 -430.018952)
					(mid 388.311932 -429.96507)
					(end 388.25805 -429.942752)
				)
				(arc
					(start 387.31825 -429.942752)
					(mid 387.264368 -429.96507)
					(end 387.24205 -430.018952)
				)
				(arc
					(start 387.24205 -430.746408)
					(mid 387.244049 -430.763749)
					(end 387.249924 -430.78019)
				)
				(arc
					(start 387.48335 -431.25644)
					(mid 387.491133 -431.289968)
					(end 387.48335 -431.323496)
				)
				(arc
					(start 387.249924 -431.799746)
					(mid 387.244029 -431.816182)
					(end 387.24205 -431.833528)
				)
			)
		)
	)
	(zone
		(layers "In5.Cu" "In7.Cu")
		(hatch none 0.5)
		(connect_pads
			(clearance 0)
		)
		(min_thickness 0.25)
		(keepout
			(tracks not_allowed)
			(vias allowed)
			(pads allowed)
			(copperpour not_allowed)
			(footprints allowed)
		)
		(placement
			(enabled no)
			(sheetname "")
		)
		(fill yes
			(thermal_gap 0.5)
			(thermal_bridge_width 0.5)
			(island_removal_mode 0)
		)
		(polygon
			(pts
				(arc
					(start 398.242028 -431.560478)
					(mid 398.264346 -431.61436)
					(end 398.318228 -431.636678)
				)
				(arc
					(start 399.258028 -431.636678)
					(mid 399.31191 -431.61436)
					(end 399.334228 -431.560478)
				)
				(arc
					(start 399.334228 -429.018954)
					(mid 399.31191 -428.965072)
					(end 399.258028 -428.942754)
				)
				(arc
					(start 398.318228 -428.942754)
					(mid 398.264346 -428.965072)
					(end 398.242028 -429.018954)
				)
				(arc
					(start 398.242028 -429.74641)
					(mid 398.244027 -429.763751)
					(end 398.249902 -429.780192)
				)
				(arc
					(start 398.483328 -430.256442)
					(mid 398.491111 -430.28997)
					(end 398.483328 -430.323498)
				)
				(arc
					(start 398.249902 -430.799748)
					(mid 398.244007 -430.816184)
					(end 398.242028 -430.83353)
				)
			)
		)
	)
	(zone
		(layers "In5.Cu" "In7.Cu")
		(hatch none 0.5)
		(connect_pads
			(clearance 0)
		)
		(min_thickness 0.25)
		(keepout
			(tracks not_allowed)
			(vias allowed)
			(pads allowed)
			(copperpour not_allowed)
			(footprints allowed)
		)
		(placement
			(enabled no)
			(sheetname "")
		)
		(fill yes
			(thermal_gap 0.5)
			(thermal_bridge_width 0.5)
			(island_removal_mode 0)
		)
		(polygon
			(pts
				(arc
					(start 62.142116 -427.960536)
					(mid 62.164434 -428.014418)
					(end 62.218316 -428.036736)
				)
				(arc
					(start 63.158116 -428.036736)
					(mid 63.211998 -428.014418)
					(end 63.234316 -427.960536)
				)
				(arc
					(start 63.234316 -425.419012)
					(mid 63.211998 -425.36513)
					(end 63.158116 -425.342812)
				)
				(arc
					(start 62.218316 -425.342812)
					(mid 62.164434 -425.36513)
					(end 62.142116 -425.419012)
				)
				(arc
					(start 62.142116 -426.146468)
					(mid 62.144115 -426.163809)
					(end 62.14999 -426.18025)
				)
				(arc
					(start 62.383416 -426.6565)
					(mid 62.391199 -426.690028)
					(end 62.383416 -426.723556)
				)
				(arc
					(start 62.14999 -427.199806)
					(mid 62.144095 -427.216242)
					(end 62.142116 -427.233588)
				)
			)
		)
	)
	(zone
		(layers "In5.Cu" "In7.Cu")
		(hatch none 0.5)
		(connect_pads
			(clearance 0)
		)
		(min_thickness 0.25)
		(keepout
			(tracks not_allowed)
			(vias allowed)
			(pads allowed)
			(copperpour not_allowed)
			(footprints allowed)
		)
		(placement
			(enabled no)
			(sheetname "")
		)
		(fill yes
			(thermal_gap 0.5)
			(thermal_bridge_width 0.5)
			(island_removal_mode 0)
		)
		(polygon
			(pts
				(arc
					(start 68.142104 -428.960534)
					(mid 68.164422 -429.014416)
					(end 68.218304 -429.036734)
				)
				(arc
					(start 69.158104 -429.036734)
					(mid 69.211986 -429.014416)
					(end 69.234304 -428.960534)
				)
				(arc
					(start 69.234304 -426.41901)
					(mid 69.211986 -426.365128)
					(end 69.158104 -426.34281)
				)
				(arc
					(start 68.218304 -426.34281)
					(mid 68.164422 -426.365128)
					(end 68.142104 -426.41901)
				)
				(arc
					(start 68.142104 -427.146466)
					(mid 68.144103 -427.163807)
					(end 68.149978 -427.180248)
				)
				(arc
					(start 68.383404 -427.656498)
					(mid 68.391187 -427.690026)
					(end 68.383404 -427.723554)
				)
				(arc
					(start 68.149978 -428.199804)
					(mid 68.144083 -428.21624)
					(end 68.142104 -428.233586)
				)
			)
		)
	)
	(zone
		(layers "In5.Cu" "In7.Cu")
		(hatch none 0.5)
		(connect_pads
			(clearance 0)
		)
		(min_thickness 0.25)
		(keepout
			(tracks not_allowed)
			(vias allowed)
			(pads allowed)
			(copperpour not_allowed)
			(footprints allowed)
		)
		(placement
			(enabled no)
			(sheetname "")
		)
		(fill yes
			(thermal_gap 0.5)
			(thermal_bridge_width 0.5)
			(island_removal_mode 0)
		)
		(polygon
			(pts
				(arc
					(start 66.142108 -427.960536)
					(mid 66.164426 -428.014418)
					(end 66.218308 -428.036736)
				)
				(arc
					(start 67.158108 -428.036736)
					(mid 67.21199 -428.014418)
					(end 67.234308 -427.960536)
				)
				(arc
					(start 67.234308 -425.419012)
					(mid 67.21199 -425.36513)
					(end 67.158108 -425.342812)
				)
				(arc
					(start 66.218308 -425.342812)
					(mid 66.164426 -425.36513)
					(end 66.142108 -425.419012)
				)
				(arc
					(start 66.142108 -426.146468)
					(mid 66.144107 -426.163809)
					(end 66.149982 -426.18025)
				)
				(arc
					(start 66.383408 -426.6565)
					(mid 66.391191 -426.690028)
					(end 66.383408 -426.723556)
				)
				(arc
					(start 66.149982 -427.199806)
					(mid 66.144087 -427.216242)
					(end 66.142108 -427.233588)
				)
			)
		)
	)
	(zone
		(layers "In5.Cu" "In7.Cu")
		(hatch none 0.5)
		(connect_pads
			(clearance 0)
		)
		(min_thickness 0.25)
		(keepout
			(tracks not_allowed)
			(vias allowed)
			(pads allowed)
			(copperpour not_allowed)
			(footprints allowed)
		)
		(placement
			(enabled no)
			(sheetname "")
		)
		(fill yes
			(thermal_gap 0.5)
			(thermal_bridge_width 0.5)
			(island_removal_mode 0)
		)
		(polygon
			(pts
				(arc
					(start 391.242042 -432.560476)
					(mid 391.26436 -432.614358)
					(end 391.318242 -432.636676)
				)
				(arc
					(start 392.258042 -432.636676)
					(mid 392.311924 -432.614358)
					(end 392.334242 -432.560476)
				)
				(arc
					(start 392.334242 -430.018952)
					(mid 392.311924 -429.96507)
					(end 392.258042 -429.942752)
				)
				(arc
					(start 391.318242 -429.942752)
					(mid 391.26436 -429.96507)
					(end 391.242042 -430.018952)
				)
				(arc
					(start 391.242042 -430.746408)
					(mid 391.244041 -430.763749)
					(end 391.249916 -430.78019)
				)
				(arc
					(start 391.483342 -431.25644)
					(mid 391.491125 -431.289968)
					(end 391.483342 -431.323496)
				)
				(arc
					(start 391.249916 -431.799746)
					(mid 391.244021 -431.816182)
					(end 391.242042 -431.833528)
				)
			)
		)
	)
	(zone
		(layers "In5.Cu" "In7.Cu")
		(hatch none 0.5)
		(connect_pads
			(clearance 0)
		)
		(min_thickness 0.25)
		(keepout
			(tracks not_allowed)
			(vias allowed)
			(pads allowed)
			(copperpour not_allowed)
			(footprints allowed)
		)
		(placement
			(enabled no)
			(sheetname "")
		)
		(fill yes
			(thermal_gap 0.5)
			(thermal_bridge_width 0.5)
			(island_removal_mode 0)
		)
		(polygon
			(pts
				(arc
					(start 72.142096 -428.960534)
					(mid 72.164414 -429.014416)
					(end 72.218296 -429.036734)
				)
				(arc
					(start 73.158096 -429.036734)
					(mid 73.211978 -429.014416)
					(end 73.234296 -428.960534)
				)
				(arc
					(start 73.234296 -426.41901)
					(mid 73.211978 -426.365128)
					(end 73.158096 -426.34281)
				)
				(arc
					(start 72.218296 -426.34281)
					(mid 72.164414 -426.365128)
					(end 72.142096 -426.41901)
				)
				(arc
					(start 72.142096 -427.146466)
					(mid 72.144095 -427.163807)
					(end 72.14997 -427.180248)
				)
				(arc
					(start 72.383396 -427.656498)
					(mid 72.391179 -427.690026)
					(end 72.383396 -427.723554)
				)
				(arc
					(start 72.14997 -428.199804)
					(mid 72.144075 -428.21624)
					(end 72.142096 -428.233586)
				)
			)
		)
	)
	(zone
		(layers "In5.Cu" "In7.Cu")
		(hatch none 0.5)
		(connect_pads
			(clearance 0)
		)
		(min_thickness 0.25)
		(keepout
			(tracks not_allowed)
			(vias allowed)
			(pads allowed)
			(copperpour not_allowed)
			(footprints allowed)
		)
		(placement
			(enabled no)
			(sheetname "")
		)
		(fill yes
			(thermal_gap 0.5)
			(thermal_bridge_width 0.5)
			(island_removal_mode 0)
		)
		(polygon
			(pts
				(arc
					(start 318.142112 -427.960536)
					(mid 318.16443 -428.014418)
					(end 318.218312 -428.036736)
				)
				(arc
					(start 319.158112 -428.036736)
					(mid 319.211994 -428.014418)
					(end 319.234312 -427.960536)
				)
				(arc
					(start 319.234312 -425.419012)
					(mid 319.211994 -425.36513)
					(end 319.158112 -425.342812)
				)
				(arc
					(start 318.218312 -425.342812)
					(mid 318.16443 -425.36513)
					(end 318.142112 -425.419012)
				)
				(arc
					(start 318.142112 -426.146468)
					(mid 318.144111 -426.163809)
					(end 318.149986 -426.18025)
				)
				(arc
					(start 318.383412 -426.6565)
					(mid 318.391195 -426.690028)
					(end 318.383412 -426.723556)
				)
				(arc
					(start 318.149986 -427.199806)
					(mid 318.144091 -427.216242)
					(end 318.142112 -427.233588)
				)
			)
		)
	)
	(zone
		(layers "In5.Cu" "In7.Cu")
		(hatch none 0.5)
		(connect_pads
			(clearance 0)
		)
		(min_thickness 0.25)
		(keepout
			(tracks not_allowed)
			(vias allowed)
			(pads allowed)
			(copperpour not_allowed)
			(footprints allowed)
		)
		(placement
			(enabled no)
			(sheetname "")
		)
		(fill yes
			(thermal_gap 0.5)
			(thermal_bridge_width 0.5)
			(island_removal_mode 0)
		)
		(polygon
			(pts
				(arc
					(start 125.242066 -431.560478)
					(mid 125.264384 -431.61436)
					(end 125.318266 -431.636678)
				)
				(arc
					(start 126.258066 -431.636678)
					(mid 126.311948 -431.61436)
					(end 126.334266 -431.560478)
				)
				(arc
					(start 126.334266 -429.018954)
					(mid 126.311948 -428.965072)
					(end 126.258066 -428.942754)
				)
				(arc
					(start 125.318266 -428.942754)
					(mid 125.264384 -428.965072)
					(end 125.242066 -429.018954)
				)
				(arc
					(start 125.242066 -429.74641)
					(mid 125.244065 -429.763751)
					(end 125.24994 -429.780192)
				)
				(arc
					(start 125.483366 -430.256442)
					(mid 125.491149 -430.28997)
					(end 125.483366 -430.323498)
				)
				(arc
					(start 125.24994 -430.799748)
					(mid 125.244045 -430.816184)
					(end 125.242066 -430.83353)
				)
			)
		)
	)
	(zone
		(layers "In5.Cu" "In7.Cu")
		(hatch none 0.5)
		(connect_pads
			(clearance 0)
		)
		(min_thickness 0.25)
		(keepout
			(tracks not_allowed)
			(vias allowed)
			(pads allowed)
			(copperpour not_allowed)
			(footprints allowed)
		)
		(placement
			(enabled no)
			(sheetname "")
		)
		(fill yes
			(thermal_gap 0.5)
			(thermal_bridge_width 0.5)
			(island_removal_mode 0)
		)
		(polygon
			(pts
				(arc
					(start 406.242012 -431.560478)
					(mid 406.26433 -431.61436)
					(end 406.318212 -431.636678)
				)
				(arc
					(start 407.258012 -431.636678)
					(mid 407.311894 -431.61436)
					(end 407.334212 -431.560478)
				)
				(arc
					(start 407.334212 -429.018954)
					(mid 407.311894 -428.965072)
					(end 407.258012 -428.942754)
				)
				(arc
					(start 406.318212 -428.942754)
					(mid 406.26433 -428.965072)
					(end 406.242012 -429.018954)
				)
				(arc
					(start 406.242012 -429.74641)
					(mid 406.244011 -429.763751)
					(end 406.249886 -429.780192)
				)
				(arc
					(start 406.483312 -430.256442)
					(mid 406.491095 -430.28997)
					(end 406.483312 -430.323498)
				)
				(arc
					(start 406.249886 -430.799748)
					(mid 406.243991 -430.816184)
					(end 406.242012 -430.83353)
				)
			)
		)
	)
	(zone
		(layers "In5.Cu" "In7.Cu")
		(hatch none 0.5)
		(connect_pads
			(clearance 0)
		)
		(min_thickness 0.25)
		(keepout
			(tracks not_allowed)
			(vias allowed)
			(pads allowed)
			(copperpour not_allowed)
			(footprints allowed)
		)
		(placement
			(enabled no)
			(sheetname "")
		)
		(fill yes
			(thermal_gap 0.5)
			(thermal_bridge_width 0.5)
			(island_removal_mode 0)
		)
		(polygon
			(pts
				(arc
					(start 70.1421 -427.960536)
					(mid 70.164418 -428.014418)
					(end 70.2183 -428.036736)
				)
				(arc
					(start 71.1581 -428.036736)
					(mid 71.211982 -428.014418)
					(end 71.2343 -427.960536)
				)
				(arc
					(start 71.2343 -425.419012)
					(mid 71.211982 -425.36513)
					(end 71.1581 -425.342812)
				)
				(arc
					(start 70.2183 -425.342812)
					(mid 70.164418 -425.36513)
					(end 70.1421 -425.419012)
				)
				(arc
					(start 70.1421 -426.146468)
					(mid 70.144099 -426.163809)
					(end 70.149974 -426.18025)
				)
				(arc
					(start 70.3834 -426.6565)
					(mid 70.391183 -426.690028)
					(end 70.3834 -426.723556)
				)
				(arc
					(start 70.149974 -427.199806)
					(mid 70.144079 -427.216242)
					(end 70.1421 -427.233588)
				)
			)
		)
	)
	(zone
		(layers "In5.Cu" "In7.Cu")
		(hatch none 0.5)
		(connect_pads
			(clearance 0)
		)
		(min_thickness 0.25)
		(keepout
			(tracks not_allowed)
			(vias allowed)
			(pads allowed)
			(copperpour not_allowed)
			(footprints allowed)
		)
		(placement
			(enabled no)
			(sheetname "")
		)
		(fill yes
			(thermal_gap 0.5)
			(thermal_bridge_width 0.5)
			(island_removal_mode 0)
		)
		(polygon
			(pts
				(arc
					(start 156.242004 -432.560476)
					(mid 156.264322 -432.614358)
					(end 156.318204 -432.636676)
				)
				(arc
					(start 157.258004 -432.636676)
					(mid 157.311886 -432.614358)
					(end 157.334204 -432.560476)
				)
				(arc
					(start 157.334204 -430.018952)
					(mid 157.311886 -429.96507)
					(end 157.258004 -429.942752)
				)
				(arc
					(start 156.318204 -429.942752)
					(mid 156.264322 -429.96507)
					(end 156.242004 -430.018952)
				)
				(arc
					(start 156.242004 -430.746408)
					(mid 156.244003 -430.763749)
					(end 156.249878 -430.78019)
				)
				(arc
					(start 156.483304 -431.25644)
					(mid 156.491087 -431.289968)
					(end 156.483304 -431.323496)
				)
				(arc
					(start 156.249878 -431.799746)
					(mid 156.243983 -431.816182)
					(end 156.242004 -431.833528)
				)
			)
		)
	)
	(zone
		(layers "In5.Cu" "In7.Cu")
		(hatch none 0.5)
		(connect_pads
			(clearance 0)
		)
		(min_thickness 0.25)
		(keepout
			(tracks not_allowed)
			(vias allowed)
			(pads allowed)
			(copperpour not_allowed)
			(footprints allowed)
		)
		(placement
			(enabled no)
			(sheetname "")
		)
		(fill yes
			(thermal_gap 0.5)
			(thermal_bridge_width 0.5)
			(island_removal_mode 0)
		)
		(polygon
			(pts
				(arc
					(start 83.142074 -427.960536)
					(mid 83.164392 -428.014418)
					(end 83.218274 -428.036736)
				)
				(arc
					(start 84.158074 -428.036736)
					(mid 84.211956 -428.014418)
					(end 84.234274 -427.960536)
				)
				(arc
					(start 84.234274 -425.419012)
					(mid 84.211956 -425.36513)
					(end 84.158074 -425.342812)
				)
				(arc
					(start 83.218274 -425.342812)
					(mid 83.164392 -425.36513)
					(end 83.142074 -425.419012)
				)
				(arc
					(start 83.142074 -426.146468)
					(mid 83.144073 -426.163809)
					(end 83.149948 -426.18025)
				)
				(arc
					(start 83.383374 -426.6565)
					(mid 83.391157 -426.690028)
					(end 83.383374 -426.723556)
				)
				(arc
					(start 83.149948 -427.199806)
					(mid 83.144053 -427.216242)
					(end 83.142074 -427.233588)
				)
			)
		)
	)
	(zone
		(layers "In5.Cu" "In7.Cu")
		(hatch none 0.5)
		(connect_pads
			(clearance 0)
		)
		(min_thickness 0.25)
		(keepout
			(tracks not_allowed)
			(vias allowed)
			(pads allowed)
			(copperpour not_allowed)
			(footprints allowed)
		)
		(placement
			(enabled no)
			(sheetname "")
		)
		(fill yes
			(thermal_gap 0.5)
			(thermal_bridge_width 0.5)
			(island_removal_mode 0)
		)
		(polygon
			(pts
				(arc
					(start 131.242054 -432.560476)
					(mid 131.264372 -432.614358)
					(end 131.318254 -432.636676)
				)
				(arc
					(start 132.258054 -432.636676)
					(mid 132.311936 -432.614358)
					(end 132.334254 -432.560476)
				)
				(arc
					(start 132.334254 -430.018952)
					(mid 132.311936 -429.96507)
					(end 132.258054 -429.942752)
				)
				(arc
					(start 131.318254 -429.942752)
					(mid 131.264372 -429.96507)
					(end 131.242054 -430.018952)
				)
				(arc
					(start 131.242054 -430.746408)
					(mid 131.244053 -430.763749)
					(end 131.249928 -430.78019)
				)
				(arc
					(start 131.483354 -431.25644)
					(mid 131.491137 -431.289968)
					(end 131.483354 -431.323496)
				)
				(arc
					(start 131.249928 -431.799746)
					(mid 131.244033 -431.816182)
					(end 131.242054 -431.833528)
				)
			)
		)
	)
	(zone
		(layers "In5.Cu" "In7.Cu")
		(hatch none 0.5)
		(connect_pads
			(clearance 0)
		)
		(min_thickness 0.25)
		(keepout
			(tracks not_allowed)
			(vias allowed)
			(pads allowed)
			(copperpour not_allowed)
			(footprints allowed)
		)
		(placement
			(enabled no)
			(sheetname "")
		)
		(fill yes
			(thermal_gap 0.5)
			(thermal_bridge_width 0.5)
			(island_removal_mode 0)
		)
		(polygon
			(pts
				(arc
					(start 331.142086 -427.960536)
					(mid 331.164404 -428.014418)
					(end 331.218286 -428.036736)
				)
				(arc
					(start 332.158086 -428.036736)
					(mid 332.211968 -428.014418)
					(end 332.234286 -427.960536)
				)
				(arc
					(start 332.234286 -425.419012)
					(mid 332.211968 -425.36513)
					(end 332.158086 -425.342812)
				)
				(arc
					(start 331.218286 -425.342812)
					(mid 331.164404 -425.36513)
					(end 331.142086 -425.419012)
				)
				(arc
					(start 331.142086 -426.146468)
					(mid 331.144085 -426.163809)
					(end 331.14996 -426.18025)
				)
				(arc
					(start 331.383386 -426.6565)
					(mid 331.391169 -426.690028)
					(end 331.383386 -426.723556)
				)
				(arc
					(start 331.14996 -427.199806)
					(mid 331.144065 -427.216242)
					(end 331.142086 -427.233588)
				)
			)
		)
	)
	(zone
		(layers "In5.Cu" "In7.Cu")
		(hatch none 0.5)
		(connect_pads
			(clearance 0)
		)
		(min_thickness 0.25)
		(keepout
			(tracks not_allowed)
			(vias allowed)
			(pads allowed)
			(copperpour not_allowed)
			(footprints allowed)
		)
		(placement
			(enabled no)
			(sheetname "")
		)
		(fill yes
			(thermal_gap 0.5)
			(thermal_bridge_width 0.5)
			(island_removal_mode 0)
		)
		(polygon
			(pts
				(arc
					(start 135.242046 -432.560476)
					(mid 135.264364 -432.614358)
					(end 135.318246 -432.636676)
				)
				(arc
					(start 136.258046 -432.636676)
					(mid 136.311928 -432.614358)
					(end 136.334246 -432.560476)
				)
				(arc
					(start 136.334246 -430.018952)
					(mid 136.311928 -429.96507)
					(end 136.258046 -429.942752)
				)
				(arc
					(start 135.318246 -429.942752)
					(mid 135.264364 -429.96507)
					(end 135.242046 -430.018952)
				)
				(arc
					(start 135.242046 -430.746408)
					(mid 135.244045 -430.763749)
					(end 135.24992 -430.78019)
				)
				(arc
					(start 135.483346 -431.25644)
					(mid 135.491129 -431.289968)
					(end 135.483346 -431.323496)
				)
				(arc
					(start 135.24992 -431.799746)
					(mid 135.244025 -431.816182)
					(end 135.242046 -431.833528)
				)
			)
		)
	)
	(zone
		(layers "In5.Cu" "In7.Cu")
		(hatch none 0.5)
		(connect_pads
			(clearance 0)
		)
		(min_thickness 0.25)
		(keepout
			(tracks not_allowed)
			(vias allowed)
			(pads allowed)
			(copperpour not_allowed)
			(footprints allowed)
		)
		(placement
			(enabled no)
			(sheetname "")
		)
		(fill yes
			(thermal_gap 0.5)
			(thermal_bridge_width 0.5)
			(island_removal_mode 0)
		)
		(polygon
			(pts
				(arc
					(start 144.242028 -432.560476)
					(mid 144.264346 -432.614358)
					(end 144.318228 -432.636676)
				)
				(arc
					(start 145.258028 -432.636676)
					(mid 145.31191 -432.614358)
					(end 145.334228 -432.560476)
				)
				(arc
					(start 145.334228 -430.018952)
					(mid 145.31191 -429.96507)
					(end 145.258028 -429.942752)
				)
				(arc
					(start 144.318228 -429.942752)
					(mid 144.264346 -429.96507)
					(end 144.242028 -430.018952)
				)
				(arc
					(start 144.242028 -430.746408)
					(mid 144.244027 -430.763749)
					(end 144.249902 -430.78019)
				)
				(arc
					(start 144.483328 -431.25644)
					(mid 144.491111 -431.289968)
					(end 144.483328 -431.323496)
				)
				(arc
					(start 144.249902 -431.799746)
					(mid 144.244007 -431.816182)
					(end 144.242028 -431.833528)
				)
			)
		)
	)
	(zone
		(layers "In5.Cu" "In7.Cu")
		(hatch none 0.5)
		(connect_pads
			(clearance 0)
		)
		(min_thickness 0.25)
		(keepout
			(tracks not_allowed)
			(vias allowed)
			(pads allowed)
			(copperpour not_allowed)
			(footprints allowed)
		)
		(placement
			(enabled no)
			(sheetname "")
		)
		(fill yes
			(thermal_gap 0.5)
			(thermal_bridge_width 0.5)
			(island_removal_mode 0)
		)
		(polygon
			(pts
				(arc
					(start 320.142108 -428.960534)
					(mid 320.164426 -429.014416)
					(end 320.218308 -429.036734)
				)
				(arc
					(start 321.158108 -429.036734)
					(mid 321.21199 -429.014416)
					(end 321.234308 -428.960534)
				)
				(arc
					(start 321.234308 -426.41901)
					(mid 321.21199 -426.365128)
					(end 321.158108 -426.34281)
				)
				(arc
					(start 320.218308 -426.34281)
					(mid 320.164426 -426.365128)
					(end 320.142108 -426.41901)
				)
				(arc
					(start 320.142108 -427.146466)
					(mid 320.144107 -427.163807)
					(end 320.149982 -427.180248)
				)
				(arc
					(start 320.383408 -427.656498)
					(mid 320.391191 -427.690026)
					(end 320.383408 -427.723554)
				)
				(arc
					(start 320.149982 -428.199804)
					(mid 320.144087 -428.21624)
					(end 320.142108 -428.233586)
				)
			)
		)
	)
	(zone
		(layers "In5.Cu" "In7.Cu")
		(hatch none 0.5)
		(connect_pads
			(clearance 0)
		)
		(min_thickness 0.25)
		(keepout
			(tracks not_allowed)
			(vias allowed)
			(pads allowed)
			(copperpour not_allowed)
			(footprints allowed)
		)
		(placement
			(enabled no)
			(sheetname "")
		)
		(fill yes
			(thermal_gap 0.5)
			(thermal_bridge_width 0.5)
			(island_removal_mode 0)
		)
		(polygon
			(pts
				(arc
					(start 333.142082 -428.960534)
					(mid 333.1644 -429.014416)
					(end 333.218282 -429.036734)
				)
				(arc
					(start 334.158082 -429.036734)
					(mid 334.211964 -429.014416)
					(end 334.234282 -428.960534)
				)
				(arc
					(start 334.234282 -426.41901)
					(mid 334.211964 -426.365128)
					(end 334.158082 -426.34281)
				)
				(arc
					(start 333.218282 -426.34281)
					(mid 333.1644 -426.365128)
					(end 333.142082 -426.41901)
				)
				(arc
					(start 333.142082 -427.146466)
					(mid 333.144081 -427.163807)
					(end 333.149956 -427.180248)
				)
				(arc
					(start 333.383382 -427.656498)
					(mid 333.391165 -427.690026)
					(end 333.383382 -427.723554)
				)
				(arc
					(start 333.149956 -428.199804)
					(mid 333.144061 -428.21624)
					(end 333.142082 -428.233586)
				)
			)
		)
	)
	(zone
		(layers "In5.Cu" "In7.Cu")
		(hatch none 0.5)
		(connect_pads
			(clearance 0)
		)
		(min_thickness 0.25)
		(keepout
			(tracks not_allowed)
			(vias allowed)
			(pads allowed)
			(copperpour not_allowed)
			(footprints allowed)
		)
		(placement
			(enabled no)
			(sheetname "")
		)
		(fill yes
			(thermal_gap 0.5)
			(thermal_bridge_width 0.5)
			(island_removal_mode 0)
		)
		(polygon
			(pts
				(arc
					(start 150.242016 -431.560478)
					(mid 150.264334 -431.61436)
					(end 150.318216 -431.636678)
				)
				(arc
					(start 151.258016 -431.636678)
					(mid 151.311898 -431.61436)
					(end 151.334216 -431.560478)
				)
				(arc
					(start 151.334216 -429.018954)
					(mid 151.311898 -428.965072)
					(end 151.258016 -428.942754)
				)
				(arc
					(start 150.318216 -428.942754)
					(mid 150.264334 -428.965072)
					(end 150.242016 -429.018954)
				)
				(arc
					(start 150.242016 -429.74641)
					(mid 150.244015 -429.763751)
					(end 150.24989 -429.780192)
				)
				(arc
					(start 150.483316 -430.256442)
					(mid 150.491099 -430.28997)
					(end 150.483316 -430.323498)
				)
				(arc
					(start 150.24989 -430.799748)
					(mid 150.243995 -430.816184)
					(end 150.242016 -430.83353)
				)
			)
		)
	)
	(zone
		(layers "In5.Cu" "In7.Cu")
		(hatch none 0.5)
		(connect_pads
			(clearance 0)
		)
		(min_thickness 0.25)
		(keepout
			(tracks not_allowed)
			(vias allowed)
			(pads allowed)
			(copperpour not_allowed)
			(footprints allowed)
		)
		(placement
			(enabled no)
			(sheetname "")
		)
		(fill yes
			(thermal_gap 0.5)
			(thermal_bridge_width 0.5)
			(island_removal_mode 0)
		)
		(polygon
			(pts
				(arc
					(start 137.242042 -431.560478)
					(mid 137.26436 -431.61436)
					(end 137.318242 -431.636678)
				)
				(arc
					(start 138.258042 -431.636678)
					(mid 138.311924 -431.61436)
					(end 138.334242 -431.560478)
				)
				(arc
					(start 138.334242 -429.018954)
					(mid 138.311924 -428.965072)
					(end 138.258042 -428.942754)
				)
				(arc
					(start 137.318242 -428.942754)
					(mid 137.26436 -428.965072)
					(end 137.242042 -429.018954)
				)
				(arc
					(start 137.242042 -429.74641)
					(mid 137.244041 -429.763751)
					(end 137.249916 -429.780192)
				)
				(arc
					(start 137.483342 -430.256442)
					(mid 137.491125 -430.28997)
					(end 137.483342 -430.323498)
				)
				(arc
					(start 137.249916 -430.799748)
					(mid 137.244021 -430.816184)
					(end 137.242042 -430.83353)
				)
			)
		)
	)
	(zone
		(layers "In5.Cu" "In7.Cu")
		(hatch none 0.5)
		(connect_pads
			(clearance 0)
		)
		(min_thickness 0.25)
		(keepout
			(tracks not_allowed)
			(vias allowed)
			(pads allowed)
			(copperpour not_allowed)
			(footprints allowed)
		)
		(placement
			(enabled no)
			(sheetname "")
		)
		(fill yes
			(thermal_gap 0.5)
			(thermal_bridge_width 0.5)
			(island_removal_mode 0)
		)
		(polygon
			(pts
				(arc
					(start 316.142116 -428.960534)
					(mid 316.164434 -429.014416)
					(end 316.218316 -429.036734)
				)
				(arc
					(start 317.158116 -429.036734)
					(mid 317.211998 -429.014416)
					(end 317.234316 -428.960534)
				)
				(arc
					(start 317.234316 -426.41901)
					(mid 317.211998 -426.365128)
					(end 317.158116 -426.34281)
				)
				(arc
					(start 316.218316 -426.34281)
					(mid 316.164434 -426.365128)
					(end 316.142116 -426.41901)
				)
				(arc
					(start 316.142116 -427.146466)
					(mid 316.144115 -427.163807)
					(end 316.14999 -427.180248)
				)
				(arc
					(start 316.383416 -427.656498)
					(mid 316.391199 -427.690026)
					(end 316.383416 -427.723554)
				)
				(arc
					(start 316.14999 -428.199804)
					(mid 316.144095 -428.21624)
					(end 316.142116 -428.233586)
				)
			)
		)
	)
	(zone
		(layers "In5.Cu" "In7.Cu")
		(hatch none 0.5)
		(connect_pads
			(clearance 0)
		)
		(min_thickness 0.25)
		(keepout
			(tracks not_allowed)
			(vias allowed)
			(pads allowed)
			(copperpour not_allowed)
			(footprints allowed)
		)
		(placement
			(enabled no)
			(sheetname "")
		)
		(fill yes
			(thermal_gap 0.5)
			(thermal_bridge_width 0.5)
			(island_removal_mode 0)
		)
		(polygon
			(pts
				(arc
					(start 335.142078 -427.960536)
					(mid 335.164396 -428.014418)
					(end 335.218278 -428.036736)
				)
				(arc
					(start 336.158078 -428.036736)
					(mid 336.21196 -428.014418)
					(end 336.234278 -427.960536)
				)
				(arc
					(start 336.234278 -425.419012)
					(mid 336.21196 -425.36513)
					(end 336.158078 -425.342812)
				)
				(arc
					(start 335.218278 -425.342812)
					(mid 335.164396 -425.36513)
					(end 335.142078 -425.419012)
				)
				(arc
					(start 335.142078 -426.146468)
					(mid 335.144077 -426.163809)
					(end 335.149952 -426.18025)
				)
				(arc
					(start 335.383378 -426.6565)
					(mid 335.391161 -426.690028)
					(end 335.383378 -426.723556)
				)
				(arc
					(start 335.149952 -427.199806)
					(mid 335.144057 -427.216242)
					(end 335.142078 -427.233588)
				)
			)
		)
	)
	(zone
		(layers "In5.Cu" "In7.Cu")
		(hatch none 0.5)
		(connect_pads
			(clearance 0)
		)
		(min_thickness 0.25)
		(keepout
			(tracks not_allowed)
			(vias allowed)
			(pads allowed)
			(copperpour not_allowed)
			(footprints allowed)
		)
		(placement
			(enabled no)
			(sheetname "")
		)
		(fill yes
			(thermal_gap 0.5)
			(thermal_bridge_width 0.5)
			(island_removal_mode 0)
		)
		(polygon
			(pts
				(arc
					(start 328.142092 -428.960534)
					(mid 328.16441 -429.014416)
					(end 328.218292 -429.036734)
				)
				(arc
					(start 329.158092 -429.036734)
					(mid 329.211974 -429.014416)
					(end 329.234292 -428.960534)
				)
				(arc
					(start 329.234292 -426.41901)
					(mid 329.211974 -426.365128)
					(end 329.158092 -426.34281)
				)
				(arc
					(start 328.218292 -426.34281)
					(mid 328.16441 -426.365128)
					(end 328.142092 -426.41901)
				)
				(arc
					(start 328.142092 -427.146466)
					(mid 328.144091 -427.163807)
					(end 328.149966 -427.180248)
				)
				(arc
					(start 328.383392 -427.656498)
					(mid 328.391175 -427.690026)
					(end 328.383392 -427.723554)
				)
				(arc
					(start 328.149966 -428.199804)
					(mid 328.144071 -428.21624)
					(end 328.142092 -428.233586)
				)
			)
		)
	)
	(zone
		(layers "In5.Cu" "In7.Cu")
		(hatch none 0.5)
		(connect_pads
			(clearance 0)
		)
		(min_thickness 0.25)
		(keepout
			(tracks not_allowed)
			(vias allowed)
			(pads allowed)
			(copperpour not_allowed)
			(footprints allowed)
		)
		(placement
			(enabled no)
			(sheetname "")
		)
		(fill yes
			(thermal_gap 0.5)
			(thermal_bridge_width 0.5)
			(island_removal_mode 0)
		)
		(polygon
			(pts
				(arc
					(start 385.242054 -431.560478)
					(mid 385.264372 -431.61436)
					(end 385.318254 -431.636678)
				)
				(arc
					(start 386.258054 -431.636678)
					(mid 386.311936 -431.61436)
					(end 386.334254 -431.560478)
				)
				(arc
					(start 386.334254 -429.018954)
					(mid 386.311936 -428.965072)
					(end 386.258054 -428.942754)
				)
				(arc
					(start 385.318254 -428.942754)
					(mid 385.264372 -428.965072)
					(end 385.242054 -429.018954)
				)
				(arc
					(start 385.242054 -429.74641)
					(mid 385.244053 -429.763751)
					(end 385.249928 -429.780192)
				)
				(arc
					(start 385.483354 -430.256442)
					(mid 385.491137 -430.28997)
					(end 385.483354 -430.323498)
				)
				(arc
					(start 385.249928 -430.799748)
					(mid 385.244033 -430.816184)
					(end 385.242054 -430.83353)
				)
			)
		)
	)
	(zone
		(layers "In5.Cu" "In7.Cu")
		(hatch none 0.5)
		(connect_pads
			(clearance 0)
		)
		(min_thickness 0.25)
		(keepout
			(tracks not_allowed)
			(vias allowed)
			(pads allowed)
			(copperpour not_allowed)
			(footprints allowed)
		)
		(placement
			(enabled no)
			(sheetname "")
		)
		(fill yes
			(thermal_gap 0.5)
			(thermal_bridge_width 0.5)
			(island_removal_mode 0)
		)
		(polygon
			(pts
				(arc
					(start 343.142062 -427.960536)
					(mid 343.16438 -428.014418)
					(end 343.218262 -428.036736)
				)
				(arc
					(start 344.158062 -428.036736)
					(mid 344.211944 -428.014418)
					(end 344.234262 -427.960536)
				)
				(arc
					(start 344.234262 -425.419012)
					(mid 344.211944 -425.36513)
					(end 344.158062 -425.342812)
				)
				(arc
					(start 343.218262 -425.342812)
					(mid 343.16438 -425.36513)
					(end 343.142062 -425.419012)
				)
				(arc
					(start 343.142062 -426.146468)
					(mid 343.144061 -426.163809)
					(end 343.149936 -426.18025)
				)
				(arc
					(start 343.383362 -426.6565)
					(mid 343.391145 -426.690028)
					(end 343.383362 -426.723556)
				)
				(arc
					(start 343.149936 -427.199806)
					(mid 343.144041 -427.216242)
					(end 343.142062 -427.233588)
				)
			)
		)
	)
	(zone
		(layers "In5.Cu" "In7.Cu")
		(hatch none 0.5)
		(connect_pads
			(clearance 0)
		)
		(min_thickness 0.25)
		(keepout
			(tracks not_allowed)
			(vias allowed)
			(pads allowed)
			(copperpour not_allowed)
			(footprints allowed)
		)
		(placement
			(enabled no)
			(sheetname "")
		)
		(fill yes
			(thermal_gap 0.5)
			(thermal_bridge_width 0.5)
			(island_removal_mode 0)
		)
		(polygon
			(pts
				(arc
					(start 402.24202 -431.560478)
					(mid 402.264338 -431.61436)
					(end 402.31822 -431.636678)
				)
				(arc
					(start 403.25802 -431.636678)
					(mid 403.311902 -431.61436)
					(end 403.33422 -431.560478)
				)
				(arc
					(start 403.33422 -429.018954)
					(mid 403.311902 -428.965072)
					(end 403.25802 -428.942754)
				)
				(arc
					(start 402.31822 -428.942754)
					(mid 402.264338 -428.965072)
					(end 402.24202 -429.018954)
				)
				(arc
					(start 402.24202 -429.74641)
					(mid 402.244019 -429.763751)
					(end 402.249894 -429.780192)
				)
				(arc
					(start 402.48332 -430.256442)
					(mid 402.491103 -430.28997)
					(end 402.48332 -430.323498)
				)
				(arc
					(start 402.249894 -430.799748)
					(mid 402.243999 -430.816184)
					(end 402.24202 -430.83353)
				)
			)
		)
	)
	(zone
		(layers "In5.Cu" "In7.Cu")
		(hatch none 0.5)
		(connect_pads
			(clearance 0)
		)
		(min_thickness 0.25)
		(keepout
			(tracks not_allowed)
			(vias allowed)
			(pads allowed)
			(copperpour not_allowed)
			(footprints allowed)
		)
		(placement
			(enabled no)
			(sheetname "")
		)
		(fill yes
			(thermal_gap 0.5)
			(thermal_bridge_width 0.5)
			(island_removal_mode 0)
		)
		(polygon
			(pts
				(arc
					(start 408.242008 -432.560476)
					(mid 408.264326 -432.614358)
					(end 408.318208 -432.636676)
				)
				(arc
					(start 409.258008 -432.636676)
					(mid 409.31189 -432.614358)
					(end 409.334208 -432.560476)
				)
				(arc
					(start 409.334208 -430.018952)
					(mid 409.31189 -429.96507)
					(end 409.258008 -429.942752)
				)
				(arc
					(start 408.318208 -429.942752)
					(mid 408.264326 -429.96507)
					(end 408.242008 -430.018952)
				)
				(arc
					(start 408.242008 -430.746408)
					(mid 408.244007 -430.763749)
					(end 408.249882 -430.78019)
				)
				(arc
					(start 408.483308 -431.25644)
					(mid 408.491091 -431.289968)
					(end 408.483308 -431.323496)
				)
				(arc
					(start 408.249882 -431.799746)
					(mid 408.243987 -431.816182)
					(end 408.242008 -431.833528)
				)
			)
		)
	)
	(zone
		(layers "In5.Cu" "In7.Cu")
		(hatch none 0.5)
		(connect_pads
			(clearance 0)
		)
		(min_thickness 0.25)
		(keepout
			(tracks not_allowed)
			(vias allowed)
			(pads allowed)
			(copperpour not_allowed)
			(footprints allowed)
		)
		(placement
			(enabled no)
			(sheetname "")
		)
		(fill yes
			(thermal_gap 0.5)
			(thermal_bridge_width 0.5)
			(island_removal_mode 0)
		)
		(polygon
			(pts
				(arc
					(start 322.142104 -427.960536)
					(mid 322.164422 -428.014418)
					(end 322.218304 -428.036736)
				)
				(arc
					(start 323.158104 -428.036736)
					(mid 323.211986 -428.014418)
					(end 323.234304 -427.960536)
				)
				(arc
					(start 323.234304 -425.419012)
					(mid 323.211986 -425.36513)
					(end 323.158104 -425.342812)
				)
				(arc
					(start 322.218304 -425.342812)
					(mid 322.164422 -425.36513)
					(end 322.142104 -425.419012)
				)
				(arc
					(start 322.142104 -426.146468)
					(mid 322.144103 -426.163809)
					(end 322.149978 -426.18025)
				)
				(arc
					(start 322.383404 -426.6565)
					(mid 322.391187 -426.690028)
					(end 322.383404 -426.723556)
				)
				(arc
					(start 322.149978 -427.199806)
					(mid 322.144083 -427.216242)
					(end 322.142104 -427.233588)
				)
			)
		)
	)
	(zone
		(layers "In5.Cu" "In7.Cu")
		(hatch none 0.5)
		(connect_pads
			(clearance 0)
		)
		(min_thickness 0.25)
		(keepout
			(tracks not_allowed)
			(vias allowed)
			(pads allowed)
			(copperpour not_allowed)
			(footprints allowed)
		)
		(placement
			(enabled no)
			(sheetname "")
		)
		(fill yes
			(thermal_gap 0.5)
			(thermal_bridge_width 0.5)
			(island_removal_mode 0)
		)
		(polygon
			(pts
				(arc
					(start 146.242024 -431.560478)
					(mid 146.264342 -431.61436)
					(end 146.318224 -431.636678)
				)
				(arc
					(start 147.258024 -431.636678)
					(mid 147.311906 -431.61436)
					(end 147.334224 -431.560478)
				)
				(arc
					(start 147.334224 -429.018954)
					(mid 147.311906 -428.965072)
					(end 147.258024 -428.942754)
				)
				(arc
					(start 146.318224 -428.942754)
					(mid 146.264342 -428.965072)
					(end 146.242024 -429.018954)
				)
				(arc
					(start 146.242024 -429.74641)
					(mid 146.244023 -429.763751)
					(end 146.249898 -429.780192)
				)
				(arc
					(start 146.483324 -430.256442)
					(mid 146.491107 -430.28997)
					(end 146.483324 -430.323498)
				)
				(arc
					(start 146.249898 -430.799748)
					(mid 146.244003 -430.816184)
					(end 146.242024 -430.83353)
				)
			)
		)
	)
	(zone
		(layers "In5.Cu" "In7.Cu")
		(hatch none 0.5)
		(connect_pads
			(clearance 0)
		)
		(min_thickness 0.25)
		(keepout
			(tracks not_allowed)
			(vias allowed)
			(pads allowed)
			(copperpour not_allowed)
			(footprints allowed)
		)
		(placement
			(enabled no)
			(sheetname "")
		)
		(fill yes
			(thermal_gap 0.5)
			(thermal_bridge_width 0.5)
			(island_removal_mode 0)
		)
		(polygon
			(pts
				(arc
					(start 314.14212 -427.960536)
					(mid 314.164438 -428.014418)
					(end 314.21832 -428.036736)
				)
				(arc
					(start 315.15812 -428.036736)
					(mid 315.212002 -428.014418)
					(end 315.23432 -427.960536)
				)
				(arc
					(start 315.23432 -425.419012)
					(mid 315.212002 -425.36513)
					(end 315.15812 -425.342812)
				)
				(arc
					(start 314.21832 -425.342812)
					(mid 314.164438 -425.36513)
					(end 314.14212 -425.419012)
				)
				(arc
					(start 314.14212 -426.146468)
					(mid 314.144119 -426.163809)
					(end 314.149994 -426.18025)
				)
				(arc
					(start 314.38342 -426.6565)
					(mid 314.391203 -426.690028)
					(end 314.38342 -426.723556)
				)
				(arc
					(start 314.149994 -427.199806)
					(mid 314.144099 -427.216242)
					(end 314.14212 -427.233588)
				)
			)
		)
	)
	(zone
		(layers "In5.Cu" "In7.Cu")
		(hatch none 0.5)
		(connect_pads
			(clearance 0)
		)
		(min_thickness 0.25)
		(keepout
			(tracks not_allowed)
			(vias allowed)
			(pads allowed)
			(copperpour not_allowed)
			(footprints allowed)
		)
		(placement
			(enabled no)
			(sheetname "")
		)
		(fill yes
			(thermal_gap 0.5)
			(thermal_bridge_width 0.5)
			(island_removal_mode 0)
		)
		(polygon
			(pts
				(arc
					(start 339.14207 -427.960536)
					(mid 339.164388 -428.014418)
					(end 339.21827 -428.036736)
				)
				(arc
					(start 340.15807 -428.036736)
					(mid 340.211952 -428.014418)
					(end 340.23427 -427.960536)
				)
				(arc
					(start 340.23427 -425.419012)
					(mid 340.211952 -425.36513)
					(end 340.15807 -425.342812)
				)
				(arc
					(start 339.21827 -425.342812)
					(mid 339.164388 -425.36513)
					(end 339.14207 -425.419012)
				)
				(arc
					(start 339.14207 -426.146468)
					(mid 339.144069 -426.163809)
					(end 339.149944 -426.18025)
				)
				(arc
					(start 339.38337 -426.6565)
					(mid 339.391153 -426.690028)
					(end 339.38337 -426.723556)
				)
				(arc
					(start 339.149944 -427.199806)
					(mid 339.144049 -427.216242)
					(end 339.14207 -427.233588)
				)
			)
		)
	)
	(zone
		(layers "In5.Cu" "In7.Cu")
		(hatch none 0.5)
		(connect_pads
			(clearance 0)
		)
		(min_thickness 0.25)
		(keepout
			(tracks not_allowed)
			(vias allowed)
			(pads allowed)
			(copperpour not_allowed)
			(footprints allowed)
		)
		(placement
			(enabled no)
			(sheetname "")
		)
		(fill yes
			(thermal_gap 0.5)
			(thermal_bridge_width 0.5)
			(island_removal_mode 0)
		)
		(polygon
			(pts
				(arc
					(start 139.242038 -432.560476)
					(mid 139.264356 -432.614358)
					(end 139.318238 -432.636676)
				)
				(arc
					(start 140.258038 -432.636676)
					(mid 140.31192 -432.614358)
					(end 140.334238 -432.560476)
				)
				(arc
					(start 140.334238 -430.018952)
					(mid 140.31192 -429.96507)
					(end 140.258038 -429.942752)
				)
				(arc
					(start 139.318238 -429.942752)
					(mid 139.264356 -429.96507)
					(end 139.242038 -430.018952)
				)
				(arc
					(start 139.242038 -430.746408)
					(mid 139.244037 -430.763749)
					(end 139.249912 -430.78019)
				)
				(arc
					(start 139.483338 -431.25644)
					(mid 139.491121 -431.289968)
					(end 139.483338 -431.323496)
				)
				(arc
					(start 139.249912 -431.799746)
					(mid 139.244017 -431.816182)
					(end 139.242038 -431.833528)
				)
			)
		)
	)
	(zone
		(layers "In5.Cu" "In7.Cu")
		(hatch none 0.5)
		(connect_pads
			(clearance 0)
		)
		(min_thickness 0.25)
		(keepout
			(tracks not_allowed)
			(vias allowed)
			(pads allowed)
			(copperpour not_allowed)
			(footprints allowed)
		)
		(placement
			(enabled no)
			(sheetname "")
		)
		(fill yes
			(thermal_gap 0.5)
			(thermal_bridge_width 0.5)
			(island_removal_mode 0)
		)
		(polygon
			(pts
				(arc
					(start 64.142112 -428.960534)
					(mid 64.16443 -429.014416)
					(end 64.218312 -429.036734)
				)
				(arc
					(start 65.158112 -429.036734)
					(mid 65.211994 -429.014416)
					(end 65.234312 -428.960534)
				)
				(arc
					(start 65.234312 -426.41901)
					(mid 65.211994 -426.365128)
					(end 65.158112 -426.34281)
				)
				(arc
					(start 64.218312 -426.34281)
					(mid 64.16443 -426.365128)
					(end 64.142112 -426.41901)
				)
				(arc
					(start 64.142112 -427.146466)
					(mid 64.144111 -427.163807)
					(end 64.149986 -427.180248)
				)
				(arc
					(start 64.383412 -427.656498)
					(mid 64.391195 -427.690026)
					(end 64.383412 -427.723554)
				)
				(arc
					(start 64.149986 -428.199804)
					(mid 64.144091 -428.21624)
					(end 64.142112 -428.233586)
				)
			)
		)
	)
	(zone
		(layers "In5.Cu" "In7.Cu")
		(hatch none 0.5)
		(connect_pads
			(clearance 0)
		)
		(min_thickness 0.25)
		(keepout
			(tracks not_allowed)
			(vias allowed)
			(pads allowed)
			(copperpour not_allowed)
			(footprints allowed)
		)
		(placement
			(enabled no)
			(sheetname "")
		)
		(fill yes
			(thermal_gap 0.5)
			(thermal_bridge_width 0.5)
			(island_removal_mode 0)
		)
		(polygon
			(pts
				(arc
					(start 79.142082 -427.960536)
					(mid 79.1644 -428.014418)
					(end 79.218282 -428.036736)
				)
				(arc
					(start 80.158082 -428.036736)
					(mid 80.211964 -428.014418)
					(end 80.234282 -427.960536)
				)
				(arc
					(start 80.234282 -425.419012)
					(mid 80.211964 -425.36513)
					(end 80.158082 -425.342812)
				)
				(arc
					(start 79.218282 -425.342812)
					(mid 79.1644 -425.36513)
					(end 79.142082 -425.419012)
				)
				(arc
					(start 79.142082 -426.146468)
					(mid 79.144081 -426.163809)
					(end 79.149956 -426.18025)
				)
				(arc
					(start 79.383382 -426.6565)
					(mid 79.391165 -426.690028)
					(end 79.383382 -426.723556)
				)
				(arc
					(start 79.149956 -427.199806)
					(mid 79.144061 -427.216242)
					(end 79.142082 -427.233588)
				)
			)
		)
	)
	(zone
		(layers "In5.Cu" "In7.Cu")
		(hatch none 0.5)
		(connect_pads
			(clearance 0)
		)
		(min_thickness 0.25)
		(keepout
			(tracks not_allowed)
			(vias allowed)
			(pads allowed)
			(copperpour not_allowed)
			(footprints allowed)
		)
		(placement
			(enabled no)
			(sheetname "")
		)
		(fill yes
			(thermal_gap 0.5)
			(thermal_bridge_width 0.5)
			(island_removal_mode 0)
		)
		(polygon
			(pts
				(arc
					(start 81.142078 -428.960534)
					(mid 81.164396 -429.014416)
					(end 81.218278 -429.036734)
				)
				(arc
					(start 82.158078 -429.036734)
					(mid 82.21196 -429.014416)
					(end 82.234278 -428.960534)
				)
				(arc
					(start 82.234278 -426.41901)
					(mid 82.21196 -426.365128)
					(end 82.158078 -426.34281)
				)
				(arc
					(start 81.218278 -426.34281)
					(mid 81.164396 -426.365128)
					(end 81.142078 -426.41901)
				)
				(arc
					(start 81.142078 -427.146466)
					(mid 81.144077 -427.163807)
					(end 81.149952 -427.180248)
				)
				(arc
					(start 81.383378 -427.656498)
					(mid 81.391161 -427.690026)
					(end 81.383378 -427.723554)
				)
				(arc
					(start 81.149952 -428.199804)
					(mid 81.144057 -428.21624)
					(end 81.142078 -428.233586)
				)
			)
		)
	)
	(zone
		(layers "In5.Cu" "In7.Cu")
		(hatch none 0.5)
		(connect_pads
			(clearance 0)
		)
		(min_thickness 0.25)
		(keepout
			(tracks not_allowed)
			(vias allowed)
			(pads allowed)
			(copperpour not_allowed)
			(footprints allowed)
		)
		(placement
			(enabled no)
			(sheetname "")
		)
		(fill yes
			(thermal_gap 0.5)
			(thermal_bridge_width 0.5)
			(island_removal_mode 0)
		)
		(polygon
			(pts
				(arc
					(start 400.242024 -432.560476)
					(mid 400.264342 -432.614358)
					(end 400.318224 -432.636676)
				)
				(arc
					(start 401.258024 -432.636676)
					(mid 401.311906 -432.614358)
					(end 401.334224 -432.560476)
				)
				(arc
					(start 401.334224 -430.018952)
					(mid 401.311906 -429.96507)
					(end 401.258024 -429.942752)
				)
				(arc
					(start 400.318224 -429.942752)
					(mid 400.264342 -429.96507)
					(end 400.242024 -430.018952)
				)
				(arc
					(start 400.242024 -430.746408)
					(mid 400.244023 -430.763749)
					(end 400.249898 -430.78019)
				)
				(arc
					(start 400.483324 -431.25644)
					(mid 400.491107 -431.289968)
					(end 400.483324 -431.323496)
				)
				(arc
					(start 400.249898 -431.799746)
					(mid 400.244003 -431.816182)
					(end 400.242024 -431.833528)
				)
			)
		)
	)
	(zone
		(layers "In5.Cu" "In7.Cu")
		(hatch none 0.5)
		(connect_pads
			(clearance 0)
		)
		(min_thickness 0.25)
		(keepout
			(tracks not_allowed)
			(vias allowed)
			(pads allowed)
			(copperpour not_allowed)
			(footprints allowed)
		)
		(placement
			(enabled no)
			(sheetname "")
		)
		(fill yes
			(thermal_gap 0.5)
			(thermal_bridge_width 0.5)
			(island_removal_mode 0)
		)
		(polygon
			(pts
				(arc
					(start 410.242004 -431.560478)
					(mid 410.264322 -431.61436)
					(end 410.318204 -431.636678)
				)
				(arc
					(start 411.258004 -431.636678)
					(mid 411.311886 -431.61436)
					(end 411.334204 -431.560478)
				)
				(arc
					(start 411.334204 -429.018954)
					(mid 411.311886 -428.965072)
					(end 411.258004 -428.942754)
				)
				(arc
					(start 410.318204 -428.942754)
					(mid 410.264322 -428.965072)
					(end 410.242004 -429.018954)
				)
				(arc
					(start 410.242004 -429.74641)
					(mid 410.244003 -429.763751)
					(end 410.249878 -429.780192)
				)
				(arc
					(start 410.483304 -430.256442)
					(mid 410.491087 -430.28997)
					(end 410.483304 -430.323498)
				)
				(arc
					(start 410.249878 -430.799748)
					(mid 410.243983 -430.816184)
					(end 410.242004 -430.83353)
				)
			)
		)
	)
	(zone
		(layers "In5.Cu" "In7.Cu")
		(hatch none 0.5)
		(connect_pads
			(clearance 0)
		)
		(min_thickness 0.25)
		(keepout
			(tracks not_allowed)
			(vias allowed)
			(pads allowed)
			(copperpour not_allowed)
			(footprints allowed)
		)
		(placement
			(enabled no)
			(sheetname "")
		)
		(fill yes
			(thermal_gap 0.5)
			(thermal_bridge_width 0.5)
			(island_removal_mode 0)
		)
		(polygon
			(pts
				(arc
					(start 326.142096 -427.960536)
					(mid 326.164414 -428.014418)
					(end 326.218296 -428.036736)
				)
				(arc
					(start 327.158096 -428.036736)
					(mid 327.211978 -428.014418)
					(end 327.234296 -427.960536)
				)
				(arc
					(start 327.234296 -425.419012)
					(mid 327.211978 -425.36513)
					(end 327.158096 -425.342812)
				)
				(arc
					(start 326.218296 -425.342812)
					(mid 326.164414 -425.36513)
					(end 326.142096 -425.419012)
				)
				(arc
					(start 326.142096 -426.146468)
					(mid 326.144095 -426.163809)
					(end 326.14997 -426.18025)
				)
				(arc
					(start 326.383396 -426.6565)
					(mid 326.391179 -426.690028)
					(end 326.383396 -426.723556)
				)
				(arc
					(start 326.14997 -427.199806)
					(mid 326.144075 -427.216242)
					(end 326.142096 -427.233588)
				)
			)
		)
	)
	(zone
		(layers "In5.Cu" "In7.Cu")
		(hatch none 0.5)
		(connect_pads
			(clearance 0)
		)
		(min_thickness 0.25)
		(keepout
			(tracks not_allowed)
			(vias allowed)
			(pads allowed)
			(copperpour not_allowed)
			(footprints allowed)
		)
		(placement
			(enabled no)
			(sheetname "")
		)
		(fill yes
			(thermal_gap 0.5)
			(thermal_bridge_width 0.5)
			(island_removal_mode 0)
		)
		(polygon
			(pts
				(arc
					(start 133.24205 -431.560478)
					(mid 133.264368 -431.61436)
					(end 133.31825 -431.636678)
				)
				(arc
					(start 134.25805 -431.636678)
					(mid 134.311932 -431.61436)
					(end 134.33425 -431.560478)
				)
				(arc
					(start 134.33425 -429.018954)
					(mid 134.311932 -428.965072)
					(end 134.25805 -428.942754)
				)
				(arc
					(start 133.31825 -428.942754)
					(mid 133.264368 -428.965072)
					(end 133.24205 -429.018954)
				)
				(arc
					(start 133.24205 -429.74641)
					(mid 133.244049 -429.763751)
					(end 133.249924 -429.780192)
				)
				(arc
					(start 133.48335 -430.256442)
					(mid 133.491133 -430.28997)
					(end 133.48335 -430.323498)
				)
				(arc
					(start 133.249924 -430.799748)
					(mid 133.244029 -430.816184)
					(end 133.24205 -430.83353)
				)
			)
		)
	)
	(zone
		(layers "In5.Cu" "In7.Cu")
		(hatch none 0.5)
		(connect_pads
			(clearance 0)
		)
		(min_thickness 0.25)
		(keepout
			(tracks not_allowed)
			(vias allowed)
			(pads allowed)
			(copperpour not_allowed)
			(footprints allowed)
		)
		(placement
			(enabled no)
			(sheetname "")
		)
		(fill yes
			(thermal_gap 0.5)
			(thermal_bridge_width 0.5)
			(island_removal_mode 0)
		)
		(polygon
			(pts
				(arc
					(start 77.142086 -428.960534)
					(mid 77.164404 -429.014416)
					(end 77.218286 -429.036734)
				)
				(arc
					(start 78.158086 -429.036734)
					(mid 78.211968 -429.014416)
					(end 78.234286 -428.960534)
				)
				(arc
					(start 78.234286 -426.41901)
					(mid 78.211968 -426.365128)
					(end 78.158086 -426.34281)
				)
				(arc
					(start 77.218286 -426.34281)
					(mid 77.164404 -426.365128)
					(end 77.142086 -426.41901)
				)
				(arc
					(start 77.142086 -427.146466)
					(mid 77.144085 -427.163807)
					(end 77.14996 -427.180248)
				)
				(arc
					(start 77.383386 -427.656498)
					(mid 77.391169 -427.690026)
					(end 77.383386 -427.723554)
				)
				(arc
					(start 77.14996 -428.199804)
					(mid 77.144065 -428.21624)
					(end 77.142086 -428.233586)
				)
			)
		)
	)
	(zone
		(layers "In5.Cu" "In7.Cu")
		(hatch none 0.5)
		(connect_pads
			(clearance 0)
		)
		(min_thickness 0.25)
		(keepout
			(tracks not_allowed)
			(vias allowed)
			(pads allowed)
			(copperpour not_allowed)
			(footprints allowed)
		)
		(placement
			(enabled no)
			(sheetname "")
		)
		(fill yes
			(thermal_gap 0.5)
			(thermal_bridge_width 0.5)
			(island_removal_mode 0)
		)
		(polygon
			(pts
				(arc
					(start 345.142058 -428.960534)
					(mid 345.164376 -429.014416)
					(end 345.218258 -429.036734)
				)
				(arc
					(start 346.158058 -429.036734)
					(mid 346.21194 -429.014416)
					(end 346.234258 -428.960534)
				)
				(arc
					(start 346.234258 -426.41901)
					(mid 346.21194 -426.365128)
					(end 346.158058 -426.34281)
				)
				(arc
					(start 345.218258 -426.34281)
					(mid 345.164376 -426.365128)
					(end 345.142058 -426.41901)
				)
				(arc
					(start 345.142058 -427.146466)
					(mid 345.144057 -427.163807)
					(end 345.149932 -427.180248)
				)
				(arc
					(start 345.383358 -427.656498)
					(mid 345.391141 -427.690026)
					(end 345.383358 -427.723554)
				)
				(arc
					(start 345.149932 -428.199804)
					(mid 345.144037 -428.21624)
					(end 345.142058 -428.233586)
				)
			)
		)
	)
	(zone
		(layers "In5.Cu" "In7.Cu")
		(hatch none 0.5)
		(connect_pads
			(clearance 0)
		)
		(min_thickness 0.25)
		(keepout
			(tracks not_allowed)
			(vias allowed)
			(pads allowed)
			(copperpour not_allowed)
			(footprints allowed)
		)
		(placement
			(enabled no)
			(sheetname "")
		)
		(fill yes
			(thermal_gap 0.5)
			(thermal_bridge_width 0.5)
			(island_removal_mode 0)
		)
		(polygon
			(pts
				(arc
					(start 337.142074 -428.960534)
					(mid 337.164392 -429.014416)
					(end 337.218274 -429.036734)
				)
				(arc
					(start 338.158074 -429.036734)
					(mid 338.211956 -429.014416)
					(end 338.234274 -428.960534)
				)
				(arc
					(start 338.234274 -426.41901)
					(mid 338.211956 -426.365128)
					(end 338.158074 -426.34281)
				)
				(arc
					(start 337.218274 -426.34281)
					(mid 337.164392 -426.365128)
					(end 337.142074 -426.41901)
				)
				(arc
					(start 337.142074 -427.146466)
					(mid 337.144073 -427.163807)
					(end 337.149948 -427.180248)
				)
				(arc
					(start 337.383374 -427.656498)
					(mid 337.391157 -427.690026)
					(end 337.383374 -427.723554)
				)
				(arc
					(start 337.149948 -428.199804)
					(mid 337.144053 -428.21624)
					(end 337.142074 -428.233586)
				)
			)
		)
	)
	(zone
		(layers "In5.Cu" "In7.Cu")
		(hatch none 0.5)
		(connect_pads
			(clearance 0)
		)
		(min_thickness 0.25)
		(keepout
			(tracks not_allowed)
			(vias allowed)
			(pads allowed)
			(copperpour not_allowed)
			(footprints allowed)
		)
		(placement
			(enabled no)
			(sheetname "")
		)
		(fill yes
			(thermal_gap 0.5)
			(thermal_bridge_width 0.5)
			(island_removal_mode 0)
		)
		(polygon
			(pts
				(arc
					(start 58.142124 -427.960536)
					(mid 58.164442 -428.014418)
					(end 58.218324 -428.036736)
				)
				(arc
					(start 59.158124 -428.036736)
					(mid 59.212006 -428.014418)
					(end 59.234324 -427.960536)
				)
				(arc
					(start 59.234324 -425.419012)
					(mid 59.212006 -425.36513)
					(end 59.158124 -425.342812)
				)
				(arc
					(start 58.218324 -425.342812)
					(mid 58.164442 -425.36513)
					(end 58.142124 -425.419012)
				)
				(arc
					(start 58.142124 -426.146468)
					(mid 58.144123 -426.163809)
					(end 58.149998 -426.18025)
				)
				(arc
					(start 58.383424 -426.6565)
					(mid 58.391207 -426.690028)
					(end 58.383424 -426.723556)
				)
				(arc
					(start 58.149998 -427.199806)
					(mid 58.144103 -427.216242)
					(end 58.142124 -427.233588)
				)
			)
		)
	)
	(zone
		(layers "In5.Cu" "In7.Cu")
		(hatch none 0.5)
		(connect_pads
			(clearance 0)
		)
		(min_thickness 0.25)
		(keepout
			(tracks not_allowed)
			(vias allowed)
			(pads allowed)
			(copperpour not_allowed)
			(footprints allowed)
		)
		(placement
			(enabled no)
			(sheetname "")
		)
		(fill yes
			(thermal_gap 0.5)
			(thermal_bridge_width 0.5)
			(island_removal_mode 0)
		)
		(polygon
			(pts
				(arc
					(start 324.1421 -428.960534)
					(mid 324.164418 -429.014416)
					(end 324.2183 -429.036734)
				)
				(arc
					(start 325.1581 -429.036734)
					(mid 325.211982 -429.014416)
					(end 325.2343 -428.960534)
				)
				(arc
					(start 325.2343 -426.41901)
					(mid 325.211982 -426.365128)
					(end 325.1581 -426.34281)
				)
				(arc
					(start 324.2183 -426.34281)
					(mid 324.164418 -426.365128)
					(end 324.1421 -426.41901)
				)
				(arc
					(start 324.1421 -427.146466)
					(mid 324.144099 -427.163807)
					(end 324.149974 -427.180248)
				)
				(arc
					(start 324.3834 -427.656498)
					(mid 324.391183 -427.690026)
					(end 324.3834 -427.723554)
				)
				(arc
					(start 324.149974 -428.199804)
					(mid 324.144079 -428.21624)
					(end 324.1421 -428.233586)
				)
			)
		)
	)
	(zone
		(layers "In5.Cu" "In7.Cu")
		(hatch none 0.5)
		(connect_pads
			(clearance 0)
		)
		(min_thickness 0.25)
		(keepout
			(tracks not_allowed)
			(vias allowed)
			(pads allowed)
			(copperpour not_allowed)
			(footprints allowed)
		)
		(placement
			(enabled no)
			(sheetname "")
		)
		(fill yes
			(thermal_gap 0.5)
			(thermal_bridge_width 0.5)
			(island_removal_mode 0)
		)
		(polygon
			(pts
				(arc
					(start 89.142062 -428.960534)
					(mid 89.16438 -429.014416)
					(end 89.218262 -429.036734)
				)
				(arc
					(start 90.158062 -429.036734)
					(mid 90.211944 -429.014416)
					(end 90.234262 -428.960534)
				)
				(arc
					(start 90.234262 -426.41901)
					(mid 90.211944 -426.365128)
					(end 90.158062 -426.34281)
				)
				(arc
					(start 89.218262 -426.34281)
					(mid 89.16438 -426.365128)
					(end 89.142062 -426.41901)
				)
				(arc
					(start 89.142062 -427.146466)
					(mid 89.144061 -427.163807)
					(end 89.149936 -427.180248)
				)
				(arc
					(start 89.383362 -427.656498)
					(mid 89.391145 -427.690026)
					(end 89.383362 -427.723554)
				)
				(arc
					(start 89.149936 -428.199804)
					(mid 89.144041 -428.21624)
					(end 89.142062 -428.233586)
				)
			)
		)
	)
	(zone
		(layers "In5.Cu" "In7.Cu")
		(hatch none 0.5)
		(connect_pads
			(clearance 0)
		)
		(min_thickness 0.25)
		(keepout
			(tracks not_allowed)
			(vias allowed)
			(pads allowed)
			(copperpour not_allowed)
			(footprints allowed)
		)
		(placement
			(enabled no)
			(sheetname "")
		)
		(fill yes
			(thermal_gap 0.5)
			(thermal_bridge_width 0.5)
			(island_removal_mode 0)
		)
		(polygon
			(pts
				(arc
					(start 383.242058 -432.560476)
					(mid 383.264376 -432.614358)
					(end 383.318258 -432.636676)
				)
				(arc
					(start 384.258058 -432.636676)
					(mid 384.31194 -432.614358)
					(end 384.334258 -432.560476)
				)
				(arc
					(start 384.334258 -430.018952)
					(mid 384.31194 -429.96507)
					(end 384.258058 -429.942752)
				)
				(arc
					(start 383.318258 -429.942752)
					(mid 383.264376 -429.96507)
					(end 383.242058 -430.018952)
				)
				(arc
					(start 383.242058 -430.746408)
					(mid 383.244057 -430.763749)
					(end 383.249932 -430.78019)
				)
				(arc
					(start 383.483358 -431.25644)
					(mid 383.491141 -431.289968)
					(end 383.483358 -431.323496)
				)
				(arc
					(start 383.249932 -431.799746)
					(mid 383.244037 -431.816182)
					(end 383.242058 -431.833528)
				)
			)
		)
	)
	(zone
		(layer "In6.Cu")
		(hatch none 0.5)
		(connect_pads
			(clearance 0)
		)
		(min_thickness 0.25)
		(keepout
			(tracks allowed)
			(vias allowed)
			(pads allowed)
			(copperpour allowed)
			(footprints allowed)
		)
		(placement
			(enabled no)
			(sheetname "")
		)
		(fill
			(thermal_gap 0.5)
			(thermal_bridge_width 0.5)
			(island_removal_mode 0)
		)
		(polygon
			(pts
				(xy 283.54274 -300.464982) (xy 283.54274 -298.197524) (xy 284.227778 -298.197524) (xy 284.227778 -300.464982)
			)
		)
	)
	(zone
		(layer "In6.Cu")
		(hatch none 0.5)
		(connect_pads
			(clearance 0)
		)
		(min_thickness 0.25)
		(keepout
			(tracks allowed)
			(vias allowed)
			(pads allowed)
			(copperpour allowed)
			(footprints allowed)
		)
		(placement
			(enabled no)
			(sheetname "")
		)
		(fill
			(thermal_gap 0.5)
			(thermal_bridge_width 0.5)
			(island_removal_mode 0)
		)
		(polygon
			(pts
				(xy 28.887674 -168.496234) (xy 28.887674 -160.663382) (xy 33.424622 -160.663382) (xy 33.424622 -168.496234)
			)
		)
	)
	(zone
		(layer "In6.Cu")
		(hatch none 0.5)
		(connect_pads
			(clearance 0)
		)
		(min_thickness 0.25)
		(keepout
			(tracks allowed)
			(vias allowed)
			(pads allowed)
			(copperpour allowed)
			(footprints allowed)
		)
		(placement
			(enabled no)
			(sheetname "")
		)
		(fill
			(thermal_gap 0.5)
			(thermal_bridge_width 0.5)
			(island_removal_mode 0)
		)
		(polygon
			(pts
				(xy 409.46705 -229.864666) (xy 409.46705 -228.512624) (xy 410.042614 -228.512624) (xy 410.042614 -229.864666)
			)
		)
	)
	(zone
		(layer "In6.Cu")
		(hatch none 0.5)
		(connect_pads
			(clearance 0)
		)
		(min_thickness 0.25)
		(keepout
			(tracks allowed)
			(vias allowed)
			(pads allowed)
			(copperpour allowed)
			(footprints allowed)
		)
		(placement
			(enabled no)
			(sheetname "")
		)
		(fill
			(thermal_gap 0.5)
			(thermal_bridge_width 0.5)
			(island_removal_mode 0)
		)
		(polygon
			(pts
				(xy 143.03756 -19.9771) (xy 143.03756 -17.19834) (xy 140.07592 -17.19834) (xy 140.07592 -19.9771)
			)
		)
	)
	(zone
		(layer "In6.Cu")
		(hatch none 0.5)
		(connect_pads
			(clearance 0)
		)
		(min_thickness 0.25)
		(keepout
			(tracks allowed)
			(vias allowed)
			(pads allowed)
			(copperpour allowed)
			(footprints allowed)
		)
		(placement
			(enabled no)
			(sheetname "")
		)
		(fill
			(thermal_gap 0.5)
			(thermal_bridge_width 0.5)
			(island_removal_mode 0)
		)
		(polygon
			(pts
				(xy 172.447966 -208.571338) (xy 172.447966 -205.546198) (xy 173.07814 -205.546198) (xy 173.07814 -208.571338)
			)
		)
	)
	(zone
		(layer "In6.Cu")
		(hatch none 0.5)
		(connect_pads
			(clearance 0)
		)
		(min_thickness 0.25)
		(keepout
			(tracks allowed)
			(vias allowed)
			(pads allowed)
			(copperpour allowed)
			(footprints allowed)
		)
		(placement
			(enabled no)
			(sheetname "")
		)
		(fill
			(thermal_gap 0.5)
			(thermal_bridge_width 0.5)
			(island_removal_mode 0)
		)
		(polygon
			(pts
				(xy 191.752982 -214.7443) (xy 191.752982 -213.212426) (xy 192.328546 -213.212426) (xy 192.328546 -214.7443)
			)
		)
	)
	(zone
		(layer "In6.Cu")
		(hatch none 0.5)
		(connect_pads
			(clearance 0)
		)
		(min_thickness 0.25)
		(keepout
			(tracks allowed)
			(vias allowed)
			(pads allowed)
			(copperpour allowed)
			(footprints allowed)
		)
		(placement
			(enabled no)
			(sheetname "")
		)
		(fill
			(thermal_gap 0.5)
			(thermal_bridge_width 0.5)
			(island_removal_mode 0)
		)
		(polygon
			(pts
				(xy 348.08414 -297.937428) (xy 348.08414 -292.222428) (xy 350.18726 -292.222428) (xy 350.18726 -297.937428)
			)
		)
	)
	(zone
		(layer "In6.Cu")
		(hatch none 0.5)
		(connect_pads
			(clearance 0)
		)
		(min_thickness 0.25)
		(keepout
			(tracks allowed)
			(vias allowed)
			(pads allowed)
			(copperpour allowed)
			(footprints allowed)
		)
		(placement
			(enabled no)
			(sheetname "")
		)
		(fill
			(thermal_gap 0.5)
			(thermal_bridge_width 0.5)
			(island_removal_mode 0)
		)
		(polygon
			(pts
				(xy 283.54274 -278.36495) (xy 283.54274 -276.097492) (xy 284.227778 -276.097492) (xy 284.227778 -278.36495)
			)
		)
	)
	(zone
		(layer "In6.Cu")
		(hatch none 0.5)
		(connect_pads
			(clearance 0)
		)
		(min_thickness 0.25)
		(keepout
			(tracks allowed)
			(vias allowed)
			(pads allowed)
			(copperpour allowed)
			(footprints allowed)
		)
		(placement
			(enabled no)
			(sheetname "")
		)
		(fill
			(thermal_gap 0.5)
			(thermal_bridge_width 0.5)
			(island_removal_mode 0)
		)
		(polygon
			(pts
				(xy 105.70718 -297.744388) (xy 105.70718 -292.240208) (xy 108.12526 -292.240208) (xy 108.12526 -297.744388)
			)
		)
	)
	(zone
		(layer "In6.Cu")
		(hatch none 0.5)
		(connect_pads
			(clearance 0)
		)
		(min_thickness 0.25)
		(keepout
			(tracks allowed)
			(vias allowed)
			(pads allowed)
			(copperpour allowed)
			(footprints allowed)
		)
		(placement
			(enabled no)
			(sheetname "")
		)
		(fill
			(thermal_gap 0.5)
			(thermal_bridge_width 0.5)
			(island_removal_mode 0)
		)
		(polygon
			(pts
				(xy 20.638008 -310.60644) (xy 20.638008 -309.28437) (xy 21.165566 -309.28437) (xy 21.165566 -310.60644)
			)
		)
	)
	(zone
		(layer "In6.Cu")
		(hatch none 0.5)
		(connect_pads
			(clearance 0)
		)
		(min_thickness 0.25)
		(keepout
			(tracks allowed)
			(vias allowed)
			(pads allowed)
			(copperpour allowed)
			(footprints allowed)
		)
		(placement
			(enabled no)
			(sheetname "")
		)
		(fill
			(thermal_gap 0.5)
			(thermal_bridge_width 0.5)
			(island_removal_mode 0)
		)
		(polygon
			(pts
				(xy 283.665676 -223.906334) (xy 283.665676 -222.584264) (xy 284.193234 -222.584264) (xy 284.193234 -223.906334)
			)
		)
	)
	(zone
		(layer "In6.Cu")
		(hatch none 0.5)
		(connect_pads
			(clearance 0)
		)
		(min_thickness 0.25)
		(keepout
			(tracks allowed)
			(vias allowed)
			(pads allowed)
			(copperpour allowed)
			(footprints allowed)
		)
		(placement
			(enabled no)
			(sheetname "")
		)
		(fill
			(thermal_gap 0.5)
			(thermal_bridge_width 0.5)
			(island_removal_mode 0)
		)
		(polygon
			(pts
				(xy 31.598362 -317.372492) (xy 31.598362 -316.063884) (xy 32.132778 -316.063884) (xy 32.132778 -317.372492)
			)
		)
	)
	(zone
		(layer "In6.Cu")
		(hatch none 0.5)
		(connect_pads
			(clearance 0)
		)
		(min_thickness 0.25)
		(keepout
			(tracks allowed)
			(vias allowed)
			(pads allowed)
			(copperpour allowed)
			(footprints allowed)
		)
		(placement
			(enabled no)
			(sheetname "")
		)
		(fill
			(thermal_gap 0.5)
			(thermal_bridge_width 0.5)
			(island_removal_mode 0)
		)
		(polygon
			(pts
				(xy 268.578076 -313.156346) (xy 268.578076 -311.834276) (xy 269.105634 -311.834276) (xy 269.105634 -313.156346)
			)
		)
	)
	(zone
		(layer "In6.Cu")
		(hatch none 0.5)
		(connect_pads
			(clearance 0)
		)
		(min_thickness 0.25)
		(keepout
			(tracks allowed)
			(vias allowed)
			(pads allowed)
			(copperpour allowed)
			(footprints allowed)
		)
		(placement
			(enabled no)
			(sheetname "")
		)
		(fill
			(thermal_gap 0.5)
			(thermal_bridge_width 0.5)
			(island_removal_mode 0)
		)
		(polygon
			(pts
				(xy 76.03998 -345.079828) (xy 76.03998 -343.017348) (xy 77.59446 -343.017348) (xy 77.59446 -345.079828)
			)
		)
	)
	(zone
		(layer "In6.Cu")
		(hatch none 0.5)
		(connect_pads
			(clearance 0)
		)
		(min_thickness 0.25)
		(keepout
			(tracks allowed)
			(vias allowed)
			(pads allowed)
			(copperpour allowed)
			(footprints allowed)
		)
		(placement
			(enabled no)
			(sheetname "")
		)
		(fill
			(thermal_gap 0.5)
			(thermal_bridge_width 0.5)
			(island_removal_mode 0)
		)
		(polygon
			(pts
				(xy 458.224382 -246.00408) (xy 458.224382 -243.812314) (xy 458.799946 -243.812314) (xy 458.799946 -246.00408)
			)
		)
	)
	(zone
		(layer "In6.Cu")
		(hatch none 0.5)
		(connect_pads
			(clearance 0)
		)
		(min_thickness 0.25)
		(keepout
			(tracks allowed)
			(vias allowed)
			(pads allowed)
			(copperpour allowed)
			(footprints allowed)
		)
		(placement
			(enabled no)
			(sheetname "")
		)
		(fill
			(thermal_gap 0.5)
			(thermal_bridge_width 0.5)
			(island_removal_mode 0)
		)
		(polygon
			(pts
				(xy 283.54274 -286.864806) (xy 283.54274 -284.597348) (xy 284.227778 -284.597348) (xy 284.227778 -286.864806)
			)
		)
	)
	(zone
		(layer "In6.Cu")
		(hatch none 0.5)
		(connect_pads
			(clearance 0)
		)
		(min_thickness 0.25)
		(keepout
			(tracks allowed)
			(vias allowed)
			(pads allowed)
			(copperpour allowed)
			(footprints allowed)
		)
		(placement
			(enabled no)
			(sheetname "")
		)
		(fill
			(thermal_gap 0.5)
			(thermal_bridge_width 0.5)
			(island_removal_mode 0)
		)
		(polygon
			(pts
				(xy 210.284314 -246.00408) (xy 210.284314 -243.812314) (xy 210.859878 -243.812314) (xy 210.859878 -246.00408)
			)
		)
	)
	(zone
		(layer "In6.Cu")
		(hatch none 0.5)
		(connect_pads
			(clearance 0)
		)
		(min_thickness 0.25)
		(keepout
			(tracks allowed)
			(vias allowed)
			(pads allowed)
			(copperpour allowed)
			(footprints allowed)
		)
		(placement
			(enabled no)
			(sheetname "")
		)
		(fill
			(thermal_gap 0.5)
			(thermal_bridge_width 0.5)
			(island_removal_mode 0)
		)
		(polygon
			(pts
				(xy 435.567582 -285.96463) (xy 435.567582 -284.612588) (xy 436.143146 -284.612588) (xy 436.143146 -285.96463)
			)
		)
	)
	(zone
		(layer "In6.Cu")
		(hatch none 0.5)
		(connect_pads
			(clearance 0)
		)
		(min_thickness 0.25)
		(keepout
			(tracks allowed)
			(vias allowed)
			(pads allowed)
			(copperpour allowed)
			(footprints allowed)
		)
		(placement
			(enabled no)
			(sheetname "")
		)
		(fill
			(thermal_gap 0.5)
			(thermal_bridge_width 0.5)
			(island_removal_mode 0)
		)
		(polygon
			(pts
				(xy 172.447966 -213.765638) (xy 172.447966 -209.79638) (xy 173.07814 -209.79638) (xy 173.07814 -213.765638)
			)
		)
	)
	(zone
		(layer "In6.Cu")
		(hatch none 0.5)
		(connect_pads
			(clearance 0)
		)
		(min_thickness 0.25)
		(keepout
			(tracks allowed)
			(vias allowed)
			(pads allowed)
			(copperpour allowed)
			(footprints allowed)
		)
		(placement
			(enabled no)
			(sheetname "")
		)
		(fill
			(thermal_gap 0.5)
			(thermal_bridge_width 0.5)
			(island_removal_mode 0)
		)
		(polygon
			(pts
				(xy 121.9327 -18.54962) (xy 121.9327 -16.58366) (xy 121.22658 -16.58366) (xy 121.22658 -18.54962)
			)
		)
	)
	(zone
		(layer "In6.Cu")
		(hatch none 0.5)
		(connect_pads
			(clearance 0)
		)
		(min_thickness 0.25)
		(keepout
			(tracks allowed)
			(vias allowed)
			(pads allowed)
			(copperpour allowed)
			(footprints allowed)
		)
		(placement
			(enabled no)
			(sheetname "")
		)
		(fill
			(thermal_gap 0.5)
			(thermal_bridge_width 0.5)
			(island_removal_mode 0)
		)
		(polygon
			(pts
				(xy 161.526982 -229.864666) (xy 161.526982 -228.512624) (xy 162.102546 -228.512624) (xy 162.102546 -229.864666)
			)
		)
	)
	(zone
		(layer "In6.Cu")
		(hatch none 0.5)
		(connect_pads
			(clearance 0)
		)
		(min_thickness 0.25)
		(keepout
			(tracks allowed)
			(vias allowed)
			(pads allowed)
			(copperpour allowed)
			(footprints allowed)
		)
		(placement
			(enabled no)
			(sheetname "")
		)
		(fill
			(thermal_gap 0.5)
			(thermal_bridge_width 0.5)
			(island_removal_mode 0)
		)
		(polygon
			(pts
				(xy 409.46705 -225.614484) (xy 409.46705 -224.262442) (xy 410.042614 -224.262442) (xy 410.042614 -225.614484)
			)
		)
	)
	(zone
		(layer "In6.Cu")
		(hatch none 0.5)
		(connect_pads
			(clearance 0)
		)
		(min_thickness 0.25)
		(keepout
			(tracks allowed)
			(vias allowed)
			(pads allowed)
			(copperpour allowed)
			(footprints allowed)
		)
		(placement
			(enabled no)
			(sheetname "")
		)
		(fill
			(thermal_gap 0.5)
			(thermal_bridge_width 0.5)
			(island_removal_mode 0)
		)
		(polygon
			(pts
				(xy 157.426914 -230.71455) (xy 157.426914 -229.362508) (xy 158.002478 -229.362508) (xy 158.002478 -230.71455)
			)
		)
	)
	(zone
		(layer "In6.Cu")
		(hatch none 0.5)
		(connect_pads
			(clearance 0)
		)
		(min_thickness 0.25)
		(keepout
			(tracks allowed)
			(vias allowed)
			(pads allowed)
			(copperpour allowed)
			(footprints allowed)
		)
		(placement
			(enabled no)
			(sheetname "")
		)
		(fill
			(thermal_gap 0.5)
			(thermal_bridge_width 0.5)
			(island_removal_mode 0)
		)
		(polygon
			(pts
				(xy 287.31718 -367.629948) (xy 287.31718 -366.347248) (xy 289.09264 -366.347248) (xy 289.09264 -367.629948)
			)
		)
	)
	(zone
		(layer "In6.Cu")
		(hatch none 0.5)
		(connect_pads
			(clearance 0)
		)
		(min_thickness 0.25)
		(keepout
			(tracks allowed)
			(vias allowed)
			(pads allowed)
			(copperpour allowed)
			(footprints allowed)
		)
		(placement
			(enabled no)
			(sheetname "")
		)
		(fill
			(thermal_gap 0.5)
			(thermal_bridge_width 0.5)
			(island_removal_mode 0)
		)
		(polygon
			(pts
				(xy 35.602672 -278.36495) (xy 35.602672 -276.097492) (xy 36.28771 -276.097492) (xy 36.28771 -278.36495)
			)
		)
	)
	(zone
		(layer "In6.Cu")
		(hatch none 0.5)
		(connect_pads
			(clearance 0)
		)
		(min_thickness 0.25)
		(keepout
			(tracks allowed)
			(vias allowed)
			(pads allowed)
			(copperpour allowed)
			(footprints allowed)
		)
		(placement
			(enabled no)
			(sheetname "")
		)
		(fill
			(thermal_gap 0.5)
			(thermal_bridge_width 0.5)
			(island_removal_mode 0)
		)
		(polygon
			(pts
				(xy 172.539914 -243.464588) (xy 172.539914 -242.112546) (xy 173.115478 -242.112546) (xy 173.115478 -243.464588)
			)
		)
	)
	(zone
		(layer "In6.Cu")
		(hatch none 0.5)
		(connect_pads
			(clearance 0)
		)
		(min_thickness 0.25)
		(keepout
			(tracks allowed)
			(vias allowed)
			(pads allowed)
			(copperpour allowed)
			(footprints allowed)
		)
		(placement
			(enabled no)
			(sheetname "")
		)
		(fill
			(thermal_gap 0.5)
			(thermal_bridge_width 0.5)
			(island_removal_mode 0)
		)
		(polygon
			(pts
				(xy 268.578076 -206.05623) (xy 268.578076 -204.73416) (xy 269.105634 -204.73416) (xy 269.105634 -206.05623)
			)
		)
	)
	(zone
		(layer "In6.Cu")
		(hatch none 0.5)
		(connect_pads
			(clearance 0)
		)
		(min_thickness 0.25)
		(keepout
			(tracks allowed)
			(vias allowed)
			(pads allowed)
			(copperpour allowed)
			(footprints allowed)
		)
		(placement
			(enabled no)
			(sheetname "")
		)
		(fill
			(thermal_gap 0.5)
			(thermal_bridge_width 0.5)
			(island_removal_mode 0)
		)
		(polygon
			(pts
				(xy 176.639982 -314.014612) (xy 176.639982 -311.802018) (xy 177.215546 -311.802018) (xy 177.215546 -314.014612)
			)
		)
	)
	(zone
		(layer "In6.Cu")
		(hatch none 0.5)
		(connect_pads
			(clearance 0)
		)
		(min_thickness 0.25)
		(keepout
			(tracks allowed)
			(vias allowed)
			(pads allowed)
			(copperpour allowed)
			(footprints allowed)
		)
		(placement
			(enabled no)
			(sheetname "")
		)
		(fill
			(thermal_gap 0.5)
			(thermal_bridge_width 0.5)
			(island_removal_mode 0)
		)
		(polygon
			(pts
				(xy 313.789822 -269.71498) (xy 313.789822 -267.605256) (xy 314.433712 -267.605256) (xy 314.433712 -269.71498)
			)
		)
	)
	(zone
		(layer "In6.Cu")
		(hatch none 0.5)
		(connect_pads
			(clearance 0)
		)
		(min_thickness 0.25)
		(keepout
			(tracks allowed)
			(vias allowed)
			(pads allowed)
			(copperpour allowed)
			(footprints allowed)
		)
		(placement
			(enabled no)
			(sheetname "")
		)
		(fill
			(thermal_gap 0.5)
			(thermal_bridge_width 0.5)
			(island_removal_mode 0)
		)
		(polygon
			(pts
				(xy 46.71314 -214.084154) (xy 46.71314 -204.721714) (xy 46.46549 -204.721714) (xy 46.46549 -203.494132)
				(xy 46.71314 -203.494132) (xy 47.240698 -203.494132) (xy 47.240698 -214.084154) (xy 47.240698 -215.406224)
				(xy 46.71314 -215.406224) (xy 46.581568 -215.406224) (xy 46.581568 -214.084154)
			)
		)
	)
	(zone
		(layer "In6.Cu")
		(hatch none 0.5)
		(connect_pads
			(clearance 0)
		)
		(min_thickness 0.25)
		(keepout
			(tracks allowed)
			(vias allowed)
			(pads allowed)
			(copperpour allowed)
			(footprints allowed)
		)
		(placement
			(enabled no)
			(sheetname "")
		)
		(fill
			(thermal_gap 0.5)
			(thermal_bridge_width 0.5)
			(island_removal_mode 0)
		)
		(polygon
			(pts
				(xy 35.725608 -231.556306) (xy 35.725608 -230.234236) (xy 36.253166 -230.234236) (xy 36.253166 -231.556306)
			)
		)
	)
	(zone
		(layer "In6.Cu")
		(hatch none 0.5)
		(connect_pads
			(clearance 0)
		)
		(min_thickness 0.25)
		(keepout
			(tracks allowed)
			(vias allowed)
			(pads allowed)
			(copperpour allowed)
			(footprints allowed)
		)
		(placement
			(enabled no)
			(sheetname "")
		)
		(fill
			(thermal_gap 0.5)
			(thermal_bridge_width 0.5)
			(island_removal_mode 0)
		)
		(polygon
			(pts
				(xy 14.70152 -45.86478) (xy 14.70152 -43.57116) (xy 13.3477 -43.57116) (xy 13.3477 -45.86478)
			)
		)
	)
	(zone
		(layer "In6.Cu")
		(hatch none 0.5)
		(connect_pads
			(clearance 0)
		)
		(min_thickness 0.25)
		(keepout
			(tracks allowed)
			(vias allowed)
			(pads allowed)
			(copperpour allowed)
			(footprints allowed)
		)
		(placement
			(enabled no)
			(sheetname "")
		)
		(fill
			(thermal_gap 0.5)
			(thermal_bridge_width 0.5)
			(island_removal_mode 0)
		)
		(polygon
			(pts
				(xy 103.738172 -212.603588) (xy 108.338112 -212.603588) (xy 111.265462 -212.610954) (xy 138.537188 -212.610446)
				(xy 138.752326 -212.610446) (xy 142.681198 -216.539318) (xy 142.681198 -216.817194) (xy 142.495016 -217.003376)
				(xy 142.495016 -217.056716) (xy 142.650972 -217.212672) (xy 142.650972 -217.54338) (xy 142.43812 -217.756232)
				(xy 142.43812 -217.817192) (xy 142.597632 -217.976704) (xy 142.597632 -218.277186) (xy 142.540736 -218.334082)
				(xy 142.540736 -218.398852) (xy 142.715488 -218.573604) (xy 142.715488 -218.866466) (xy 142.521686 -219.060268)
				(xy 142.521686 -219.953586) (xy 138.814556 -223.660716) (xy 138.814556 -223.703388) (xy 139.655296 -224.544128)
				(xy 139.655296 -224.710752) (xy 139.496038 -224.87001) (xy 138.849354 -225.516694) (xy 138.849354 -225.61042)
				(xy 139.062206 -225.823272) (xy 139.138152 -225.823272) (xy 139.655296 -225.306128) (xy 139.913868 -225.306128)
				(xy 140.15339 -225.54565) (xy 140.15339 -225.788982) (xy 139.41552 -226.526852) (xy 139.41552 -229.339902)
				(xy 139.616942 -229.541324) (xy 140.115036 -229.541324) (xy 140.202412 -229.6287) (xy 140.202412 -230.997506)
				(xy 140.331698 -231.126792) (xy 140.331698 -232.48366) (xy 140.200634 -232.614724) (xy 140.200634 -234.650534)
				(xy 140.381482 -234.831382) (xy 140.381482 -236.992668) (xy 140.552424 -237.16361) (xy 140.552424 -242.739672)
				(xy 140.442696 -242.8494) (xy 137.90803 -242.8494) (xy 137.862818 -242.894612) (xy 137.862818 -243.2558)
				(xy 137.963656 -243.356638) (xy 137.963656 -243.943632) (xy 137.27684 -244.630448) (xy 137.27684 -245.970552)
				(xy 136.952228 -246.295164) (xy 136.952228 -247.276112) (xy 136.67486 -247.55348) (xy 136.67486 -247.907048)
				(xy 136.70915 -247.941338) (xy 137.632948 -247.941338) (xy 137.824464 -248.132854) (xy 137.824464 -249.218196)
				(xy 138.765788 -250.15952) (xy 138.765788 -250.6726) (xy 138.751818 -250.68657) (xy 138.622278 -250.68657)
				(xy 128.800098 -250.68657) (xy 127.796798 -251.68987) (xy 127.796798 -253.57201) (xy 128.408938 -254.18415)
				(xy 128.61544 -254.18415) (xy 128.925066 -253.874524) (xy 128.925066 -253.58852) (xy 128.839468 -253.502922)
				(xy 128.839468 -253.119128) (xy 128.919224 -253.039372) (xy 129.74447 -253.039372) (xy 129.773934 -253.068836)
				(xy 129.773934 -253.2126) (xy 129.773934 -253.5174) (xy 130.442462 -254.185928) (xy 131.572254 -254.185928)
				(xy 131.73456 -254.023622) (xy 131.73456 -253.495556) (xy 131.898898 -253.330964) (xy 132.183632 -253.04623)
				(xy 135.924798 -253.04623) (xy 135.945118 -253.02591) (xy 136.143238 -253.02591) (xy 136.221216 -253.02591)
				(xy 136.263634 -253.068328) (xy 136.263634 -253.317756) (xy 136.277858 -253.33198) (xy 137.78103 -253.33198)
				(xy 137.852912 -253.403862) (xy 137.852912 -253.981458) (xy 138.103864 -254.23241) (xy 139.90955 -254.23241)
				(xy 140.05814 -254.381) (xy 140.05814 -256.480056) (xy 139.93495 -256.603246) (xy 139.80795 -256.603246)
				(xy 122.45975 -256.6035) (xy 121.87555 -256.0193) (xy 121.51995 -256.0193) (xy 121.26595 -256.2733)
				(xy 121.26595 -256.4511) (xy 121.74855 -256.9337) (xy 137.927842 -256.933446) (xy 137.927842 -257.238246)
				(xy 137.927842 -257.567176) (xy 137.819384 -257.675634) (xy 137.819384 -258.48945) (xy 138.24458 -258.914646)
				(xy 139.70635 -258.914646) (xy 139.875768 -259.084064) (xy 139.875768 -260.1976) (xy 139.908026 -260.229858)
				(xy 140.560044 -260.229858) (xy 140.596366 -260.26618) (xy 140.596366 -261.290816) (xy 140.634212 -261.328662)
				(xy 140.96111 -261.328662) (xy 141.007084 -261.374636) (xy 141.007084 -262.171434) (xy 140.949172 -262.229346)
				(xy 140.900404 -262.229346) (xy 140.705586 -262.2296) (xy 140.705586 -275.318728) (xy 140.648436 -275.375878)
				(xy 140.302996 -275.375878) (xy 139.64793 -276.030944) (xy 139.64793 -276.038818) (xy 140.102082 -276.49297)
				(xy 140.367766 -276.49297) (xy 140.525754 -276.650958) (xy 140.525754 -276.916642) (xy 140.525754 -278.407368)
				(xy 140.65885 -278.540464) (xy 140.65885 -279.048718) (xy 140.567664 -279.139904) (xy 140.567664 -279.458928)
				(xy 140.41628 -279.610312) (xy 140.41628 -280.412444) (xy 140.567664 -280.563828) (xy 140.567664 -281.961844)
				(xy 138.085068 -284.44444) (xy 138.369548 -284.44444) (xy 138.369802 -290.269676) (xy 138.126216 -290.513262)
				(xy 111.2774 -290.51377) (xy 108.339636 -290.51377) (xy 103.739696 -290.51377)
			)
		)
	)
	(zone
		(layer "In6.Cu")
		(hatch none 0.5)
		(connect_pads
			(clearance 0)
		)
		(min_thickness 0.25)
		(keepout
			(tracks allowed)
			(vias allowed)
			(pads allowed)
			(copperpour allowed)
			(footprints allowed)
		)
		(placement
			(enabled no)
			(sheetname "")
		)
		(fill
			(thermal_gap 0.5)
			(thermal_bridge_width 0.5)
			(island_removal_mode 0)
		)
		(polygon
			(pts
				(xy 176.548034 -208.60258) (xy 176.548034 -207.24622) (xy 177.178208 -207.24622) (xy 177.178208 -208.60258)
			)
		)
	)
	(zone
		(layer "In6.Cu")
		(hatch none 0.5)
		(connect_pads
			(clearance 0)
		)
		(min_thickness 0.25)
		(keepout
			(tracks allowed)
			(vias allowed)
			(pads allowed)
			(copperpour allowed)
			(footprints allowed)
		)
		(placement
			(enabled no)
			(sheetname "")
		)
		(fill
			(thermal_gap 0.5)
			(thermal_bridge_width 0.5)
			(island_removal_mode 0)
		)
		(polygon
			(pts
				(xy 54.210966 -245.149878) (xy 54.210966 -243.766086) (xy 54.84114 -243.766086) (xy 54.84114 -245.149878)
			)
		)
	)
	(zone
		(layer "In6.Cu")
		(hatch none 0.5)
		(connect_pads
			(clearance 0)
		)
		(min_thickness 0.25)
		(keepout
			(tracks allowed)
			(vias allowed)
			(pads allowed)
			(copperpour allowed)
			(footprints allowed)
		)
		(placement
			(enabled no)
			(sheetname "")
		)
		(fill
			(thermal_gap 0.5)
			(thermal_bridge_width 0.5)
			(island_removal_mode 0)
		)
		(polygon
			(pts
				(xy 424.58005 -245.16461) (xy 424.58005 -243.812568) (xy 425.155614 -243.812568) (xy 425.155614 -245.16461)
			)
		)
	)
	(zone
		(layer "In6.Cu")
		(hatch none 0.5)
		(connect_pads
			(clearance 0)
		)
		(min_thickness 0.25)
		(keepout
			(tracks allowed)
			(vias allowed)
			(pads allowed)
			(copperpour allowed)
			(footprints allowed)
		)
		(placement
			(enabled no)
			(sheetname "")
		)
		(fill
			(thermal_gap 0.5)
			(thermal_bridge_width 0.5)
			(island_removal_mode 0)
		)
		(polygon
			(pts
				(xy 283.54274 -282.614878) (xy 283.54274 -280.34742) (xy 284.227778 -280.34742) (xy 284.227778 -282.614878)
			)
		)
	)
	(zone
		(layer "In6.Cu")
		(hatch none 0.5)
		(connect_pads
			(clearance 0)
		)
		(min_thickness 0.25)
		(keepout
			(tracks allowed)
			(vias allowed)
			(pads allowed)
			(copperpour allowed)
			(footprints allowed)
		)
		(placement
			(enabled no)
			(sheetname "")
		)
		(fill
			(thermal_gap 0.5)
			(thermal_bridge_width 0.5)
			(island_removal_mode 0)
		)
		(polygon
			(pts
				(xy 420.479982 -215.414606) (xy 420.479982 -214.062564) (xy 421.055546 -214.062564) (xy 421.055546 -215.414606)
			)
		)
	)
	(zone
		(layer "In6.Cu")
		(hatch none 0.5)
		(connect_pads
			(clearance 0)
		)
		(min_thickness 0.25)
		(keepout
			(tracks allowed)
			(vias allowed)
			(pads allowed)
			(copperpour allowed)
			(footprints allowed)
		)
		(placement
			(enabled no)
			(sheetname "")
		)
		(fill
			(thermal_gap 0.5)
			(thermal_bridge_width 0.5)
			(island_removal_mode 0)
		)
		(polygon
			(pts
				(xy 35.602672 -307.264816) (xy 35.602672 -304.997358) (xy 36.28771 -304.997358) (xy 36.28771 -307.264816)
				(xy 36.28771 -308.065932) (xy 35.602672 -308.065932)
			)
		)
	)
	(zone
		(layer "In6.Cu")
		(hatch none 0.5)
		(connect_pads
			(clearance 0)
		)
		(min_thickness 0.25)
		(keepout
			(tracks allowed)
			(vias allowed)
			(pads allowed)
			(copperpour allowed)
			(footprints allowed)
		)
		(placement
			(enabled no)
			(sheetname "")
		)
		(fill
			(thermal_gap 0.5)
			(thermal_bridge_width 0.5)
			(island_removal_mode 0)
		)
		(polygon
			(pts
				(xy 176.548034 -215.402668) (xy 176.548034 -214.046308) (xy 177.178208 -214.046308) (xy 177.178208 -215.402668)
			)
		)
	)
	(zone
		(layer "In6.Cu")
		(hatch none 0.5)
		(connect_pads
			(clearance 0)
		)
		(min_thickness 0.25)
		(keepout
			(tracks allowed)
			(vias allowed)
			(pads allowed)
			(copperpour allowed)
			(footprints allowed)
		)
		(placement
			(enabled no)
			(sheetname "")
		)
		(fill
			(thermal_gap 0.5)
			(thermal_bridge_width 0.5)
			(island_removal_mode 0)
		)
		(polygon
			(pts
				(xy 161.552382 -229.014528) (xy 161.552382 -227.662486) (xy 162.127946 -227.662486) (xy 162.127946 -229.014528)
			)
		)
	)
	(zone
		(layer "In6.Cu")
		(hatch none 0.5)
		(connect_pads
			(clearance 0)
		)
		(min_thickness 0.25)
		(keepout
			(tracks allowed)
			(vias allowed)
			(pads allowed)
			(copperpour allowed)
			(footprints allowed)
		)
		(placement
			(enabled no)
			(sheetname "")
		)
		(fill
			(thermal_gap 0.5)
			(thermal_bridge_width 0.5)
			(island_removal_mode 0)
		)
		(polygon
			(pts
				(xy 439.575702 -202.146408) (xy 440.205876 -202.146408) (xy 440.205876 -203.502768) (xy 440.205876 -204.088746)
				(xy 439.25871 -204.088746) (xy 439.25871 -203.502768) (xy 439.25871 -202.146408)
			)
		)
	)
	(zone
		(layer "In6.Cu")
		(hatch none 0.5)
		(connect_pads
			(clearance 0)
		)
		(min_thickness 0.25)
		(keepout
			(tracks allowed)
			(vias allowed)
			(pads allowed)
			(copperpour allowed)
			(footprints allowed)
		)
		(placement
			(enabled no)
			(sheetname "")
		)
		(fill
			(thermal_gap 0.5)
			(thermal_bridge_width 0.5)
			(island_removal_mode 0)
		)
		(polygon
			(pts
				(xy 202.740514 -205.394306) (xy 202.740514 -203.862432) (xy 203.316078 -203.862432) (xy 203.316078 -205.394306)
				(xy 203.316078 -206.844138) (xy 202.740514 -206.844138)
			)
		)
	)
	(zone
		(layer "In6.Cu")
		(hatch none 0.5)
		(connect_pads
			(clearance 0)
		)
		(min_thickness 0.25)
		(keepout
			(tracks allowed)
			(vias allowed)
			(pads allowed)
			(copperpour allowed)
			(footprints allowed)
		)
		(placement
			(enabled no)
			(sheetname "")
		)
		(fill
			(thermal_gap 0.5)
			(thermal_bridge_width 0.5)
			(island_removal_mode 0)
		)
		(polygon
			(pts
				(xy 35.602672 -300.464982) (xy 35.602672 -298.197524) (xy 36.28771 -298.197524) (xy 36.28771 -300.464982)
			)
		)
	)
	(zone
		(layer "In6.Cu")
		(hatch none 0.5)
		(connect_pads
			(clearance 0)
		)
		(min_thickness 0.25)
		(keepout
			(tracks allowed)
			(vias allowed)
			(pads allowed)
			(copperpour allowed)
			(footprints allowed)
		)
		(placement
			(enabled no)
			(sheetname "")
		)
		(fill
			(thermal_gap 0.5)
			(thermal_bridge_width 0.5)
			(island_removal_mode 0)
		)
		(polygon
			(pts
				(xy 115.79606 -338.889848) (xy 115.79606 -335.803748) (xy 123.00458 -335.803748) (xy 123.00458 -338.889848)
			)
		)
	)
	(zone
		(layer "In6.Cu")
		(hatch none 0.5)
		(connect_pads
			(clearance 0)
		)
		(min_thickness 0.25)
		(keepout
			(tracks allowed)
			(vias allowed)
			(pads allowed)
			(copperpour allowed)
			(footprints allowed)
		)
		(placement
			(enabled no)
			(sheetname "")
		)
		(fill
			(thermal_gap 0.5)
			(thermal_bridge_width 0.5)
			(island_removal_mode 0)
		)
		(polygon
			(pts
				(xy 311.631584 -243.464842) (xy 311.631584 -241.272822) (xy 312.152284 -241.272822) (xy 312.152284 -243.464842)
			)
		)
	)
	(zone
		(layer "In6.Cu")
		(hatch none 0.5)
		(connect_pads
			(clearance 0)
		)
		(min_thickness 0.25)
		(keepout
			(tracks allowed)
			(vias allowed)
			(pads allowed)
			(copperpour allowed)
			(footprints allowed)
		)
		(placement
			(enabled no)
			(sheetname "")
		)
		(fill
			(thermal_gap 0.5)
			(thermal_bridge_width 0.5)
			(island_removal_mode 0)
		)
		(polygon
			(pts
				(xy 409.49245 -229.014528) (xy 409.49245 -227.662486) (xy 410.068014 -227.662486) (xy 410.068014 -229.014528)
			)
		)
	)
	(zone
		(layer "In6.Cu")
		(hatch none 0.5)
		(connect_pads
			(clearance 0)
		)
		(min_thickness 0.25)
		(keepout
			(tracks allowed)
			(vias allowed)
			(pads allowed)
			(copperpour allowed)
			(footprints allowed)
		)
		(placement
			(enabled no)
			(sheetname "")
		)
		(fill
			(thermal_gap 0.5)
			(thermal_bridge_width 0.5)
			(island_removal_mode 0)
		)
		(polygon
			(pts
				(xy 435.475634 -203.502768) (xy 435.475634 -202.146408) (xy 436.105808 -202.146408) (xy 436.105808 -203.502768)
			)
		)
	)
	(zone
		(layer "In6.Cu")
		(hatch none 0.5)
		(connect_pads
			(clearance 0)
		)
		(min_thickness 0.25)
		(keepout
			(tracks allowed)
			(vias allowed)
			(pads allowed)
			(copperpour allowed)
			(footprints allowed)
		)
		(placement
			(enabled no)
			(sheetname "")
		)
		(fill
			(thermal_gap 0.5)
			(thermal_bridge_width 0.5)
			(island_removal_mode 0)
		)
		(polygon
			(pts
				(xy 176.639982 -304.664618) (xy 176.639982 -302.48098) (xy 177.215546 -302.48098) (xy 177.215546 -304.664618)
			)
		)
	)
	(zone
		(layer "In6.Cu")
		(hatch none 0.5)
		(connect_pads
			(clearance 0)
		)
		(min_thickness 0.25)
		(keepout
			(tracks allowed)
			(vias allowed)
			(pads allowed)
			(copperpour allowed)
			(footprints allowed)
		)
		(placement
			(enabled no)
			(sheetname "")
		)
		(fill
			(thermal_gap 0.5)
			(thermal_bridge_width 0.5)
			(island_removal_mode 0)
		)
		(polygon
			(pts
				(xy 351.67824 -212.603588) (xy 356.27818 -212.603588) (xy 359.20553 -212.610954) (xy 386.477256 -212.610446)
				(xy 386.692394 -212.610446) (xy 390.621266 -216.539318) (xy 390.621266 -216.817194) (xy 390.435084 -217.003376)
				(xy 390.435084 -217.056716) (xy 390.59104 -217.212672) (xy 390.59104 -217.54338) (xy 390.378188 -217.756232)
				(xy 390.378188 -217.817192) (xy 390.5377 -217.976704) (xy 390.5377 -218.277186) (xy 390.480804 -218.334082)
				(xy 390.480804 -218.398852) (xy 390.655556 -218.573604) (xy 390.655556 -218.866466) (xy 390.461754 -219.060268)
				(xy 390.461754 -219.953586) (xy 386.754624 -223.660716) (xy 386.754624 -223.703388) (xy 387.595364 -224.544128)
				(xy 387.595364 -224.710752) (xy 387.436106 -224.87001) (xy 386.789422 -225.516694) (xy 386.789422 -225.61042)
				(xy 387.002274 -225.823272) (xy 387.07822 -225.823272) (xy 387.595364 -225.306128) (xy 387.853936 -225.306128)
				(xy 388.093458 -225.54565) (xy 388.093458 -225.788982) (xy 387.355588 -226.526852) (xy 387.355588 -229.339902)
				(xy 387.55701 -229.541324) (xy 388.055104 -229.541324) (xy 388.14248 -229.6287) (xy 388.14248 -230.997506)
				(xy 388.271766 -231.126792) (xy 388.271766 -232.48366) (xy 388.140702 -232.614724) (xy 388.140702 -234.650534)
				(xy 388.32155 -234.831382) (xy 388.32155 -236.992668) (xy 388.492492 -237.16361) (xy 388.492492 -242.739672)
				(xy 388.382764 -242.8494) (xy 385.848098 -242.8494) (xy 385.802886 -242.894612) (xy 385.802886 -243.2558)
				(xy 385.903724 -243.356638) (xy 385.903724 -243.971064) (xy 385.245864 -244.628924) (xy 385.245864 -245.941596)
				(xy 384.892296 -246.295164) (xy 384.892296 -247.276112) (xy 384.614928 -247.55348) (xy 384.614928 -247.907048)
				(xy 384.649218 -247.941338) (xy 385.573016 -247.941338) (xy 385.764532 -248.132854) (xy 385.764532 -249.218196)
				(xy 386.705856 -250.15952) (xy 386.705856 -250.6726) (xy 386.691886 -250.68657) (xy 386.562346 -250.68657)
				(xy 376.740166 -250.68657) (xy 375.736866 -251.68987) (xy 375.736866 -253.57201) (xy 376.349006 -254.18415)
				(xy 376.555508 -254.18415) (xy 376.865134 -253.874524) (xy 376.865134 -253.58852) (xy 376.779536 -253.502922)
				(xy 376.779536 -253.119128) (xy 376.859292 -253.039372) (xy 377.684538 -253.039372) (xy 377.714002 -253.068836)
				(xy 377.714002 -253.2126) (xy 377.714002 -253.5174) (xy 378.38253 -254.185928) (xy 379.512322 -254.185928)
				(xy 379.674628 -254.023622) (xy 379.674628 -253.495556) (xy 379.838966 -253.330964) (xy 380.1237 -253.04623)
				(xy 383.864866 -253.04623) (xy 383.885186 -253.02591) (xy 384.083306 -253.02591) (xy 384.161284 -253.02591)
				(xy 384.203702 -253.068328) (xy 384.203702 -253.317756) (xy 384.217926 -253.33198) (xy 385.721098 -253.33198)
				(xy 385.79298 -253.403862) (xy 385.79298 -253.981458) (xy 386.043932 -254.23241) (xy 387.849618 -254.23241)
				(xy 387.998208 -254.381) (xy 387.998208 -256.480056) (xy 387.875018 -256.603246) (xy 387.748018 -256.603246)
				(xy 370.399818 -256.6035) (xy 369.815618 -256.0193) (xy 369.460018 -256.0193) (xy 369.206018 -256.2733)
				(xy 369.206018 -256.4511) (xy 369.688618 -256.9337) (xy 385.86791 -256.933446) (xy 385.86791 -257.238246)
				(xy 385.86791 -257.567176) (xy 385.759452 -257.675634) (xy 385.759452 -258.48945) (xy 386.184648 -258.914646)
				(xy 387.646418 -258.914646) (xy 387.815836 -259.084064) (xy 387.815836 -260.1976) (xy 387.848094 -260.229858)
				(xy 388.500112 -260.229858) (xy 388.536434 -260.26618) (xy 388.536434 -261.290816) (xy 388.57428 -261.328662)
				(xy 388.901178 -261.328662) (xy 388.947152 -261.374636) (xy 388.947152 -262.171434) (xy 388.88924 -262.229346)
				(xy 388.840472 -262.229346) (xy 388.645654 -262.2296) (xy 388.645654 -275.318728) (xy 388.588504 -275.375878)
				(xy 388.243064 -275.375878) (xy 387.587998 -276.030944) (xy 387.587998 -276.038818) (xy 388.04215 -276.49297)
				(xy 388.307834 -276.49297) (xy 388.465822 -276.650958) (xy 388.465822 -276.916642) (xy 388.465822 -278.407368)
				(xy 388.598918 -278.540464) (xy 388.598918 -279.00249) (xy 388.46633 -279.135078) (xy 388.46633 -279.531318)
				(xy 388.34314 -279.654508) (xy 388.34314 -280.411936) (xy 388.507732 -280.576528) (xy 388.507732 -281.974036)
				(xy 386.037328 -284.44444) (xy 386.309616 -284.44444) (xy 386.30987 -290.269676) (xy 386.066284 -290.513262)
				(xy 359.217468 -290.51377) (xy 356.279704 -290.51377) (xy 351.679764 -290.51377)
			)
		)
	)
	(zone
		(layer "In6.Cu")
		(hatch none 0.5)
		(connect_pads
			(clearance 0)
		)
		(min_thickness 0.25)
		(keepout
			(tracks allowed)
			(vias allowed)
			(pads allowed)
			(copperpour allowed)
			(footprints allowed)
		)
		(placement
			(enabled no)
			(sheetname "")
		)
		(fill
			(thermal_gap 0.5)
			(thermal_bridge_width 0.5)
			(island_removal_mode 0)
		)
		(polygon
			(pts
				(xy 3.35534 -74.41438) (xy 3.35534 -73.25106) (xy 1.62052 -73.25106) (xy 1.62052 -74.41438)
			)
		)
	)
	(zone
		(layer "In6.Cu")
		(hatch none 0.5)
		(connect_pads
			(clearance 0)
		)
		(min_thickness 0.25)
		(keepout
			(tracks allowed)
			(vias allowed)
			(pads allowed)
			(copperpour allowed)
			(footprints allowed)
		)
		(placement
			(enabled no)
			(sheetname "")
		)
		(fill
			(thermal_gap 0.5)
			(thermal_bridge_width 0.5)
			(island_removal_mode 0)
		)
		(polygon
			(pts
				(xy 202.715114 -312.302398) (xy 202.715114 -309.351426) (xy 202.632818 -309.351426) (xy 202.632818 -308.412642)
				(xy 202.632818 -308.082442) (xy 203.290678 -308.082442) (xy 203.290678 -308.412642) (xy 203.290678 -312.302398)
			)
		)
	)
	(zone
		(layer "In6.Cu")
		(hatch none 0.5)
		(connect_pads
			(clearance 0)
		)
		(min_thickness 0.25)
		(keepout
			(tracks allowed)
			(vias allowed)
			(pads allowed)
			(copperpour allowed)
			(footprints allowed)
		)
		(placement
			(enabled no)
			(sheetname "")
		)
		(fill
			(thermal_gap 0.5)
			(thermal_bridge_width 0.5)
			(island_removal_mode 0)
		)
		(polygon
			(pts
				(xy 261.034276 -246.006366) (xy 261.034276 -244.684296) (xy 261.561834 -244.684296) (xy 261.561834 -246.006366)
			)
		)
	)
	(zone
		(layer "In6.Cu")
		(hatch none 0.5)
		(connect_pads
			(clearance 0)
		)
		(min_thickness 0.25)
		(keepout
			(tracks allowed)
			(vias allowed)
			(pads allowed)
			(copperpour allowed)
			(footprints allowed)
		)
		(placement
			(enabled no)
			(sheetname "")
		)
		(fill
			(thermal_gap 0.5)
			(thermal_bridge_width 0.5)
			(island_removal_mode 0)
		)
		(polygon
			(pts
				(xy 283.54274 -272.415) (xy 283.54274 -270.147542) (xy 284.227778 -270.147542) (xy 284.227778 -272.415)
			)
		)
	)
	(zone
		(layer "In6.Cu")
		(hatch none 0.5)
		(connect_pads
			(clearance 0)
		)
		(min_thickness 0.25)
		(keepout
			(tracks allowed)
			(vias allowed)
			(pads allowed)
			(copperpour allowed)
			(footprints allowed)
		)
		(placement
			(enabled no)
			(sheetname "")
		)
		(fill
			(thermal_gap 0.5)
			(thermal_bridge_width 0.5)
			(island_removal_mode 0)
		)
		(polygon
			(pts
				(xy 412.29788 -366.756188) (xy 412.29788 -365.387128) (xy 413.55264 -365.387128) (xy 413.55264 -366.756188)
			)
		)
	)
	(zone
		(layer "In6.Cu")
		(hatch none 0.5)
		(connect_pads
			(clearance 0)
		)
		(min_thickness 0.25)
		(keepout
			(tracks allowed)
			(vias allowed)
			(pads allowed)
			(copperpour allowed)
			(footprints allowed)
		)
		(placement
			(enabled no)
			(sheetname "")
		)
		(fill
			(thermal_gap 0.5)
			(thermal_bridge_width 0.5)
			(island_removal_mode 0)
		)
		(polygon
			(pts
				(xy 309.67934 -304.609754) (xy 309.67934 -299.047408) (xy 310.295798 -299.047408) (xy 310.295798 -304.609754)
			)
		)
	)
	(zone
		(layer "In6.Cu")
		(hatch none 0.5)
		(connect_pads
			(clearance 0)
		)
		(min_thickness 0.25)
		(keepout
			(tracks allowed)
			(vias allowed)
			(pads allowed)
			(copperpour allowed)
			(footprints allowed)
		)
		(placement
			(enabled no)
			(sheetname "")
		)
		(fill
			(thermal_gap 0.5)
			(thermal_bridge_width 0.5)
			(island_removal_mode 0)
		)
		(polygon
			(pts
				(xy 35.602672 -289.414966) (xy 35.602672 -287.147508) (xy 36.28771 -287.147508) (xy 36.28771 -289.414966)
			)
		)
	)
	(zone
		(layer "In6.Cu")
		(hatch none 0.5)
		(connect_pads
			(clearance 0)
		)
		(min_thickness 0.25)
		(keepout
			(tracks allowed)
			(vias allowed)
			(pads allowed)
			(copperpour allowed)
			(footprints allowed)
		)
		(placement
			(enabled no)
			(sheetname "")
		)
		(fill
			(thermal_gap 0.5)
			(thermal_bridge_width 0.5)
			(island_removal_mode 0)
		)
		(polygon
			(pts
				(xy 331.574394 -290.514024) (xy 331.57414 -284.48635) (xy 332.010766 -284.049724) (xy 332.010766 -283.794454)
				(xy 331.73797 -283.521658) (xy 331.73797 -283.414216) (xy 331.947012 -283.205174) (xy 331.947012 -282.684474)
				(xy 332.357476 -282.27401) (xy 332.357476 -281.323034) (xy 332.29677 -281.262328) (xy 331.973428 -281.262328)
				(xy 331.832966 -281.121866) (xy 331.832966 -280.505916) (xy 331.77607 -280.44902) (xy 331.380846 -280.44902)
				(xy 331.277976 -280.34615) (xy 331.277976 -278.833326) (xy 331.13726 -278.69261) (xy 331.13726 -269.988792)
				(xy 331.105002 -269.956534) (xy 330.954634 -269.956534) (xy 330.867258 -269.869158) (xy 330.867258 -264.497312)
				(xy 330.414884 -264.044938) (xy 330.414884 -260.144514) (xy 330.516738 -260.04266) (xy 330.910946 -260.04266)
				(xy 330.910946 -258.112514) (xy 330.977494 -258.045966) (xy 332.024228 -258.045966) (xy 332.024228 -257.747008)
				(xy 346.777818 -257.746754) (xy 347.108018 -257.416554) (xy 347.108018 -257.060954) (xy 347.641418 -256.527554)
				(xy 347.641418 -256.197354) (xy 347.717618 -256.121154) (xy 347.870018 -256.121154) (xy 348.047818 -255.943354)
				(xy 348.047818 -255.511554) (xy 348.555818 -255.003554) (xy 348.555818 -254.622554) (xy 348.733618 -254.444754)
				(xy 349.216218 -254.444754) (xy 349.597218 -254.063754) (xy 349.597218 -253.758954) (xy 349.495618 -253.657354)
				(xy 349.063818 -253.657354) (xy 348.276418 -254.444754) (xy 348.276418 -254.825754) (xy 348.174818 -254.927354)
				(xy 348.149418 -254.927354) (xy 347.793818 -255.282954) (xy 347.793818 -255.638554) (xy 347.717618 -255.714754)
				(xy 347.692218 -255.714754) (xy 347.285818 -256.121154) (xy 347.285818 -256.476754) (xy 346.879418 -256.883154)
				(xy 346.879418 -257.213354) (xy 346.676218 -257.416554) (xy 332.706218 -257.416808) (xy 332.680818 -257.442208)
				(xy 331.028802 -257.442208) (xy 330.982828 -257.442208) (xy 330.91755 -257.442208) (xy 330.839064 -257.363722)
				(xy 330.839064 -255.051814) (xy 330.997306 -254.893572) (xy 332.223364 -254.893572) (xy 332.272132 -254.844804)
				(xy 332.272132 -252.645164) (xy 332.345792 -252.571504) (xy 332.760066 -252.571504) (xy 334.806544 -252.571504)
				(xy 335.016602 -252.781562) (xy 348.402402 -252.781308) (xy 348.402402 -250.368308) (xy 331.460602 -250.368562)
				(xy 331.25918 -250.16714) (xy 331.25918 -246.873268) (xy 331.228446 -246.842534) (xy 331.038454 -246.842534)
				(xy 330.973684 -246.777764) (xy 330.973684 -244.804692) (xy 330.897738 -244.728746) (xy 330.897738 -238.680244)
				(xy 330.64704 -238.429546) (xy 330.64704 -234.27055) (xy 330.407264 -234.030774) (xy 330.407264 -228.210872)
				(xy 330.266802 -228.07041) (xy 330.266802 -220.626432) (xy 331.573124 -219.32011) (xy 331.57287 -212.603842)
				(xy 351.67824 -212.603588) (xy 351.679764 -290.51377)
			)
		)
	)
	(zone
		(layer "In6.Cu")
		(hatch none 0.5)
		(connect_pads
			(clearance 0)
		)
		(min_thickness 0.25)
		(keepout
			(tracks allowed)
			(vias allowed)
			(pads allowed)
			(copperpour allowed)
			(footprints allowed)
		)
		(placement
			(enabled no)
			(sheetname "")
		)
		(fill
			(thermal_gap 0.5)
			(thermal_bridge_width 0.5)
			(island_removal_mode 0)
		)
		(polygon
			(pts
				(xy 16.92148 -100.95992) (xy 16.92148 -99.93122) (xy 18.3642 -99.93122) (xy 18.3642 -100.95992)
			)
		)
	)
	(zone
		(layer "In6.Cu")
		(hatch none 0.5)
		(connect_pads
			(clearance 0)
		)
		(min_thickness 0.25)
		(keepout
			(tracks allowed)
			(vias allowed)
			(pads allowed)
			(copperpour allowed)
			(footprints allowed)
		)
		(placement
			(enabled no)
			(sheetname "")
		)
		(fill
			(thermal_gap 0.5)
			(thermal_bridge_width 0.5)
			(island_removal_mode 0)
		)
		(polygon
			(pts
				(xy 63.691516 -243.464842) (xy 63.691516 -241.272822) (xy 64.212216 -241.272822) (xy 64.212216 -243.464842)
			)
		)
	)
	(zone
		(layer "In6.Cu")
		(hatch none 0.5)
		(connect_pads
			(clearance 0)
		)
		(min_thickness 0.25)
		(keepout
			(tracks allowed)
			(vias allowed)
			(pads allowed)
			(copperpour allowed)
			(footprints allowed)
		)
		(placement
			(enabled no)
			(sheetname "")
		)
		(fill
			(thermal_gap 0.5)
			(thermal_bridge_width 0.5)
			(island_removal_mode 0)
		)
		(polygon
			(pts
				(xy 435.567582 -303.81448) (xy 435.567582 -301.328074) (xy 435.254654 -301.328074) (xy 435.254654 -300.346364)
				(xy 435.409086 -300.346364) (xy 435.567582 -300.346364) (xy 436.143146 -300.346364) (xy 436.143146 -300.765718)
				(xy 436.143146 -303.81448)
			)
		)
	)
	(zone
		(layer "In6.Cu")
		(hatch none 0.5)
		(connect_pads
			(clearance 0)
		)
		(min_thickness 0.25)
		(keepout
			(tracks allowed)
			(vias allowed)
			(pads allowed)
			(copperpour allowed)
			(footprints allowed)
		)
		(placement
			(enabled no)
			(sheetname "")
		)
		(fill
			(thermal_gap 0.5)
			(thermal_bridge_width 0.5)
			(island_removal_mode 0)
		)
		(polygon
			(pts
				(xy 187.627514 -284.264608) (xy 187.627514 -282.114498) (xy 188.203078 -282.114498) (xy 188.203078 -284.264608)
			)
		)
	)
	(zone
		(layer "In6.Cu")
		(hatch none 0.5)
		(connect_pads
			(clearance 0)
		)
		(min_thickness 0.25)
		(keepout
			(tracks allowed)
			(vias allowed)
			(pads allowed)
			(copperpour allowed)
			(footprints allowed)
		)
		(placement
			(enabled no)
			(sheetname "")
		)
		(fill
			(thermal_gap 0.5)
			(thermal_bridge_width 0.5)
			(island_removal_mode 0)
		)
		(polygon
			(pts
				(xy 187.627514 -306.36464) (xy 187.627514 -305.012598) (xy 188.203078 -305.012598) (xy 188.203078 -306.36464)
			)
		)
	)
	(zone
		(layer "In6.Cu")
		(hatch none 0.5)
		(connect_pads
			(clearance 0)
		)
		(min_thickness 0.25)
		(keepout
			(tracks allowed)
			(vias allowed)
			(pads allowed)
			(copperpour allowed)
			(footprints allowed)
		)
		(placement
			(enabled no)
			(sheetname "")
		)
		(fill
			(thermal_gap 0.5)
			(thermal_bridge_width 0.5)
			(island_removal_mode 0)
		)
		(polygon
			(pts
				(xy 125.17374 -341.902288) (xy 125.17374 -339.570568) (xy 131.0767 -339.570568) (xy 131.0767 -341.902288)
			)
		)
	)
	(zone
		(layer "In6.Cu")
		(hatch none 0.5)
		(connect_pads
			(clearance 0)
		)
		(min_thickness 0.25)
		(keepout
			(tracks allowed)
			(vias allowed)
			(pads allowed)
			(copperpour allowed)
			(footprints allowed)
		)
		(placement
			(enabled no)
			(sheetname "")
		)
		(fill
			(thermal_gap 0.5)
			(thermal_bridge_width 0.5)
			(island_removal_mode 0)
		)
		(polygon
			(pts
				(xy 420.388034 -208.571338) (xy 420.388034 -205.546198) (xy 421.018208 -205.546198) (xy 421.018208 -208.571338)
			)
		)
	)
	(zone
		(layer "In6.Cu")
		(hatch none 0.5)
		(connect_pads
			(clearance 0)
		)
		(min_thickness 0.25)
		(keepout
			(tracks allowed)
			(vias allowed)
			(pads allowed)
			(copperpour allowed)
			(footprints allowed)
		)
		(placement
			(enabled no)
			(sheetname "")
		)
		(fill
			(thermal_gap 0.5)
			(thermal_bridge_width 0.5)
			(island_removal_mode 0)
		)
		(polygon
			(pts
				(xy 35.725608 -220.50629) (xy 35.725608 -219.18422) (xy 36.253166 -219.18422) (xy 36.253166 -220.50629)
			)
		)
	)
	(zone
		(layer "In6.Cu")
		(hatch none 0.5)
		(connect_pads
			(clearance 0)
		)
		(min_thickness 0.25)
		(keepout
			(tracks allowed)
			(vias allowed)
			(pads allowed)
			(copperpour allowed)
			(footprints allowed)
		)
		(placement
			(enabled no)
			(sheetname "")
		)
		(fill
			(thermal_gap 0.5)
			(thermal_bridge_width 0.5)
			(island_removal_mode 0)
		)
		(polygon
			(pts
				(xy 46.590204 -305.564794) (xy 46.590204 -303.297336) (xy 47.275242 -303.297336) (xy 47.275242 -305.564794)
			)
		)
	)
	(zone
		(layer "In6.Cu")
		(hatch none 0.5)
		(connect_pads
			(clearance 0)
		)
		(min_thickness 0.25)
		(keepout
			(tracks allowed)
			(vias allowed)
			(pads allowed)
			(copperpour allowed)
			(footprints allowed)
		)
		(placement
			(enabled no)
			(sheetname "")
		)
		(fill
			(thermal_gap 0.5)
			(thermal_bridge_width 0.5)
			(island_removal_mode 0)
		)
		(polygon
			(pts
				(xy 409.49245 -224.7646) (xy 409.49245 -223.412558) (xy 410.068014 -223.412558) (xy 410.068014 -224.7646)
			)
		)
	)
	(zone
		(layer "In6.Cu")
		(hatch none 0.5)
		(connect_pads
			(clearance 0)
		)
		(min_thickness 0.25)
		(keepout
			(tracks allowed)
			(vias allowed)
			(pads allowed)
			(copperpour allowed)
			(footprints allowed)
		)
		(placement
			(enabled no)
			(sheetname "")
		)
		(fill
			(thermal_gap 0.5)
			(thermal_bridge_width 0.5)
			(island_removal_mode 0)
		)
		(polygon
			(pts
				(xy 172.539914 -314.864496) (xy 172.539914 -312.680858) (xy 173.115478 -312.680858) (xy 173.115478 -314.864496)
			)
		)
	)
	(zone
		(layer "In6.Cu")
		(hatch none 0.5)
		(connect_pads
			(clearance 0)
		)
		(min_thickness 0.25)
		(keepout
			(tracks allowed)
			(vias allowed)
			(pads allowed)
			(copperpour allowed)
			(footprints allowed)
		)
		(placement
			(enabled no)
			(sheetname "")
		)
		(fill
			(thermal_gap 0.5)
			(thermal_bridge_width 0.5)
			(island_removal_mode 0)
		)
		(polygon
			(pts
				(xy 405.392382 -225.614484) (xy 405.392382 -224.262442) (xy 405.967946 -224.262442) (xy 405.967946 -225.614484)
			)
		)
	)
	(zone
		(layer "In6.Cu")
		(hatch none 0.5)
		(connect_pads
			(clearance 0)
		)
		(min_thickness 0.25)
		(keepout
			(tracks allowed)
			(vias allowed)
			(pads allowed)
			(copperpour allowed)
			(footprints allowed)
		)
		(placement
			(enabled no)
			(sheetname "")
		)
		(fill
			(thermal_gap 0.5)
			(thermal_bridge_width 0.5)
			(island_removal_mode 0)
		)
		(polygon
			(pts
				(xy 283.665676 -227.306378) (xy 283.665676 -225.984308) (xy 284.193234 -225.984308) (xy 284.193234 -227.306378)
			)
		)
	)
	(zone
		(layer "In6.Cu")
		(hatch none 0.5)
		(connect_pads
			(clearance 0)
		)
		(min_thickness 0.25)
		(keepout
			(tracks allowed)
			(vias allowed)
			(pads allowed)
			(copperpour allowed)
			(footprints allowed)
		)
		(placement
			(enabled no)
			(sheetname "")
		)
		(fill
			(thermal_gap 0.5)
			(thermal_bridge_width 0.5)
			(island_removal_mode 0)
		)
		(polygon
			(pts
				(xy 359.691432 -359.024428) (xy 359.691432 -353.810062) (xy 362.814362 -353.810062) (xy 362.814362 -359.024428)
			)
		)
	)
	(zone
		(layer "In6.Cu")
		(hatch none 0.5)
		(connect_pads
			(clearance 0)
		)
		(min_thickness 0.25)
		(keepout
			(tracks allowed)
			(vias allowed)
			(pads allowed)
			(copperpour allowed)
			(footprints allowed)
		)
		(placement
			(enabled no)
			(sheetname "")
		)
		(fill
			(thermal_gap 0.5)
			(thermal_bridge_width 0.5)
			(island_removal_mode 0)
		)
		(polygon
			(pts
				(xy 283.665676 -219.656406) (xy 283.665676 -218.334336) (xy 284.193234 -218.334336) (xy 284.193234 -219.656406)
			)
		)
	)
	(zone
		(layer "In6.Cu")
		(hatch none 0.5)
		(connect_pads
			(clearance 0)
		)
		(min_thickness 0.25)
		(keepout
			(tracks allowed)
			(vias allowed)
			(pads allowed)
			(copperpour allowed)
			(footprints allowed)
		)
		(placement
			(enabled no)
			(sheetname "")
		)
		(fill
			(thermal_gap 0.5)
			(thermal_bridge_width 0.5)
			(island_removal_mode 0)
		)
		(polygon
			(pts
				(xy 61.636656 -233.257852) (xy 61.636656 -224.188274) (xy 62.376558 -224.188274) (xy 62.376558 -233.257852)
			)
		)
	)
	(zone
		(layer "In6.Cu")
		(hatch none 0.5)
		(connect_pads
			(clearance 0)
		)
		(min_thickness 0.25)
		(keepout
			(tracks allowed)
			(vias allowed)
			(pads allowed)
			(copperpour allowed)
			(footprints allowed)
		)
		(placement
			(enabled no)
			(sheetname "")
		)
		(fill
			(thermal_gap 0.5)
			(thermal_bridge_width 0.5)
			(island_removal_mode 0)
		)
		(polygon
			(pts
				(xy 35.602672 -284.3149) (xy 35.602672 -282.047442) (xy 36.28771 -282.047442) (xy 36.28771 -284.3149)
			)
		)
	)
	(zone
		(layer "In6.Cu")
		(hatch none 0.5)
		(connect_pads
			(clearance 0)
		)
		(min_thickness 0.25)
		(keepout
			(tracks allowed)
			(vias allowed)
			(pads allowed)
			(copperpour allowed)
			(footprints allowed)
		)
		(placement
			(enabled no)
			(sheetname "")
		)
		(fill
			(thermal_gap 0.5)
			(thermal_bridge_width 0.5)
			(island_removal_mode 0)
		)
		(polygon
			(pts
				(xy 35.725608 -249.40641) (xy 35.725608 -248.08434) (xy 36.253166 -248.08434) (xy 36.253166 -249.40641)
			)
		)
	)
	(zone
		(layer "In6.Cu")
		(hatch none 0.5)
		(connect_pads
			(clearance 0)
		)
		(min_thickness 0.25)
		(keepout
			(tracks allowed)
			(vias allowed)
			(pads allowed)
			(copperpour allowed)
			(footprints allowed)
		)
		(placement
			(enabled no)
			(sheetname "")
		)
		(fill
			(thermal_gap 0.5)
			(thermal_bridge_width 0.5)
			(island_removal_mode 0)
		)
		(polygon
			(pts
				(xy 187.652914 -232.404158) (xy 187.652914 -230.212392) (xy 188.228478 -230.212392) (xy 188.228478 -232.404158)
			)
		)
	)
	(zone
		(layer "In6.Cu")
		(hatch none 0.5)
		(connect_pads
			(clearance 0)
		)
		(min_thickness 0.25)
		(keepout
			(tracks allowed)
			(vias allowed)
			(pads allowed)
			(copperpour allowed)
			(footprints allowed)
		)
		(placement
			(enabled no)
			(sheetname "")
		)
		(fill
			(thermal_gap 0.5)
			(thermal_bridge_width 0.5)
			(island_removal_mode 0)
		)
		(polygon
			(pts
				(xy 450.680582 -205.394306) (xy 450.680582 -203.862432) (xy 451.256146 -203.862432) (xy 451.256146 -205.394306)
				(xy 451.256146 -206.844138) (xy 450.680582 -206.844138)
			)
		)
	)
	(zone
		(layer "In6.Cu")
		(hatch none 0.5)
		(connect_pads
			(clearance 0)
		)
		(min_thickness 0.25)
		(keepout
			(tracks allowed)
			(vias allowed)
			(pads allowed)
			(copperpour allowed)
			(footprints allowed)
		)
		(placement
			(enabled no)
			(sheetname "")
		)
		(fill
			(thermal_gap 0.5)
			(thermal_bridge_width 0.5)
			(island_removal_mode 0)
		)
		(polygon
			(pts
				(xy 43.172126 -245.178326) (xy 43.172126 -243.781072) (xy 43.857164 -243.781072) (xy 43.857164 -245.178326)
			)
		)
	)
	(zone
		(layer "In6.Cu")
		(hatch none 0.5)
		(connect_pads
			(clearance 0)
		)
		(min_thickness 0.25)
		(keepout
			(tracks allowed)
			(vias allowed)
			(pads allowed)
			(copperpour allowed)
			(footprints allowed)
		)
		(placement
			(enabled no)
			(sheetname "")
		)
		(fill
			(thermal_gap 0.5)
			(thermal_bridge_width 0.5)
			(island_removal_mode 0)
		)
		(polygon
			(pts
				(xy 176.548034 -212.947758) (xy 176.548034 -208.946242) (xy 177.178208 -208.946242) (xy 177.178208 -212.947758)
			)
		)
	)
	(zone
		(layer "In6.Cu")
		(hatch none 0.5)
		(connect_pads
			(clearance 0)
		)
		(min_thickness 0.25)
		(keepout
			(tracks allowed)
			(vias allowed)
			(pads allowed)
			(copperpour allowed)
			(footprints allowed)
		)
		(placement
			(enabled no)
			(sheetname "")
		)
		(fill
			(thermal_gap 0.5)
			(thermal_bridge_width 0.5)
			(island_removal_mode 0)
		)
		(polygon
			(pts
				(xy 313.82589 -306.790852) (xy 313.82589 -305.482244) (xy 314.360306 -305.482244) (xy 314.360306 -306.790852)
			)
		)
	)
	(zone
		(layer "In6.Cu")
		(hatch none 0.5)
		(connect_pads
			(clearance 0)
		)
		(min_thickness 0.25)
		(keepout
			(tracks allowed)
			(vias allowed)
			(pads allowed)
			(copperpour allowed)
			(footprints allowed)
		)
		(placement
			(enabled no)
			(sheetname "")
		)
		(fill
			(thermal_gap 0.5)
			(thermal_bridge_width 0.5)
			(island_removal_mode 0)
		)
		(polygon
			(pts
				(xy 116.05006 -354.922328) (xy 116.05006 -353.339908) (xy 117.84584 -353.339908) (xy 117.84584 -354.922328)
			)
		)
	)
	(zone
		(layer "In6.Cu")
		(hatch none 0.5)
		(connect_pads
			(clearance 0)
		)
		(min_thickness 0.25)
		(keepout
			(tracks allowed)
			(vias allowed)
			(pads allowed)
			(copperpour allowed)
			(footprints allowed)
		)
		(placement
			(enabled no)
			(sheetname "")
		)
		(fill
			(thermal_gap 0.5)
			(thermal_bridge_width 0.5)
			(island_removal_mode 0)
		)
		(polygon
			(pts
				(xy 450.680582 -250.254262) (xy 450.680582 -248.062496) (xy 451.256146 -248.062496) (xy 451.256146 -250.254262)
			)
		)
	)
	(zone
		(layer "In6.Cu")
		(hatch none 0.5)
		(connect_pads
			(clearance 0)
		)
		(min_thickness 0.25)
		(keepout
			(tracks allowed)
			(vias allowed)
			(pads allowed)
			(copperpour allowed)
			(footprints allowed)
		)
		(placement
			(enabled no)
			(sheetname "")
		)
		(fill
			(thermal_gap 0.5)
			(thermal_bridge_width 0.5)
			(island_removal_mode 0)
		)
		(polygon
			(pts
				(xy 20.638008 -246.006366) (xy 20.638008 -244.684296) (xy 21.165566 -244.684296) (xy 21.165566 -246.006366)
			)
		)
	)
	(zone
		(layer "In6.Cu")
		(hatch none 0.5)
		(connect_pads
			(clearance 0)
		)
		(min_thickness 0.25)
		(keepout
			(tracks allowed)
			(vias allowed)
			(pads allowed)
			(copperpour allowed)
			(footprints allowed)
		)
		(placement
			(enabled no)
			(sheetname "")
		)
		(fill
			(thermal_gap 0.5)
			(thermal_bridge_width 0.5)
			(island_removal_mode 0)
		)
		(polygon
			(pts
				(xy 46.71314 -246.85625) (xy 46.71314 -245.53418) (xy 47.240698 -245.53418) (xy 47.240698 -246.85625)
			)
		)
	)
	(zone
		(layer "In6.Cu")
		(hatch none 0.5)
		(connect_pads
			(clearance 0)
		)
		(min_thickness 0.25)
		(keepout
			(tracks allowed)
			(vias allowed)
			(pads allowed)
			(copperpour allowed)
			(footprints allowed)
		)
		(placement
			(enabled no)
			(sheetname "")
		)
		(fill
			(thermal_gap 0.5)
			(thermal_bridge_width 0.5)
			(island_removal_mode 0)
		)
		(polygon
			(pts
				(xy 309.77459 -307.570632) (xy 309.77459 -306.262024) (xy 310.309006 -306.262024) (xy 310.309006 -307.570632)
			)
		)
	)
	(zone
		(layer "In6.Cu")
		(hatch none 0.5)
		(connect_pads
			(clearance 0)
		)
		(min_thickness 0.25)
		(keepout
			(tracks allowed)
			(vias allowed)
			(pads allowed)
			(copperpour allowed)
			(footprints allowed)
		)
		(placement
			(enabled no)
			(sheetname "")
		)
		(fill
			(thermal_gap 0.5)
			(thermal_bridge_width 0.5)
			(island_removal_mode 0)
		)
		(polygon
			(pts
				(xy 283.665676 -217.956384) (xy 283.665676 -216.634314) (xy 284.193234 -216.634314) (xy 284.193234 -217.956384)
			)
		)
	)
	(zone
		(layer "In6.Cu")
		(hatch none 0.5)
		(connect_pads
			(clearance 0)
		)
		(min_thickness 0.25)
		(keepout
			(tracks allowed)
			(vias allowed)
			(pads allowed)
			(copperpour allowed)
			(footprints allowed)
		)
		(placement
			(enabled no)
			(sheetname "")
		)
		(fill
			(thermal_gap 0.5)
			(thermal_bridge_width 0.5)
			(island_removal_mode 0)
		)
		(polygon
			(pts
				(xy 83.634326 -290.514024) (xy 83.634072 -284.48635) (xy 84.070698 -284.049724) (xy 84.070698 -283.794454)
				(xy 83.797902 -283.521658) (xy 83.797902 -283.414216) (xy 84.006944 -283.205174) (xy 84.006944 -282.684474)
				(xy 84.417408 -282.27401) (xy 84.417408 -281.323034) (xy 84.356702 -281.262328) (xy 84.03336 -281.262328)
				(xy 83.892898 -281.121866) (xy 83.892898 -280.505916) (xy 83.836002 -280.44902) (xy 83.440778 -280.44902)
				(xy 83.337908 -280.34615) (xy 83.337908 -278.833326) (xy 83.197192 -278.69261) (xy 83.197192 -277.597108)
				(xy 83.30184 -277.49246) (xy 83.30184 -276.581108) (xy 83.197192 -276.47646) (xy 83.197192 -269.988792)
				(xy 83.164934 -269.956534) (xy 83.014566 -269.956534) (xy 82.92719 -269.869158) (xy 82.92719 -264.497312)
				(xy 82.474816 -264.044938) (xy 82.474816 -260.144514) (xy 82.57667 -260.04266) (xy 82.970878 -260.04266)
				(xy 82.970878 -258.112514) (xy 83.037426 -258.045966) (xy 84.08416 -258.045966) (xy 84.08416 -257.747008)
				(xy 98.83775 -257.746754) (xy 99.16795 -257.416554) (xy 99.16795 -257.060954) (xy 99.70135 -256.527554)
				(xy 99.70135 -256.197354) (xy 99.77755 -256.121154) (xy 99.92995 -256.121154) (xy 100.10775 -255.943354)
				(xy 100.10775 -255.511554) (xy 100.61575 -255.003554) (xy 100.61575 -254.622554) (xy 100.79355 -254.444754)
				(xy 101.27615 -254.444754) (xy 101.65715 -254.063754) (xy 101.65715 -253.758954) (xy 101.55555 -253.657354)
				(xy 101.12375 -253.657354) (xy 100.33635 -254.444754) (xy 100.33635 -254.825754) (xy 100.23475 -254.927354)
				(xy 100.20935 -254.927354) (xy 99.85375 -255.282954) (xy 99.85375 -255.638554) (xy 99.77755 -255.714754)
				(xy 99.75215 -255.714754) (xy 99.34575 -256.121154) (xy 99.34575 -256.476754) (xy 98.93935 -256.883154)
				(xy 98.93935 -257.213354) (xy 98.73615 -257.416554) (xy 84.76615 -257.416808) (xy 84.74075 -257.442208)
				(xy 83.088734 -257.442208) (xy 83.04276 -257.442208) (xy 82.977482 -257.442208) (xy 82.898996 -257.363722)
				(xy 82.898996 -255.051814) (xy 83.057238 -254.893572) (xy 84.283296 -254.893572) (xy 84.332064 -254.844804)
				(xy 84.332064 -252.645164) (xy 84.405724 -252.571504) (xy 84.819998 -252.571504) (xy 86.866476 -252.571504)
				(xy 87.076534 -252.781562) (xy 100.462334 -252.781308) (xy 100.462334 -250.368308) (xy 83.520534 -250.368562)
				(xy 83.319112 -250.16714) (xy 83.319112 -246.873268) (xy 83.288378 -246.842534) (xy 83.098386 -246.842534)
				(xy 83.033616 -246.777764) (xy 83.033616 -244.804692) (xy 82.95767 -244.728746) (xy 82.95767 -238.680244)
				(xy 82.706972 -238.429546) (xy 82.706972 -234.27055) (xy 82.467196 -234.030774) (xy 82.467196 -228.210872)
				(xy 82.326734 -228.07041) (xy 82.326734 -220.626432) (xy 83.633056 -219.32011) (xy 83.632802 -212.603842)
				(xy 103.738172 -212.603588) (xy 103.739696 -290.51377)
			)
		)
	)
	(zone
		(layer "In6.Cu")
		(hatch none 0.5)
		(connect_pads
			(clearance 0)
		)
		(min_thickness 0.25)
		(keepout
			(tracks allowed)
			(vias allowed)
			(pads allowed)
			(copperpour allowed)
			(footprints allowed)
		)
		(placement
			(enabled no)
			(sheetname "")
		)
		(fill
			(thermal_gap 0.5)
			(thermal_bridge_width 0.5)
			(island_removal_mode 0)
		)
		(polygon
			(pts
				(xy 450.680582 -212.194394) (xy 450.680582 -210.66252) (xy 451.256146 -210.66252) (xy 451.256146 -212.194394)
			)
		)
	)
	(zone
		(layer "In6.Cu")
		(hatch none 0.5)
		(connect_pads
			(clearance 0)
		)
		(min_thickness 0.25)
		(keepout
			(tracks allowed)
			(vias allowed)
			(pads allowed)
			(copperpour allowed)
			(footprints allowed)
		)
		(placement
			(enabled no)
			(sheetname "")
		)
		(fill
			(thermal_gap 0.5)
			(thermal_bridge_width 0.5)
			(island_removal_mode 0)
		)
		(polygon
			(pts
				(xy 357.67772 -365.189008) (xy 357.67772 -361.871768) (xy 361.52582 -361.871768) (xy 361.52582 -365.189008)
			)
		)
	)
	(zone
		(layer "In6.Cu")
		(hatch none 0.5)
		(connect_pads
			(clearance 0)
		)
		(min_thickness 0.25)
		(keepout
			(tracks allowed)
			(vias allowed)
			(pads allowed)
			(copperpour allowed)
			(footprints allowed)
		)
		(placement
			(enabled no)
			(sheetname "")
		)
		(fill
			(thermal_gap 0.5)
			(thermal_bridge_width 0.5)
			(island_removal_mode 0)
		)
		(polygon
			(pts
				(xy 414.95218 -366.880648) (xy 414.95218 -365.577628) (xy 416.36442 -365.577628) (xy 416.36442 -366.880648)
			)
		)
	)
	(zone
		(layer "In6.Cu")
		(hatch none 0.5)
		(connect_pads
			(clearance 0)
		)
		(min_thickness 0.25)
		(keepout
			(tracks allowed)
			(vias allowed)
			(pads allowed)
			(copperpour allowed)
			(footprints allowed)
		)
		(placement
			(enabled no)
			(sheetname "")
		)
		(fill
			(thermal_gap 0.5)
			(thermal_bridge_width 0.5)
			(island_removal_mode 0)
		)
		(polygon
			(pts
				(xy 377.753626 -253.038356) (xy 377.753626 -252.517656) (xy 378.477272 -251.79401) (xy 390.725406 -251.79401)
				(xy 390.763506 -251.75591) (xy 390.887966 -251.75591) (xy 392.780266 -249.86361) (xy 395.813026 -249.86361)
				(xy 396.757906 -248.91873) (xy 396.757906 -247.69445) (xy 396.709646 -247.64619) (xy 391.398252 -247.64619)
				(xy 388.612126 -250.432316) (xy 386.705856 -250.432316) (xy 386.705856 -250.6726) (xy 386.684266 -250.69419)
				(xy 386.557266 -250.69419) (xy 377.954286 -250.69419) (xy 377.942602 -250.682506) (xy 376.736102 -250.682506)
				(xy 375.747026 -251.671836) (xy 375.747026 -253.581916) (xy 376.349006 -254.183896) (xy 376.555762 -254.183896)
				(xy 376.865134 -253.874524) (xy 376.865134 -253.58852) (xy 376.779536 -253.502922) (xy 376.779536 -253.119128)
				(xy 376.860308 -253.038356)
			)
		)
	)
	(zone
		(layer "In6.Cu")
		(hatch none 0.5)
		(connect_pads
			(clearance 0)
		)
		(min_thickness 0.25)
		(keepout
			(tracks allowed)
			(vias allowed)
			(pads allowed)
			(copperpour allowed)
			(footprints allowed)
		)
		(placement
			(enabled no)
			(sheetname "")
		)
		(fill
			(thermal_gap 0.5)
			(thermal_bridge_width 0.5)
			(island_removal_mode 0)
		)
		(polygon
			(pts
				(xy 298.753276 -214.55634) (xy 298.753276 -213.23427) (xy 298.753276 -204.351128) (xy 298.558458 -204.351128)
				(xy 298.558458 -202.991212) (xy 298.753276 -202.991212) (xy 299.280834 -202.991212) (xy 299.280834 -213.23427)
				(xy 299.280834 -214.55634)
			)
		)
	)
	(zone
		(layer "In6.Cu")
		(hatch none 0.5)
		(connect_pads
			(clearance 0)
		)
		(min_thickness 0.25)
		(keepout
			(tracks allowed)
			(vias allowed)
			(pads allowed)
			(copperpour allowed)
			(footprints allowed)
		)
		(placement
			(enabled no)
			(sheetname "")
		)
		(fill
			(thermal_gap 0.5)
			(thermal_bridge_width 0.5)
			(island_removal_mode 0)
		)
		(polygon
			(pts
				(xy 176.639982 -216.26449) (xy 176.639982 -214.912448) (xy 177.215546 -214.912448) (xy 177.215546 -216.26449)
			)
		)
	)
	(zone
		(layer "In6.Cu")
		(hatch none 0.5)
		(connect_pads
			(clearance 0)
		)
		(min_thickness 0.25)
		(keepout
			(tracks allowed)
			(vias allowed)
			(pads allowed)
			(copperpour allowed)
			(footprints allowed)
		)
		(placement
			(enabled no)
			(sheetname "")
		)
		(fill
			(thermal_gap 0.5)
			(thermal_bridge_width 0.5)
			(island_removal_mode 0)
		)
		(polygon
			(pts
				(xy 256.934208 -246.006366) (xy 256.934208 -244.684296) (xy 257.461766 -244.684296) (xy 257.461766 -246.006366)
			)
		)
	)
	(zone
		(layer "In6.Cu")
		(hatch none 0.5)
		(connect_pads
			(clearance 0)
		)
		(min_thickness 0.25)
		(keepout
			(tracks allowed)
			(vias allowed)
			(pads allowed)
			(copperpour allowed)
			(footprints allowed)
		)
		(placement
			(enabled no)
			(sheetname "")
		)
		(fill
			(thermal_gap 0.5)
			(thermal_bridge_width 0.5)
			(island_removal_mode 0)
		)
		(polygon
			(pts
				(xy 43.182286 -243.382546) (xy 43.182286 -241.272568) (xy 43.88104 -241.272568) (xy 43.88104 -243.382546)
			)
		)
	)
	(zone
		(layer "In6.Cu")
		(hatch none 0.5)
		(connect_pads
			(clearance 0)
		)
		(min_thickness 0.25)
		(keepout
			(tracks allowed)
			(vias allowed)
			(pads allowed)
			(copperpour allowed)
			(footprints allowed)
		)
		(placement
			(enabled no)
			(sheetname "")
		)
		(fill
			(thermal_gap 0.5)
			(thermal_bridge_width 0.5)
			(island_removal_mode 0)
		)
		(polygon
			(pts
				(xy 264.478008 -245.156228) (xy 264.478008 -243.834158) (xy 265.005566 -243.834158) (xy 265.005566 -245.156228)
			)
		)
	)
	(zone
		(layer "In6.Cu")
		(hatch none 0.5)
		(connect_pads
			(clearance 0)
		)
		(min_thickness 0.25)
		(keepout
			(tracks allowed)
			(vias allowed)
			(pads allowed)
			(copperpour allowed)
			(footprints allowed)
		)
		(placement
			(enabled no)
			(sheetname "")
		)
		(fill
			(thermal_gap 0.5)
			(thermal_bridge_width 0.5)
			(island_removal_mode 0)
		)
		(polygon
			(pts
				(xy 298.65574 -302.165004) (xy 298.65574 -299.897546) (xy 299.340778 -299.897546) (xy 299.340778 -302.165004)
				(xy 299.340778 -308.849522) (xy 299.340778 -311.390792) (xy 298.65574 -311.390792) (xy 298.65574 -308.849522)
			)
		)
	)
	(zone
		(layer "In6.Cu")
		(hatch none 0.5)
		(connect_pads
			(clearance 0)
		)
		(min_thickness 0.25)
		(keepout
			(tracks allowed)
			(vias allowed)
			(pads allowed)
			(copperpour allowed)
			(footprints allowed)
		)
		(placement
			(enabled no)
			(sheetname "")
		)
		(fill
			(thermal_gap 0.5)
			(thermal_bridge_width 0.5)
			(island_removal_mode 0)
		)
		(polygon
			(pts
				(xy 439.69305 -214.7443) (xy 439.69305 -213.212426) (xy 440.268614 -213.212426) (xy 440.268614 -214.7443)
			)
		)
	)
	(zone
		(layer "In6.Cu")
		(hatch none 0.5)
		(connect_pads
			(clearance 0)
		)
		(min_thickness 0.25)
		(keepout
			(tracks allowed)
			(vias allowed)
			(pads allowed)
			(copperpour allowed)
			(footprints allowed)
		)
		(placement
			(enabled no)
			(sheetname "")
		)
		(fill
			(thermal_gap 0.5)
			(thermal_bridge_width 0.5)
			(island_removal_mode 0)
		)
		(polygon
			(pts
				(xy 435.567582 -278.314658) (xy 435.567582 -276.962616) (xy 436.143146 -276.962616) (xy 436.143146 -278.314658)
			)
		)
	)
	(zone
		(layer "In6.Cu")
		(hatch none 0.5)
		(connect_pads
			(clearance 0)
		)
		(min_thickness 0.25)
		(keepout
			(tracks allowed)
			(vias allowed)
			(pads allowed)
			(copperpour allowed)
			(footprints allowed)
		)
		(placement
			(enabled no)
			(sheetname "")
		)
		(fill
			(thermal_gap 0.5)
			(thermal_bridge_width 0.5)
			(island_removal_mode 0)
		)
		(polygon
			(pts
				(xy 331.3684 -41.504108) (xy 331.3684 -39.413688) (xy 334.20812 -39.413688) (xy 334.20812 -41.504108)
			)
		)
	)
	(zone
		(layer "In6.Cu")
		(hatch none 0.5)
		(connect_pads
			(clearance 0)
		)
		(min_thickness 0.25)
		(keepout
			(tracks allowed)
			(vias allowed)
			(pads allowed)
			(copperpour allowed)
			(footprints allowed)
		)
		(placement
			(enabled no)
			(sheetname "")
		)
		(fill
			(thermal_gap 0.5)
			(thermal_bridge_width 0.5)
			(island_removal_mode 0)
		)
		(polygon
			(pts
				(xy 424.488102 -212.947758) (xy 424.488102 -208.946242) (xy 425.118276 -208.946242) (xy 425.118276 -212.947758)
			)
		)
	)
	(zone
		(layer "In6.Cu")
		(hatch none 0.5)
		(connect_pads
			(clearance 0)
		)
		(min_thickness 0.25)
		(keepout
			(tracks allowed)
			(vias allowed)
			(pads allowed)
			(copperpour allowed)
			(footprints allowed)
		)
		(placement
			(enabled no)
			(sheetname "")
		)
		(fill
			(thermal_gap 0.5)
			(thermal_bridge_width 0.5)
			(island_removal_mode 0)
		)
		(polygon
			(pts
				(xy 351.89414 -352.219768) (xy 351.89414 -351.307908) (xy 353.57816 -351.307908) (xy 353.57816 -352.219768)
			)
		)
	)
	(zone
		(layer "In6.Cu")
		(hatch none 0.5)
		(connect_pads
			(clearance 0)
		)
		(min_thickness 0.25)
		(keepout
			(tracks allowed)
			(vias allowed)
			(pads allowed)
			(copperpour allowed)
			(footprints allowed)
		)
		(placement
			(enabled no)
			(sheetname "")
		)
		(fill
			(thermal_gap 0.5)
			(thermal_bridge_width 0.5)
			(island_removal_mode 0)
		)
		(polygon
			(pts
				(xy 275.942044 -243.464842) (xy 275.942044 -241.272568) (xy 276.72284 -241.272568) (xy 276.72284 -243.464842)
			)
		)
	)
	(zone
		(layer "In6.Cu")
		(hatch none 0.5)
		(connect_pads
			(clearance 0)
		)
		(min_thickness 0.25)
		(keepout
			(tracks allowed)
			(vias allowed)
			(pads allowed)
			(copperpour allowed)
			(footprints allowed)
		)
		(placement
			(enabled no)
			(sheetname "")
		)
		(fill
			(thermal_gap 0.5)
			(thermal_bridge_width 0.5)
			(island_removal_mode 0)
		)
		(polygon
			(pts
				(xy 187.535566 -197.552564) (xy 187.535566 -196.196204) (xy 188.16574 -196.196204) (xy 188.16574 -197.552564)
			)
		)
	)
	(zone
		(layer "In6.Cu")
		(hatch none 0.5)
		(connect_pads
			(clearance 0)
		)
		(min_thickness 0.25)
		(keepout
			(tracks allowed)
			(vias allowed)
			(pads allowed)
			(copperpour allowed)
			(footprints allowed)
		)
		(placement
			(enabled no)
			(sheetname "")
		)
		(fill
			(thermal_gap 0.5)
			(thermal_bridge_width 0.5)
			(island_removal_mode 0)
		)
		(polygon
			(pts
				(xy 35.725608 -217.956384) (xy 35.725608 -216.634314) (xy 36.253166 -216.634314) (xy 36.253166 -217.956384)
			)
		)
	)
	(zone
		(layer "In6.Cu")
		(hatch none 0.5)
		(connect_pads
			(clearance 0)
		)
		(min_thickness 0.25)
		(keepout
			(tracks allowed)
			(vias allowed)
			(pads allowed)
			(copperpour allowed)
			(footprints allowed)
		)
		(placement
			(enabled no)
			(sheetname "")
		)
		(fill
			(thermal_gap 0.5)
			(thermal_bridge_width 0.5)
			(island_removal_mode 0)
		)
		(polygon
			(pts
				(xy 50.715672 -302.165004) (xy 50.715672 -299.897546) (xy 51.40071 -299.897546) (xy 51.40071 -302.165004)
				(xy 51.40071 -308.849522) (xy 51.40071 -311.390792) (xy 50.715672 -311.390792) (xy 50.715672 -308.849522)
			)
		)
	)
	(zone
		(layer "In6.Cu")
		(hatch none 0.5)
		(connect_pads
			(clearance 0)
		)
		(min_thickness 0.25)
		(keepout
			(tracks allowed)
			(vias allowed)
			(pads allowed)
			(copperpour allowed)
			(footprints allowed)
		)
		(placement
			(enabled no)
			(sheetname "")
		)
		(fill
			(thermal_gap 0.5)
			(thermal_bridge_width 0.5)
			(island_removal_mode 0)
		)
		(polygon
			(pts
				(xy 40.23614 -358.488488) (xy 40.23614 -357.076248) (xy 42.37482 -357.076248) (xy 42.37482 -358.488488)
			)
		)
	)
	(zone
		(layer "In6.Cu")
		(hatch none 0.5)
		(connect_pads
			(clearance 0)
		)
		(min_thickness 0.25)
		(keepout
			(tracks allowed)
			(vias allowed)
			(pads allowed)
			(copperpour allowed)
			(footprints allowed)
		)
		(placement
			(enabled no)
			(sheetname "")
		)
		(fill
			(thermal_gap 0.5)
			(thermal_bridge_width 0.5)
			(island_removal_mode 0)
		)
		(polygon
			(pts
				(xy 35.725608 -225.606356) (xy 35.725608 -224.284286) (xy 36.253166 -224.284286) (xy 36.253166 -225.606356)
			)
		)
	)
	(zone
		(layer "In6.Cu")
		(hatch none 0.5)
		(connect_pads
			(clearance 0)
		)
		(min_thickness 0.25)
		(keepout
			(tracks allowed)
			(vias allowed)
			(pads allowed)
			(copperpour allowed)
			(footprints allowed)
		)
		(placement
			(enabled no)
			(sheetname "")
		)
		(fill
			(thermal_gap 0.5)
			(thermal_bridge_width 0.5)
			(island_removal_mode 0)
		)
		(polygon
			(pts
				(xy 170.7515 -358.201468) (xy 170.7515 -357.010208) (xy 172.44822 -357.010208) (xy 172.44822 -358.201468)
			)
		)
	)
	(zone
		(layer "In6.Cu")
		(hatch none 0.5)
		(connect_pads
			(clearance 0)
		)
		(min_thickness 0.25)
		(keepout
			(tracks allowed)
			(vias allowed)
			(pads allowed)
			(copperpour allowed)
			(footprints allowed)
		)
		(placement
			(enabled no)
			(sheetname "")
		)
		(fill
			(thermal_gap 0.5)
			(thermal_bridge_width 0.5)
			(island_removal_mode 0)
		)
		(polygon
			(pts
				(xy 450.655182 -316.564518) (xy 450.655182 -314.364878) (xy 451.230746 -314.364878) (xy 451.230746 -316.564518)
			)
		)
	)
	(zone
		(layer "In6.Cu")
		(hatch none 0.5)
		(connect_pads
			(clearance 0)
		)
		(min_thickness 0.25)
		(keepout
			(tracks allowed)
			(vias allowed)
			(pads allowed)
			(copperpour allowed)
			(footprints allowed)
		)
		(placement
			(enabled no)
			(sheetname "")
		)
		(fill
			(thermal_gap 0.5)
			(thermal_bridge_width 0.5)
			(island_removal_mode 0)
		)
		(polygon
			(pts
				(xy 268.578076 -314.00623) (xy 268.578076 -312.68416) (xy 269.105634 -312.68416) (xy 269.105634 -314.00623)
			)
		)
	)
	(zone
		(layer "In6.Cu")
		(hatch none 0.5)
		(connect_pads
			(clearance 0)
		)
		(min_thickness 0.25)
		(keepout
			(tracks allowed)
			(vias allowed)
			(pads allowed)
			(copperpour allowed)
			(footprints allowed)
		)
		(placement
			(enabled no)
			(sheetname "")
		)
		(fill
			(thermal_gap 0.5)
			(thermal_bridge_width 0.5)
			(island_removal_mode 0)
		)
		(polygon
			(pts
				(xy 20.638008 -308.906418) (xy 20.638008 -307.584348) (xy 21.165566 -307.584348) (xy 21.165566 -308.906418)
			)
		)
	)
	(zone
		(layer "In6.Cu")
		(hatch none 0.5)
		(connect_pads
			(clearance 0)
		)
		(min_thickness 0.25)
		(keepout
			(tracks allowed)
			(vias allowed)
			(pads allowed)
			(copperpour allowed)
			(footprints allowed)
		)
		(placement
			(enabled no)
			(sheetname "")
		)
		(fill
			(thermal_gap 0.5)
			(thermal_bridge_width 0.5)
			(island_removal_mode 0)
		)
		(polygon
			(pts
				(xy 381.50038 -347.739208) (xy 381.50038 -343.827608) (xy 386.82676 -343.827608) (xy 386.82676 -347.739208)
			)
		)
	)
	(zone
		(layer "In6.Cu")
		(hatch none 0.5)
		(connect_pads
			(clearance 0)
		)
		(min_thickness 0.25)
		(keepout
			(tracks allowed)
			(vias allowed)
			(pads allowed)
			(copperpour allowed)
			(footprints allowed)
		)
		(placement
			(enabled no)
			(sheetname "")
		)
		(fill
			(thermal_gap 0.5)
			(thermal_bridge_width 0.5)
			(island_removal_mode 0)
		)
		(polygon
			(pts
				(xy 353.55276 -297.655488) (xy 353.55276 -292.186868) (xy 356.18166 -292.186868) (xy 356.18166 -297.655488)
			)
		)
	)
	(zone
		(layer "In6.Cu")
		(hatch none 0.5)
		(connect_pads
			(clearance 0)
		)
		(min_thickness 0.25)
		(keepout
			(tracks allowed)
			(vias allowed)
			(pads allowed)
			(copperpour allowed)
			(footprints allowed)
		)
		(placement
			(enabled no)
			(sheetname "")
		)
		(fill
			(thermal_gap 0.5)
			(thermal_bridge_width 0.5)
			(island_removal_mode 0)
		)
		(polygon
			(pts
				(xy 294.530272 -308.114954) (xy 294.530272 -305.847496) (xy 295.21531 -305.847496) (xy 295.21531 -308.114954)
				(xy 295.21531 -314.799472) (xy 294.530272 -314.799472)
			)
		)
	)
	(zone
		(layer "In6.Cu")
		(hatch none 0.5)
		(connect_pads
			(clearance 0)
		)
		(min_thickness 0.25)
		(keepout
			(tracks allowed)
			(vias allowed)
			(pads allowed)
			(copperpour allowed)
			(footprints allowed)
		)
		(placement
			(enabled no)
			(sheetname "")
		)
		(fill
			(thermal_gap 0.5)
			(thermal_bridge_width 0.5)
			(island_removal_mode 0)
		)
		(polygon
			(pts
				(xy 35.725608 -229.0064) (xy 35.725608 -227.68433) (xy 36.253166 -227.68433) (xy 36.253166 -229.0064)
			)
		)
	)
	(zone
		(layer "In6.Cu")
		(hatch none 0.5)
		(connect_pads
			(clearance 0)
		)
		(min_thickness 0.25)
		(keepout
			(tracks allowed)
			(vias allowed)
			(pads allowed)
			(copperpour allowed)
			(footprints allowed)
		)
		(placement
			(enabled no)
			(sheetname "")
		)
		(fill
			(thermal_gap 0.5)
			(thermal_bridge_width 0.5)
			(island_removal_mode 0)
		)
		(polygon
			(pts
				(xy 283.665676 -222.206312) (xy 283.665676 -220.884242) (xy 284.193234 -220.884242) (xy 284.193234 -222.206312)
			)
		)
	)
	(zone
		(layer "In6.Cu")
		(hatch none 0.5)
		(connect_pads
			(clearance 0)
		)
		(min_thickness 0.25)
		(keepout
			(tracks allowed)
			(vias allowed)
			(pads allowed)
			(copperpour allowed)
			(footprints allowed)
		)
		(placement
			(enabled no)
			(sheetname "")
		)
		(fill
			(thermal_gap 0.5)
			(thermal_bridge_width 0.5)
			(island_removal_mode 0)
		)
		(polygon
			(pts
				(xy 133.35254 -347.894148) (xy 133.35254 -345.349068) (xy 138.71448 -345.349068) (xy 138.71448 -347.894148)
			)
		)
	)
	(zone
		(layer "In6.Cu")
		(hatch none 0.5)
		(connect_pads
			(clearance 0)
		)
		(min_thickness 0.25)
		(keepout
			(tracks allowed)
			(vias allowed)
			(pads allowed)
			(copperpour allowed)
			(footprints allowed)
		)
		(placement
			(enabled no)
			(sheetname "")
		)
		(fill
			(thermal_gap 0.5)
			(thermal_bridge_width 0.5)
			(island_removal_mode 0)
		)
		(polygon
			(pts
				(xy 424.58005 -314.014612) (xy 424.58005 -311.802018) (xy 425.155614 -311.802018) (xy 425.155614 -314.014612)
			)
		)
	)
	(zone
		(layer "In6.Cu")
		(hatch none 0.5)
		(connect_pads
			(clearance 0)
		)
		(min_thickness 0.25)
		(keepout
			(tracks allowed)
			(vias allowed)
			(pads allowed)
			(copperpour allowed)
			(footprints allowed)
		)
		(placement
			(enabled no)
			(sheetname "")
		)
		(fill
			(thermal_gap 0.5)
			(thermal_bridge_width 0.5)
			(island_removal_mode 0)
		)
		(polygon
			(pts
				(xy 130.25374 -20.62734) (xy 130.25374 -17.21358) (xy 129.20726 -17.21358) (xy 129.20726 -20.62734)
			)
		)
	)
	(zone
		(layer "In6.Cu")
		(hatch none 0.5)
		(connect_pads
			(clearance 0)
		)
		(min_thickness 0.25)
		(keepout
			(tracks allowed)
			(vias allowed)
			(pads allowed)
			(copperpour allowed)
			(footprints allowed)
		)
		(placement
			(enabled no)
			(sheetname "")
		)
		(fill
			(thermal_gap 0.5)
			(thermal_bridge_width 0.5)
			(island_removal_mode 0)
		)
		(polygon
			(pts
				(xy 13.094208 -246.006366) (xy 13.094208 -244.684296) (xy 13.621766 -244.684296) (xy 13.621766 -246.006366)
			)
		)
	)
	(zone
		(layer "In6.Cu")
		(hatch none 0.5)
		(connect_pads
			(clearance 0)
		)
		(min_thickness 0.25)
		(keepout
			(tracks allowed)
			(vias allowed)
			(pads allowed)
			(copperpour allowed)
			(footprints allowed)
		)
		(placement
			(enabled no)
			(sheetname "")
		)
		(fill
			(thermal_gap 0.5)
			(thermal_bridge_width 0.5)
			(island_removal_mode 0)
		)
		(polygon
			(pts
				(xy 294.653208 -214.084154) (xy 294.653208 -204.721714) (xy 294.405558 -204.721714) (xy 294.405558 -203.494132)
				(xy 294.653208 -203.494132) (xy 295.180766 -203.494132) (xy 295.180766 -214.084154) (xy 295.180766 -215.406224)
				(xy 294.653208 -215.406224) (xy 294.521636 -215.406224) (xy 294.521636 -214.084154)
			)
		)
	)
	(zone
		(layer "In6.Cu")
		(hatch none 0.5)
		(connect_pads
			(clearance 0)
		)
		(min_thickness 0.25)
		(keepout
			(tracks allowed)
			(vias allowed)
			(pads allowed)
			(copperpour allowed)
			(footprints allowed)
		)
		(placement
			(enabled no)
			(sheetname "")
		)
		(fill
			(thermal_gap 0.5)
			(thermal_bridge_width 0.5)
			(island_removal_mode 0)
		)
		(polygon
			(pts
				(xy 424.58005 -216.26449) (xy 424.58005 -214.912448) (xy 425.155614 -214.912448) (xy 425.155614 -216.26449)
			)
		)
	)
	(zone
		(layer "In6.Cu")
		(hatch none 0.5)
		(connect_pads
			(clearance 0)
		)
		(min_thickness 0.25)
		(keepout
			(tracks allowed)
			(vias allowed)
			(pads allowed)
			(copperpour allowed)
			(footprints allowed)
		)
		(placement
			(enabled no)
			(sheetname "")
		)
		(fill
			(thermal_gap 0.5)
			(thermal_bridge_width 0.5)
			(island_removal_mode 0)
		)
		(polygon
			(pts
				(xy 65.808352 -303.760378) (xy 65.808352 -298.198032) (xy 66.452242 -298.198032) (xy 66.452242 -303.760378)
			)
		)
	)
	(zone
		(layer "In6.Cu")
		(hatch none 0.5)
		(connect_pads
			(clearance 0)
		)
		(min_thickness 0.25)
		(keepout
			(tracks allowed)
			(vias allowed)
			(pads allowed)
			(copperpour allowed)
			(footprints allowed)
		)
		(placement
			(enabled no)
			(sheetname "")
		)
		(fill
			(thermal_gap 0.5)
			(thermal_bridge_width 0.5)
			(island_removal_mode 0)
		)
		(polygon
			(pts
				(xy 435.592982 -223.054164) (xy 435.592982 -221.760796) (xy 435.087776 -221.760796) (xy 435.087776 -220.586046)
				(xy 435.592982 -220.586046) (xy 435.592982 -216.244678) (xy 436.168546 -216.244678) (xy 436.168546 -220.862398)
				(xy 436.168546 -223.054164)
			)
		)
	)
	(zone
		(layer "In6.Cu")
		(hatch none 0.5)
		(connect_pads
			(clearance 0)
		)
		(min_thickness 0.25)
		(keepout
			(tracks allowed)
			(vias allowed)
			(pads allowed)
			(copperpour allowed)
			(footprints allowed)
		)
		(placement
			(enabled no)
			(sheetname "")
		)
		(fill
			(thermal_gap 0.5)
			(thermal_bridge_width 0.5)
			(island_removal_mode 0)
		)
		(polygon
			(pts
				(xy 50.813208 -214.55634) (xy 50.813208 -213.23427) (xy 50.813208 -204.351128) (xy 50.61839 -204.351128)
				(xy 50.61839 -202.991212) (xy 50.813208 -202.991212) (xy 51.340766 -202.991212) (xy 51.340766 -213.23427)
				(xy 51.340766 -214.55634)
			)
		)
	)
	(zone
		(layer "In6.Cu")
		(hatch none 0.5)
		(connect_pads
			(clearance 0)
		)
		(min_thickness 0.25)
		(keepout
			(tracks allowed)
			(vias allowed)
			(pads allowed)
			(copperpour allowed)
			(footprints allowed)
		)
		(placement
			(enabled no)
			(sheetname "")
		)
		(fill
			(thermal_gap 0.5)
			(thermal_bridge_width 0.5)
			(island_removal_mode 0)
		)
		(polygon
			(pts
				(xy 358.83088 -56.37784) (xy 358.83088 -54.57698) (xy 362.4326 -54.57698) (xy 362.4326 -56.37784)
			)
		)
	)
	(zone
		(layer "In6.Cu")
		(hatch none 0.5)
		(connect_pads
			(clearance 0)
		)
		(min_thickness 0.25)
		(keepout
			(tracks allowed)
			(vias allowed)
			(pads allowed)
			(copperpour allowed)
			(footprints allowed)
		)
		(placement
			(enabled no)
			(sheetname "")
		)
		(fill
			(thermal_gap 0.5)
			(thermal_bridge_width 0.5)
			(island_removal_mode 0)
		)
		(polygon
			(pts
				(xy 283.620972 -317.447676) (xy 283.620972 -315.940694) (xy 284.23743 -315.940694) (xy 284.23743 -317.447676)
			)
		)
	)
	(zone
		(layer "In6.Cu")
		(hatch none 0.5)
		(connect_pads
			(clearance 0)
		)
		(min_thickness 0.25)
		(keepout
			(tracks allowed)
			(vias allowed)
			(pads allowed)
			(copperpour allowed)
			(footprints allowed)
		)
		(placement
			(enabled no)
			(sheetname "")
		)
		(fill
			(thermal_gap 0.5)
			(thermal_bridge_width 0.5)
			(island_removal_mode 0)
		)
		(polygon
			(pts
				(xy 313.74842 -303.760378) (xy 313.74842 -298.198032) (xy 314.39231 -298.198032) (xy 314.39231 -303.760378)
			)
		)
	)
	(zone
		(layer "In6.Cu")
		(hatch none 0.5)
		(connect_pads
			(clearance 0)
		)
		(min_thickness 0.25)
		(keepout
			(tracks allowed)
			(vias allowed)
			(pads allowed)
			(copperpour allowed)
			(footprints allowed)
		)
		(placement
			(enabled no)
			(sheetname "")
		)
		(fill
			(thermal_gap 0.5)
			(thermal_bridge_width 0.5)
			(island_removal_mode 0)
		)
		(polygon
			(pts
				(xy 283.665676 -220.50629) (xy 283.665676 -219.18422) (xy 284.193234 -219.18422) (xy 284.193234 -220.50629)
			)
		)
	)
	(zone
		(layer "In6.Cu")
		(hatch none 0.5)
		(connect_pads
			(clearance 0)
		)
		(min_thickness 0.25)
		(keepout
			(tracks allowed)
			(vias allowed)
			(pads allowed)
			(copperpour allowed)
			(footprints allowed)
		)
		(placement
			(enabled no)
			(sheetname "")
		)
		(fill
			(thermal_gap 0.5)
			(thermal_bridge_width 0.5)
			(island_removal_mode 0)
		)
		(polygon
			(pts
				(xy 202.740514 -212.194394) (xy 202.740514 -210.66252) (xy 203.316078 -210.66252) (xy 203.316078 -212.194394)
			)
		)
	)
	(zone
		(layer "In6.Cu")
		(hatch none 0.5)
		(connect_pads
			(clearance 0)
		)
		(min_thickness 0.25)
		(keepout
			(tracks allowed)
			(vias allowed)
			(pads allowed)
			(copperpour allowed)
			(footprints allowed)
		)
		(placement
			(enabled no)
			(sheetname "")
		)
		(fill
			(thermal_gap 0.5)
			(thermal_bridge_width 0.5)
			(island_removal_mode 0)
		)
		(polygon
			(pts
				(xy 268.578076 -214.55634) (xy 268.578076 -213.23427) (xy 269.105634 -213.23427) (xy 269.105634 -214.55634)
			)
		)
	)
	(zone
		(layer "In6.Cu")
		(hatch none 0.5)
		(connect_pads
			(clearance 0)
		)
		(min_thickness 0.25)
		(keepout
			(tracks allowed)
			(vias allowed)
			(pads allowed)
			(copperpour allowed)
			(footprints allowed)
		)
		(placement
			(enabled no)
			(sheetname "")
		)
		(fill
			(thermal_gap 0.5)
			(thermal_bridge_width 0.5)
			(island_removal_mode 0)
		)
		(polygon
			(pts
				(xy 291.112194 -245.178326) (xy 291.112194 -243.781072) (xy 291.797232 -243.781072) (xy 291.797232 -245.178326)
			)
		)
	)
	(zone
		(layer "In6.Cu")
		(hatch none 0.5)
		(connect_pads
			(clearance 0)
		)
		(min_thickness 0.25)
		(keepout
			(tracks allowed)
			(vias allowed)
			(pads allowed)
			(copperpour allowed)
			(footprints allowed)
		)
		(placement
			(enabled no)
			(sheetname "")
		)
		(fill
			(thermal_gap 0.5)
			(thermal_bridge_width 0.5)
			(island_removal_mode 0)
		)
		(polygon
			(pts
				(xy 93.50756 -337.917028) (xy 93.50756 -336.400648) (xy 96.901 -336.400648) (xy 96.901 -337.917028)
			)
		)
	)
	(zone
		(layer "In6.Cu")
		(hatch none 0.5)
		(connect_pads
			(clearance 0)
		)
		(min_thickness 0.25)
		(keepout
			(tracks allowed)
			(vias allowed)
			(pads allowed)
			(copperpour allowed)
			(footprints allowed)
		)
		(placement
			(enabled no)
			(sheetname "")
		)
		(fill
			(thermal_gap 0.5)
			(thermal_bridge_width 0.5)
			(island_removal_mode 0)
		)
		(polygon
			(pts
				(xy 31.611824 -307.250592) (xy 31.611824 -306.700174) (xy 31.991808 -306.32019) (xy 32.54756 -306.32019)
				(xy 32.54756 -306.97678) (xy 32.273748 -307.250592) (xy 32.170624 -307.250592)
			)
		)
	)
	(zone
		(layer "In6.Cu")
		(hatch none 0.5)
		(connect_pads
			(clearance 0)
		)
		(min_thickness 0.25)
		(keepout
			(tracks allowed)
			(vias allowed)
			(pads allowed)
			(copperpour allowed)
			(footprints allowed)
		)
		(placement
			(enabled no)
			(sheetname "")
		)
		(fill
			(thermal_gap 0.5)
			(thermal_bridge_width 0.5)
			(island_removal_mode 0)
		)
		(polygon
			(pts
				(xy 86.89594 -341.589868) (xy 86.89594 -340.307168) (xy 89.12352 -340.307168) (xy 89.12352 -341.589868)
			)
		)
	)
	(zone
		(layer "In6.Cu")
		(hatch none 0.5)
		(connect_pads
			(clearance 0)
		)
		(min_thickness 0.25)
		(keepout
			(tracks allowed)
			(vias allowed)
			(pads allowed)
			(copperpour allowed)
			(footprints allowed)
		)
		(placement
			(enabled no)
			(sheetname "")
		)
		(fill
			(thermal_gap 0.5)
			(thermal_bridge_width 0.5)
			(island_removal_mode 0)
		)
		(polygon
			(pts
				(xy 16.7767 -106.61142) (xy 16.7767 -103.68534) (xy 15.38732 -103.68534) (xy 15.38732 -106.61142)
			)
		)
	)
	(zone
		(layer "In6.Cu")
		(hatch none 0.5)
		(connect_pads
			(clearance 0)
		)
		(min_thickness 0.25)
		(keepout
			(tracks allowed)
			(vias allowed)
			(pads allowed)
			(copperpour allowed)
			(footprints allowed)
		)
		(placement
			(enabled no)
			(sheetname "")
		)
		(fill
			(thermal_gap 0.5)
			(thermal_bridge_width 0.5)
			(island_removal_mode 0)
		)
		(polygon
			(pts
				(xy 283.665676 -229.856284) (xy 283.665676 -228.534214) (xy 284.193234 -228.534214) (xy 284.193234 -229.856284)
			)
		)
	)
	(zone
		(layer "In6.Cu")
		(hatch none 0.5)
		(connect_pads
			(clearance 0)
		)
		(min_thickness 0.25)
		(keepout
			(tracks allowed)
			(vias allowed)
			(pads allowed)
			(copperpour allowed)
			(footprints allowed)
		)
		(placement
			(enabled no)
			(sheetname "")
		)
		(fill
			(thermal_gap 0.5)
			(thermal_bridge_width 0.5)
			(island_removal_mode 0)
		)
		(polygon
			(pts
				(xy 20.638008 -317.406274) (xy 20.638008 -316.084204) (xy 21.165566 -316.084204) (xy 21.165566 -317.406274)
			)
		)
	)
	(zone
		(layer "In6.Cu")
		(hatch none 0.5)
		(connect_pads
			(clearance 0)
		)
		(min_thickness 0.25)
		(keepout
			(tracks allowed)
			(vias allowed)
			(pads allowed)
			(copperpour allowed)
			(footprints allowed)
		)
		(placement
			(enabled no)
			(sheetname "")
		)
		(fill
			(thermal_gap 0.5)
			(thermal_bridge_width 0.5)
			(island_removal_mode 0)
		)
		(polygon
			(pts
				(xy 420.388034 -213.765638) (xy 420.388034 -209.79638) (xy 421.018208 -209.79638) (xy 421.018208 -213.765638)
			)
		)
	)
	(zone
		(layer "In6.Cu")
		(hatch none 0.5)
		(connect_pads
			(clearance 0)
		)
		(min_thickness 0.25)
		(keepout
			(tracks allowed)
			(vias allowed)
			(pads allowed)
			(copperpour allowed)
			(footprints allowed)
		)
		(placement
			(enabled no)
			(sheetname "")
		)
		(fill
			(thermal_gap 0.5)
			(thermal_bridge_width 0.5)
			(island_removal_mode 0)
		)
		(polygon
			(pts
				(xy 294.653208 -243.45646) (xy 294.653208 -242.13439) (xy 295.180766 -242.13439) (xy 295.180766 -243.45646)
			)
		)
	)
	(zone
		(layer "In6.Cu")
		(hatch none 0.5)
		(connect_pads
			(clearance 0)
		)
		(min_thickness 0.25)
		(keepout
			(tracks allowed)
			(vias allowed)
			(pads allowed)
			(copperpour allowed)
			(footprints allowed)
		)
		(placement
			(enabled no)
			(sheetname "")
		)
		(fill
			(thermal_gap 0.5)
			(thermal_bridge_width 0.5)
			(island_removal_mode 0)
		)
		(polygon
			(pts
				(xy 420.479982 -312.31459) (xy 420.479982 -303.346358) (xy 421.055546 -303.346358) (xy 421.055546 -312.31459)
			)
		)
	)
	(zone
		(layer "In6.Cu")
		(hatch none 0.5)
		(connect_pads
			(clearance 0)
		)
		(min_thickness 0.25)
		(keepout
			(tracks allowed)
			(vias allowed)
			(pads allowed)
			(copperpour allowed)
			(footprints allowed)
		)
		(placement
			(enabled no)
			(sheetname "")
		)
		(fill
			(thermal_gap 0.5)
			(thermal_bridge_width 0.5)
			(island_removal_mode 0)
		)
		(polygon
			(pts
				(xy 35.725608 -233.256328) (xy 35.725608 -231.934258) (xy 36.253166 -231.934258) (xy 36.253166 -233.256328)
			)
		)
	)
	(zone
		(layer "In6.Cu")
		(hatch none 0.5)
		(connect_pads
			(clearance 0)
		)
		(min_thickness 0.25)
		(keepout
			(tracks allowed)
			(vias allowed)
			(pads allowed)
			(copperpour allowed)
			(footprints allowed)
		)
		(placement
			(enabled no)
			(sheetname "")
		)
		(fill
			(thermal_gap 0.5)
			(thermal_bridge_width 0.5)
			(island_removal_mode 0)
		)
		(polygon
			(pts
				(xy 278.50846 -217.038428) (xy 278.50846 -213.952328) (xy 281.7495 -213.952328) (xy 281.7495 -217.038428)
			)
		)
	)
	(zone
		(layer "In6.Cu")
		(hatch none 0.5)
		(connect_pads
			(clearance 0)
		)
		(min_thickness 0.25)
		(keepout
			(tracks allowed)
			(vias allowed)
			(pads allowed)
			(copperpour allowed)
			(footprints allowed)
		)
		(placement
			(enabled no)
			(sheetname "")
		)
		(fill
			(thermal_gap 0.5)
			(thermal_bridge_width 0.5)
			(island_removal_mode 0)
		)
		(polygon
			(pts
				(xy 283.54274 -284.3149) (xy 283.54274 -282.047442) (xy 284.227778 -282.047442) (xy 284.227778 -284.3149)
			)
		)
	)
	(zone
		(layer "In6.Cu")
		(hatch none 0.5)
		(connect_pads
			(clearance 0)
		)
		(min_thickness 0.25)
		(keepout
			(tracks allowed)
			(vias allowed)
			(pads allowed)
			(copperpour allowed)
			(footprints allowed)
		)
		(placement
			(enabled no)
			(sheetname "")
		)
		(fill
			(thermal_gap 0.5)
			(thermal_bridge_width 0.5)
			(island_removal_mode 0)
		)
		(polygon
			(pts
				(xy 76.6445 -350.726248) (xy 76.6445 -349.347028) (xy 77.41666 -349.347028) (xy 77.41666 -350.726248)
			)
		)
	)
	(zone
		(layer "In6.Cu")
		(hatch none 0.5)
		(connect_pads
			(clearance 0)
		)
		(min_thickness 0.25)
		(keepout
			(tracks allowed)
			(vias allowed)
			(pads allowed)
			(copperpour allowed)
			(footprints allowed)
		)
		(placement
			(enabled no)
			(sheetname "")
		)
		(fill
			(thermal_gap 0.5)
			(thermal_bridge_width 0.5)
			(island_removal_mode 0)
		)
		(polygon
			(pts
				(xy 172.539914 -217.114628) (xy 172.539914 -215.762586) (xy 173.115478 -215.762586) (xy 173.115478 -217.114628)
			)
		)
	)
	(zone
		(layer "In6.Cu")
		(hatch none 0.5)
		(connect_pads
			(clearance 0)
		)
		(min_thickness 0.25)
		(keepout
			(tracks allowed)
			(vias allowed)
			(pads allowed)
			(copperpour allowed)
			(footprints allowed)
		)
		(placement
			(enabled no)
			(sheetname "")
		)
		(fill
			(thermal_gap 0.5)
			(thermal_bridge_width 0.5)
			(island_removal_mode 0)
		)
		(polygon
			(pts
				(xy 51.950366 -195.800726) (xy 51.950366 -194.567556) (xy 52.546504 -194.567556) (xy 52.546504 -195.800726)
			)
		)
	)
	(zone
		(layer "In6.Cu")
		(hatch none 0.5)
		(connect_pads
			(clearance 0)
		)
		(min_thickness 0.25)
		(keepout
			(tracks allowed)
			(vias allowed)
			(pads allowed)
			(copperpour allowed)
			(footprints allowed)
		)
		(placement
			(enabled no)
			(sheetname "")
		)
		(fill
			(thermal_gap 0.5)
			(thermal_bridge_width 0.5)
			(island_removal_mode 0)
		)
		(polygon
			(pts
				(xy 202.740514 -207.805782) (xy 202.740514 -207.262476) (xy 203.316078 -207.262476) (xy 203.316078 -208.79435)
				(xy 202.740514 -208.79435) (xy 202.613768 -208.79435) (xy 202.613768 -207.805782)
			)
		)
	)
	(zone
		(layer "In6.Cu")
		(hatch none 0.5)
		(connect_pads
			(clearance 0)
		)
		(min_thickness 0.25)
		(keepout
			(tracks allowed)
			(vias allowed)
			(pads allowed)
			(copperpour allowed)
			(footprints allowed)
		)
		(placement
			(enabled no)
			(sheetname "")
		)
		(fill
			(thermal_gap 0.5)
			(thermal_bridge_width 0.5)
			(island_removal_mode 0)
		)
		(polygon
			(pts
				(xy 35.602672 -288.564828) (xy 35.602672 -286.29737) (xy 36.28771 -286.29737) (xy 36.28771 -288.564828)
			)
		)
	)
	(zone
		(layer "In6.Cu")
		(hatch none 0.5)
		(connect_pads
			(clearance 0)
		)
		(min_thickness 0.25)
		(keepout
			(tracks allowed)
			(vias allowed)
			(pads allowed)
			(copperpour allowed)
			(footprints allowed)
		)
		(placement
			(enabled no)
			(sheetname "")
		)
		(fill
			(thermal_gap 0.5)
			(thermal_bridge_width 0.5)
			(island_removal_mode 0)
		)
		(polygon
			(pts
				(xy 35.602672 -282.614878) (xy 35.602672 -280.34742) (xy 36.28771 -280.34742) (xy 36.28771 -282.614878)
			)
		)
	)
	(zone
		(layer "In6.Cu")
		(hatch none 0.5)
		(connect_pads
			(clearance 0)
		)
		(min_thickness 0.25)
		(keepout
			(tracks allowed)
			(vias allowed)
			(pads allowed)
			(copperpour allowed)
			(footprints allowed)
		)
		(placement
			(enabled no)
			(sheetname "")
		)
		(fill
			(thermal_gap 0.5)
			(thermal_bridge_width 0.5)
			(island_removal_mode 0)
		)
		(polygon
			(pts
				(xy 187.627514 -285.96463) (xy 187.627514 -284.612588) (xy 188.203078 -284.612588) (xy 188.203078 -285.96463)
			)
		)
	)
	(zone
		(layer "In6.Cu")
		(hatch none 0.5)
		(connect_pads
			(clearance 0)
		)
		(min_thickness 0.25)
		(keepout
			(tracks allowed)
			(vias allowed)
			(pads allowed)
			(copperpour allowed)
			(footprints allowed)
		)
		(placement
			(enabled no)
			(sheetname "")
		)
		(fill
			(thermal_gap 0.5)
			(thermal_bridge_width 0.5)
			(island_removal_mode 0)
		)
		(polygon
			(pts
				(xy 172.539914 -215.414606) (xy 172.539914 -214.062564) (xy 173.115478 -214.062564) (xy 173.115478 -215.414606)
			)
		)
	)
	(zone
		(layer "In6.Cu")
		(hatch none 0.5)
		(connect_pads
			(clearance 0)
		)
		(min_thickness 0.25)
		(keepout
			(tracks allowed)
			(vias allowed)
			(pads allowed)
			(copperpour allowed)
			(footprints allowed)
		)
		(placement
			(enabled no)
			(sheetname "")
		)
		(fill
			(thermal_gap 0.5)
			(thermal_bridge_width 0.5)
			(island_removal_mode 0)
		)
		(polygon
			(pts
				(xy 191.2493 -306.365148) (xy 191.2493 -305.376834) (xy 192.303146 -305.376834) (xy 192.303146 -305.862482)
				(xy 192.303146 -307.214524) (xy 191.727582 -307.214524) (xy 191.2493 -307.214524)
			)
		)
	)
	(zone
		(layer "In6.Cu")
		(hatch none 0.5)
		(connect_pads
			(clearance 0)
		)
		(min_thickness 0.25)
		(keepout
			(tracks allowed)
			(vias allowed)
			(pads allowed)
			(copperpour allowed)
			(footprints allowed)
		)
		(placement
			(enabled no)
			(sheetname "")
		)
		(fill
			(thermal_gap 0.5)
			(thermal_bridge_width 0.5)
			(island_removal_mode 0)
		)
		(polygon
			(pts
				(xy 309.617872 -270.714978) (xy 309.617872 -268.44752) (xy 310.30291 -268.44752) (xy 310.30291 -270.714978)
			)
		)
	)
	(zone
		(layer "In6.Cu")
		(hatch none 0.5)
		(connect_pads
			(clearance 0)
		)
		(min_thickness 0.25)
		(keepout
			(tracks allowed)
			(vias allowed)
			(pads allowed)
			(copperpour allowed)
			(footprints allowed)
		)
		(placement
			(enabled no)
			(sheetname "")
		)
		(fill
			(thermal_gap 0.5)
			(thermal_bridge_width 0.5)
			(island_removal_mode 0)
		)
		(polygon
			(pts
				(xy 294.653208 -246.85625) (xy 294.653208 -245.53418) (xy 295.180766 -245.53418) (xy 295.180766 -246.85625)
			)
		)
	)
	(zone
		(layer "In6.Cu")
		(hatch none 0.5)
		(connect_pads
			(clearance 0)
		)
		(min_thickness 0.25)
		(keepout
			(tracks allowed)
			(vias allowed)
			(pads allowed)
			(copperpour allowed)
			(footprints allowed)
		)
		(placement
			(enabled no)
			(sheetname "")
		)
		(fill
			(thermal_gap 0.5)
			(thermal_bridge_width 0.5)
			(island_removal_mode 0)
		)
		(polygon
			(pts
				(xy 187.627514 -278.314658) (xy 187.627514 -276.962616) (xy 188.203078 -276.962616) (xy 188.203078 -278.314658)
			)
		)
	)
	(zone
		(layer "In6.Cu")
		(hatch none 0.5)
		(connect_pads
			(clearance 0)
		)
		(min_thickness 0.25)
		(keepout
			(tracks allowed)
			(vias allowed)
			(pads allowed)
			(copperpour allowed)
			(footprints allowed)
		)
		(placement
			(enabled no)
			(sheetname "")
		)
		(fill
			(thermal_gap 0.5)
			(thermal_bridge_width 0.5)
			(island_removal_mode 0)
		)
		(polygon
			(pts
				(xy 50.795682 -314.423552) (xy 50.795682 -313.114944) (xy 51.330098 -313.114944) (xy 51.330098 -314.423552)
			)
		)
	)
	(zone
		(layer "In6.Cu")
		(hatch none 0.5)
		(connect_pads
			(clearance 0)
		)
		(min_thickness 0.25)
		(keepout
			(tracks allowed)
			(vias allowed)
			(pads allowed)
			(copperpour allowed)
			(footprints allowed)
		)
		(placement
			(enabled no)
			(sheetname "")
		)
		(fill
			(thermal_gap 0.5)
			(thermal_bridge_width 0.5)
			(island_removal_mode 0)
		)
		(polygon
			(pts
				(xy 20.638008 -212.856318) (xy 20.638008 -211.534248) (xy 21.165566 -211.534248) (xy 21.165566 -212.856318)
			)
		)
	)
	(zone
		(layer "In6.Cu")
		(hatch none 0.5)
		(connect_pads
			(clearance 0)
		)
		(min_thickness 0.25)
		(keepout
			(tracks allowed)
			(vias allowed)
			(pads allowed)
			(copperpour allowed)
			(footprints allowed)
		)
		(placement
			(enabled no)
			(sheetname "")
		)
		(fill
			(thermal_gap 0.5)
			(thermal_bridge_width 0.5)
			(island_removal_mode 0)
		)
		(polygon
			(pts
				(xy 283.665676 -229.0064) (xy 283.665676 -227.68433) (xy 284.193234 -227.68433) (xy 284.193234 -229.0064)
			)
		)
	)
	(zone
		(layer "In6.Cu")
		(hatch none 0.5)
		(connect_pads
			(clearance 0)
		)
		(min_thickness 0.25)
		(keepout
			(tracks allowed)
			(vias allowed)
			(pads allowed)
			(copperpour allowed)
			(footprints allowed)
		)
		(placement
			(enabled no)
			(sheetname "")
		)
		(fill
			(thermal_gap 0.5)
			(thermal_bridge_width 0.5)
			(island_removal_mode 0)
		)
		(polygon
			(pts
				(xy 309.740808 -243.464842) (xy 309.740808 -242.163346) (xy 310.316372 -242.163346) (xy 310.316372 -243.464842)
			)
		)
	)
	(zone
		(layer "In6.Cu")
		(hatch none 0.5)
		(connect_pads
			(clearance 0)
		)
		(min_thickness 0.25)
		(keepout
			(tracks allowed)
			(vias allowed)
			(pads allowed)
			(copperpour allowed)
			(footprints allowed)
		)
		(placement
			(enabled no)
			(sheetname "")
		)
		(fill
			(thermal_gap 0.5)
			(thermal_bridge_width 0.5)
			(island_removal_mode 0)
		)
		(polygon
			(pts
				(xy 424.58005 -304.664618) (xy 424.58005 -302.48098) (xy 425.155614 -302.48098) (xy 425.155614 -304.664618)
			)
		)
	)
	(zone
		(layer "In6.Cu")
		(hatch none 0.5)
		(connect_pads
			(clearance 0)
		)
		(min_thickness 0.25)
		(keepout
			(tracks allowed)
			(vias allowed)
			(pads allowed)
			(copperpour allowed)
			(footprints allowed)
		)
		(placement
			(enabled no)
			(sheetname "")
		)
		(fill
			(thermal_gap 0.5)
			(thermal_bridge_width 0.5)
			(island_removal_mode 0)
		)
		(polygon
			(pts
				(xy 268.578076 -315.706252) (xy 268.578076 -314.384182) (xy 269.105634 -314.384182) (xy 269.105634 -315.706252)
			)
		)
	)
	(zone
		(layer "In6.Cu")
		(hatch none 0.5)
		(connect_pads
			(clearance 0)
		)
		(min_thickness 0.25)
		(keepout
			(tracks allowed)
			(vias allowed)
			(pads allowed)
			(copperpour allowed)
			(footprints allowed)
		)
		(placement
			(enabled no)
			(sheetname "")
		)
		(fill
			(thermal_gap 0.5)
			(thermal_bridge_width 0.5)
			(island_removal_mode 0)
		)
		(polygon
			(pts
				(xy 161.526982 -225.614484) (xy 161.526982 -224.262442) (xy 162.102546 -224.262442) (xy 162.102546 -225.614484)
			)
		)
	)
	(zone
		(layer "In6.Cu")
		(hatch none 0.5)
		(connect_pads
			(clearance 0)
		)
		(min_thickness 0.25)
		(keepout
			(tracks allowed)
			(vias allowed)
			(pads allowed)
			(copperpour allowed)
			(footprints allowed)
		)
		(placement
			(enabled no)
			(sheetname "")
		)
		(fill
			(thermal_gap 0.5)
			(thermal_bridge_width 0.5)
			(island_removal_mode 0)
		)
		(polygon
			(pts
				(xy 187.652914 -229.854252) (xy 187.652914 -226.776788) (xy 187.002166 -226.776788) (xy 187.002166 -225.863658)
				(xy 187.652914 -225.863658) (xy 188.228478 -225.863658) (xy 188.228478 -229.854252)
			)
		)
	)
	(zone
		(layer "In6.Cu")
		(hatch none 0.5)
		(connect_pads
			(clearance 0)
		)
		(min_thickness 0.25)
		(keepout
			(tracks allowed)
			(vias allowed)
			(pads allowed)
			(copperpour allowed)
			(footprints allowed)
		)
		(placement
			(enabled no)
			(sheetname "")
		)
		(fill
			(thermal_gap 0.5)
			(thermal_bridge_width 0.5)
			(island_removal_mode 0)
		)
		(polygon
			(pts
				(xy 439.66765 -246.854218) (xy 439.66765 -244.662452) (xy 440.243214 -244.662452) (xy 440.243214 -246.854218)
			)
		)
	)
	(zone
		(layer "In6.Cu")
		(hatch none 0.5)
		(connect_pads
			(clearance 0)
		)
		(min_thickness 0.25)
		(keepout
			(tracks allowed)
			(vias allowed)
			(pads allowed)
			(copperpour allowed)
			(footprints allowed)
		)
		(placement
			(enabled no)
			(sheetname "")
		)
		(fill
			(thermal_gap 0.5)
			(thermal_bridge_width 0.5)
			(island_removal_mode 0)
		)
		(polygon
			(pts
				(xy 31.62554 -248.556272) (xy 31.62554 -247.234202) (xy 32.153098 -247.234202) (xy 32.153098 -248.556272)
			)
		)
	)
	(zone
		(layer "In6.Cu")
		(hatch none 0.5)
		(connect_pads
			(clearance 0)
		)
		(min_thickness 0.25)
		(keepout
			(tracks allowed)
			(vias allowed)
			(pads allowed)
			(copperpour allowed)
			(footprints allowed)
		)
		(placement
			(enabled no)
			(sheetname "")
		)
		(fill
			(thermal_gap 0.5)
			(thermal_bridge_width 0.5)
			(island_removal_mode 0)
		)
		(polygon
			(pts
				(xy 268.578076 -210.306412) (xy 268.578076 -208.984342) (xy 269.105634 -208.984342) (xy 269.105634 -210.306412)
			)
		)
	)
	(zone
		(layer "In6.Cu")
		(hatch none 0.5)
		(connect_pads
			(clearance 0)
		)
		(min_thickness 0.25)
		(keepout
			(tracks allowed)
			(vias allowed)
			(pads allowed)
			(copperpour allowed)
			(footprints allowed)
		)
		(placement
			(enabled no)
			(sheetname "")
		)
		(fill
			(thermal_gap 0.5)
			(thermal_bridge_width 0.5)
			(island_removal_mode 0)
		)
		(polygon
			(pts
				(xy 65.849754 -269.71498) (xy 65.849754 -267.605256) (xy 66.493644 -267.605256) (xy 66.493644 -269.71498)
			)
		)
	)
	(zone
		(layer "In6.Cu")
		(hatch none 0.5)
		(connect_pads
			(clearance 0)
		)
		(min_thickness 0.25)
		(keepout
			(tracks allowed)
			(vias allowed)
			(pads allowed)
			(copperpour allowed)
			(footprints allowed)
		)
		(placement
			(enabled no)
			(sheetname "")
		)
		(fill
			(thermal_gap 0.5)
			(thermal_bridge_width 0.5)
			(island_removal_mode 0)
		)
		(polygon
			(pts
				(xy 283.665676 -246.006366) (xy 283.665676 -244.684296) (xy 284.193234 -244.684296) (xy 284.193234 -246.006366)
			)
		)
	)
	(zone
		(layer "In6.Cu")
		(hatch none 0.5)
		(connect_pads
			(clearance 0)
		)
		(min_thickness 0.25)
		(keepout
			(tracks allowed)
			(vias allowed)
			(pads allowed)
			(copperpour allowed)
			(footprints allowed)
		)
		(placement
			(enabled no)
			(sheetname "")
		)
		(fill
			(thermal_gap 0.5)
			(thermal_bridge_width 0.5)
			(island_removal_mode 0)
		)
		(polygon
			(pts
				(xy 422.08196 -366.619028) (xy 422.08196 -365.554768) (xy 423.06748 -365.554768) (xy 423.06748 -366.619028)
			)
		)
	)
	(zone
		(layer "In6.Cu")
		(hatch none 0.5)
		(connect_pads
			(clearance 0)
		)
		(min_thickness 0.25)
		(keepout
			(tracks allowed)
			(vias allowed)
			(pads allowed)
			(copperpour allowed)
			(footprints allowed)
		)
		(placement
			(enabled no)
			(sheetname "")
		)
		(fill
			(thermal_gap 0.5)
			(thermal_bridge_width 0.5)
			(island_removal_mode 0)
		)
		(polygon
			(pts
				(xy 46.590204 -308.114954) (xy 46.590204 -305.847496) (xy 47.275242 -305.847496) (xy 47.275242 -308.114954)
				(xy 47.275242 -314.799472) (xy 46.590204 -314.799472)
			)
		)
	)
	(zone
		(layer "In6.Cu")
		(hatch none 0.5)
		(connect_pads
			(clearance 0)
		)
		(min_thickness 0.25)
		(keepout
			(tracks allowed)
			(vias allowed)
			(pads allowed)
			(copperpour allowed)
			(footprints allowed)
		)
		(placement
			(enabled no)
			(sheetname "")
		)
		(fill
			(thermal_gap 0.5)
			(thermal_bridge_width 0.5)
			(island_removal_mode 0)
		)
		(polygon
			(pts
				(xy 435.567582 -276.614636) (xy 435.567582 -272.724118) (xy 436.143146 -272.724118) (xy 436.143146 -276.614636)
			)
		)
	)
	(zone
		(layer "In6.Cu")
		(hatch none 0.5)
		(connect_pads
			(clearance 0)
		)
		(min_thickness 0.25)
		(keepout
			(tracks allowed)
			(vias allowed)
			(pads allowed)
			(copperpour allowed)
			(footprints allowed)
		)
		(placement
			(enabled no)
			(sheetname "")
		)
		(fill
			(thermal_gap 0.5)
			(thermal_bridge_width 0.5)
			(island_removal_mode 0)
		)
		(polygon
			(pts
				(xy 405.366982 -230.71455) (xy 405.366982 -229.362508) (xy 405.942546 -229.362508) (xy 405.942546 -230.71455)
			)
		)
	)
	(zone
		(layer "In6.Cu")
		(hatch none 0.5)
		(connect_pads
			(clearance 0)
		)
		(min_thickness 0.25)
		(keepout
			(tracks allowed)
			(vias allowed)
			(pads allowed)
			(copperpour allowed)
			(footprints allowed)
		)
		(placement
			(enabled no)
			(sheetname "")
		)
		(fill
			(thermal_gap 0.5)
			(thermal_bridge_width 0.5)
			(island_removal_mode 0)
		)
		(polygon
			(pts
				(xy 294.530272 -305.564794) (xy 294.530272 -303.297336) (xy 295.21531 -303.297336) (xy 295.21531 -305.564794)
			)
		)
	)
	(zone
		(layer "In6.Cu")
		(hatch none 0.5)
		(connect_pads
			(clearance 0)
		)
		(min_thickness 0.25)
		(keepout
			(tracks allowed)
			(vias allowed)
			(pads allowed)
			(copperpour allowed)
			(footprints allowed)
		)
		(placement
			(enabled no)
			(sheetname "")
		)
		(fill
			(thermal_gap 0.5)
			(thermal_bridge_width 0.5)
			(island_removal_mode 0)
		)
		(polygon
			(pts
				(xy 283.665676 -249.40641) (xy 283.665676 -248.08434) (xy 284.193234 -248.08434) (xy 284.193234 -249.40641)
			)
		)
	)
	(zone
		(layer "In6.Cu")
		(hatch none 0.5)
		(connect_pads
			(clearance 0)
		)
		(min_thickness 0.25)
		(keepout
			(tracks allowed)
			(vias allowed)
			(pads allowed)
			(copperpour allowed)
			(footprints allowed)
		)
		(placement
			(enabled no)
			(sheetname "")
		)
		(fill
			(thermal_gap 0.5)
			(thermal_bridge_width 0.5)
			(island_removal_mode 0)
		)
		(polygon
			(pts
				(xy 268.578076 -308.906418) (xy 268.578076 -307.584348) (xy 269.105634 -307.584348) (xy 269.105634 -308.906418)
			)
		)
	)
	(zone
		(layer "In6.Cu")
		(hatch none 0.5)
		(connect_pads
			(clearance 0)
		)
		(min_thickness 0.25)
		(keepout
			(tracks allowed)
			(vias allowed)
			(pads allowed)
			(copperpour allowed)
			(footprints allowed)
		)
		(placement
			(enabled no)
			(sheetname "")
		)
		(fill
			(thermal_gap 0.5)
			(thermal_bridge_width 0.5)
			(island_removal_mode 0)
		)
		(polygon
			(pts
				(xy 65.885822 -306.790852) (xy 65.885822 -305.482244) (xy 66.420238 -305.482244) (xy 66.420238 -306.790852)
			)
		)
	)
	(zone
		(layer "In6.Cu")
		(hatch none 0.5)
		(connect_pads
			(clearance 0)
		)
		(min_thickness 0.25)
		(keepout
			(tracks allowed)
			(vias allowed)
			(pads allowed)
			(copperpour allowed)
			(footprints allowed)
		)
		(placement
			(enabled no)
			(sheetname "")
		)
		(fill
			(thermal_gap 0.5)
			(thermal_bridge_width 0.5)
			(island_removal_mode 0)
		)
		(polygon
			(pts
				(xy 176.639982 -245.16461) (xy 176.639982 -243.812568) (xy 177.215546 -243.812568) (xy 177.215546 -245.16461)
			)
		)
	)
	(zone
		(layer "In6.Cu")
		(hatch none 0.5)
		(connect_pads
			(clearance 0)
		)
		(min_thickness 0.25)
		(keepout
			(tracks allowed)
			(vias allowed)
			(pads allowed)
			(copperpour allowed)
			(footprints allowed)
		)
		(placement
			(enabled no)
			(sheetname "")
		)
		(fill
			(thermal_gap 0.5)
			(thermal_bridge_width 0.5)
			(island_removal_mode 0)
		)
		(polygon
			(pts
				(xy 187.627514 -299.564552) (xy 187.627514 -298.21251) (xy 188.203078 -298.21251) (xy 188.203078 -299.564552)
			)
		)
	)
	(zone
		(layer "In6.Cu")
		(hatch none 0.5)
		(connect_pads
			(clearance 0)
		)
		(min_thickness 0.25)
		(keepout
			(tracks allowed)
			(vias allowed)
			(pads allowed)
			(copperpour allowed)
			(footprints allowed)
		)
		(placement
			(enabled no)
			(sheetname "")
		)
		(fill
			(thermal_gap 0.5)
			(thermal_bridge_width 0.5)
			(island_removal_mode 0)
		)
		(polygon
			(pts
				(xy 299.890434 -195.800726) (xy 299.890434 -194.567556) (xy 300.486572 -194.567556) (xy 300.486572 -195.800726)
			)
		)
	)
	(zone
		(layer "In6.Cu")
		(hatch none 0.5)
		(connect_pads
			(clearance 0)
		)
		(min_thickness 0.25)
		(keepout
			(tracks allowed)
			(vias allowed)
			(pads allowed)
			(copperpour allowed)
			(footprints allowed)
		)
		(placement
			(enabled no)
			(sheetname "")
		)
		(fill
			(thermal_gap 0.5)
			(thermal_bridge_width 0.5)
			(island_removal_mode 0)
		)
		(polygon
			(pts
				(xy 20.638008 -214.55634) (xy 20.638008 -213.23427) (xy 21.165566 -213.23427) (xy 21.165566 -214.55634)
			)
		)
	)
	(zone
		(layer "In6.Cu")
		(hatch none 0.5)
		(connect_pads
			(clearance 0)
		)
		(min_thickness 0.25)
		(keepout
			(tracks allowed)
			(vias allowed)
			(pads allowed)
			(copperpour allowed)
			(footprints allowed)
		)
		(placement
			(enabled no)
			(sheetname "")
		)
		(fill
			(thermal_gap 0.5)
			(thermal_bridge_width 0.5)
			(island_removal_mode 0)
		)
		(polygon
			(pts
				(xy 435.592982 -229.854252) (xy 435.592982 -226.776788) (xy 434.942234 -226.776788) (xy 434.942234 -225.863658)
				(xy 435.592982 -225.863658) (xy 436.168546 -225.863658) (xy 436.168546 -229.854252)
			)
		)
	)
	(zone
		(layer "In6.Cu")
		(hatch none 0.5)
		(connect_pads
			(clearance 0)
		)
		(min_thickness 0.25)
		(keepout
			(tracks allowed)
			(vias allowed)
			(pads allowed)
			(copperpour allowed)
			(footprints allowed)
		)
		(placement
			(enabled no)
			(sheetname "")
		)
		(fill
			(thermal_gap 0.5)
			(thermal_bridge_width 0.5)
			(island_removal_mode 0)
		)
		(polygon
			(pts
				(xy 309.576724 -233.257852) (xy 309.576724 -224.188274) (xy 310.316626 -224.188274) (xy 310.316626 -233.257852)
			)
		)
	)
	(zone
		(layer "In6.Cu")
		(hatch none 0.5)
		(connect_pads
			(clearance 0)
		)
		(min_thickness 0.25)
		(keepout
			(tracks allowed)
			(vias allowed)
			(pads allowed)
			(copperpour allowed)
			(footprints allowed)
		)
		(placement
			(enabled no)
			(sheetname "")
		)
		(fill
			(thermal_gap 0.5)
			(thermal_bridge_width 0.5)
			(island_removal_mode 0)
		)
		(polygon
			(pts
				(xy 52.77358 -157.399228) (xy 52.77358 -155.989528) (xy 54.00802 -155.989528) (xy 54.00802 -157.399228)
			)
		)
	)
	(zone
		(layer "In6.Cu")
		(hatch none 0.5)
		(connect_pads
			(clearance 0)
		)
		(min_thickness 0.25)
		(keepout
			(tracks allowed)
			(vias allowed)
			(pads allowed)
			(copperpour allowed)
			(footprints allowed)
		)
		(placement
			(enabled no)
			(sheetname "")
		)
		(fill
			(thermal_gap 0.5)
			(thermal_bridge_width 0.5)
			(island_removal_mode 0)
		)
		(polygon
			(pts
				(xy 191.635634 -202.146408) (xy 192.265808 -202.146408) (xy 192.265808 -203.502768) (xy 192.265808 -204.088746)
				(xy 191.318642 -204.088746) (xy 191.318642 -203.502768) (xy 191.318642 -202.146408)
			)
		)
	)
	(zone
		(layer "In6.Cu")
		(hatch none 0.5)
		(connect_pads
			(clearance 0)
		)
		(min_thickness 0.25)
		(keepout
			(tracks allowed)
			(vias allowed)
			(pads allowed)
			(copperpour allowed)
			(footprints allowed)
		)
		(placement
			(enabled no)
			(sheetname "")
		)
		(fill
			(thermal_gap 0.5)
			(thermal_bridge_width 0.5)
			(island_removal_mode 0)
		)
		(polygon
			(pts
				(xy 439.189368 -306.365148) (xy 439.189368 -305.376834) (xy 440.243214 -305.376834) (xy 440.243214 -305.862482)
				(xy 440.243214 -307.214524) (xy 439.66765 -307.214524) (xy 439.189368 -307.214524)
			)
		)
	)
	(zone
		(layer "In6.Cu")
		(hatch none 0.5)
		(connect_pads
			(clearance 0)
		)
		(min_thickness 0.25)
		(keepout
			(tracks allowed)
			(vias allowed)
			(pads allowed)
			(copperpour allowed)
			(footprints allowed)
		)
		(placement
			(enabled no)
			(sheetname "")
		)
		(fill
			(thermal_gap 0.5)
			(thermal_bridge_width 0.5)
			(island_removal_mode 0)
		)
		(polygon
			(pts
				(xy 282.09494 -204.158088) (xy 282.09494 -201.765408) (xy 285.60522 -201.765408) (xy 285.60522 -204.158088)
			)
		)
	)
	(zone
		(layer "In6.Cu")
		(hatch none 0.5)
		(connect_pads
			(clearance 0)
		)
		(min_thickness 0.25)
		(keepout
			(tracks allowed)
			(vias allowed)
			(pads allowed)
			(copperpour allowed)
			(footprints allowed)
		)
		(placement
			(enabled no)
			(sheetname "")
		)
		(fill
			(thermal_gap 0.5)
			(thermal_bridge_width 0.5)
			(island_removal_mode 0)
		)
		(polygon
			(pts
				(xy 283.54274 -304.71491) (xy 283.54274 -302.447452) (xy 284.227778 -302.447452) (xy 284.227778 -304.71491)
			)
		)
	)
	(zone
		(layer "In6.Cu")
		(hatch none 0.5)
		(connect_pads
			(clearance 0)
		)
		(min_thickness 0.25)
		(keepout
			(tracks allowed)
			(vias allowed)
			(pads allowed)
			(copperpour allowed)
			(footprints allowed)
		)
		(placement
			(enabled no)
			(sheetname "")
		)
		(fill
			(thermal_gap 0.5)
			(thermal_bridge_width 0.5)
			(island_removal_mode 0)
		)
		(polygon
			(pts
				(xy 35.680904 -317.447676) (xy 35.680904 -315.940694) (xy 36.297362 -315.940694) (xy 36.297362 -317.447676)
			)
		)
	)
	(zone
		(layer "In6.Cu")
		(hatch none 0.5)
		(connect_pads
			(clearance 0)
		)
		(min_thickness 0.25)
		(keepout
			(tracks allowed)
			(vias allowed)
			(pads allowed)
			(copperpour allowed)
			(footprints allowed)
		)
		(placement
			(enabled no)
			(sheetname "")
		)
		(fill
			(thermal_gap 0.5)
			(thermal_bridge_width 0.5)
			(island_removal_mode 0)
		)
		(polygon
			(pts
				(xy 35.725608 -222.206312) (xy 35.725608 -220.884242) (xy 36.253166 -220.884242) (xy 36.253166 -222.206312)
			)
		)
	)
	(zone
		(layer "In6.Cu")
		(hatch none 0.5)
		(connect_pads
			(clearance 0)
		)
		(min_thickness 0.25)
		(keepout
			(tracks allowed)
			(vias allowed)
			(pads allowed)
			(copperpour allowed)
			(footprints allowed)
		)
		(placement
			(enabled no)
			(sheetname "")
		)
		(fill
			(thermal_gap 0.5)
			(thermal_bridge_width 0.5)
			(island_removal_mode 0)
		)
		(polygon
			(pts
				(xy 435.567582 -281.714702) (xy 435.567582 -280.36266) (xy 436.143146 -280.36266) (xy 436.143146 -281.714702)
			)
		)
	)
	(zone
		(layer "In6.Cu")
		(hatch none 0.5)
		(connect_pads
			(clearance 0)
		)
		(min_thickness 0.25)
		(keepout
			(tracks allowed)
			(vias allowed)
			(pads allowed)
			(copperpour allowed)
			(footprints allowed)
		)
		(placement
			(enabled no)
			(sheetname "")
		)
		(fill
			(thermal_gap 0.5)
			(thermal_bridge_width 0.5)
			(island_removal_mode 0)
		)
		(polygon
			(pts
				(xy 206.840582 -248.55424) (xy 206.840582 -246.362474) (xy 207.416146 -246.362474) (xy 207.416146 -248.55424)
			)
		)
	)
	(zone
		(layer "In6.Cu")
		(hatch none 0.5)
		(connect_pads
			(clearance 0)
		)
		(min_thickness 0.25)
		(keepout
			(tracks allowed)
			(vias allowed)
			(pads allowed)
			(copperpour allowed)
			(footprints allowed)
		)
		(placement
			(enabled no)
			(sheetname "")
		)
		(fill
			(thermal_gap 0.5)
			(thermal_bridge_width 0.5)
			(island_removal_mode 0)
		)
		(polygon
			(pts
				(xy 298.73575 -314.423552) (xy 298.73575 -313.114944) (xy 299.270166 -313.114944) (xy 299.270166 -314.423552)
			)
		)
	)
	(zone
		(layer "In6.Cu")
		(hatch none 0.5)
		(connect_pads
			(clearance 0)
		)
		(min_thickness 0.25)
		(keepout
			(tracks allowed)
			(vias allowed)
			(pads allowed)
			(copperpour allowed)
			(footprints allowed)
		)
		(placement
			(enabled no)
			(sheetname "")
		)
		(fill
			(thermal_gap 0.5)
			(thermal_bridge_width 0.5)
			(island_removal_mode 0)
		)
		(polygon
			(pts
				(xy 35.725608 -200.956418) (xy 35.725608 -199.634348) (xy 36.253166 -199.634348) (xy 36.253166 -200.956418)
				(xy 36.253166 -203.461112) (xy 35.725608 -203.461112)
			)
		)
	)
	(zone
		(layer "In6.Cu")
		(hatch none 0.5)
		(connect_pads
			(clearance 0)
		)
		(min_thickness 0.25)
		(keepout
			(tracks allowed)
			(vias allowed)
			(pads allowed)
			(copperpour allowed)
			(footprints allowed)
		)
		(placement
			(enabled no)
			(sheetname "")
		)
		(fill
			(thermal_gap 0.5)
			(thermal_bridge_width 0.5)
			(island_removal_mode 0)
		)
		(polygon
			(pts
				(xy 424.58005 -311.464452) (xy 424.58005 -305.926998) (xy 425.155614 -305.926998) (xy 425.155614 -311.464452)
			)
		)
	)
	(zone
		(layer "In6.Cu")
		(hatch none 0.5)
		(connect_pads
			(clearance 0)
		)
		(min_thickness 0.25)
		(keepout
			(tracks allowed)
			(vias allowed)
			(pads allowed)
			(copperpour allowed)
			(footprints allowed)
		)
		(placement
			(enabled no)
			(sheetname "")
		)
		(fill
			(thermal_gap 0.5)
			(thermal_bridge_width 0.5)
			(island_removal_mode 0)
		)
		(polygon
			(pts
				(xy 16.53794 -245.156228) (xy 16.53794 -243.834158) (xy 17.065498 -243.834158) (xy 17.065498 -245.156228)
			)
		)
	)
	(zone
		(layer "In6.Cu")
		(hatch none 0.5)
		(connect_pads
			(clearance 0)
		)
		(min_thickness 0.25)
		(keepout
			(tracks allowed)
			(vias allowed)
			(pads allowed)
			(copperpour allowed)
			(footprints allowed)
		)
		(placement
			(enabled no)
			(sheetname "")
		)
		(fill
			(thermal_gap 0.5)
			(thermal_bridge_width 0.5)
			(island_removal_mode 0)
		)
		(polygon
			(pts
				(xy 435.592982 -232.404158) (xy 435.592982 -230.212392) (xy 436.168546 -230.212392) (xy 436.168546 -232.404158)
			)
		)
	)
	(zone
		(layer "In6.Cu")
		(hatch none 0.5)
		(connect_pads
			(clearance 0)
		)
		(min_thickness 0.25)
		(keepout
			(tracks allowed)
			(vias allowed)
			(pads allowed)
			(copperpour allowed)
			(footprints allowed)
		)
		(placement
			(enabled no)
			(sheetname "")
		)
		(fill
			(thermal_gap 0.5)
			(thermal_bridge_width 0.5)
			(island_removal_mode 0)
		)
		(polygon
			(pts
				(xy 454.78065 -248.55424) (xy 454.78065 -246.362474) (xy 455.356214 -246.362474) (xy 455.356214 -248.55424)
			)
		)
	)
	(zone
		(layer "In6.Cu")
		(hatch none 0.5)
		(connect_pads
			(clearance 0)
		)
		(min_thickness 0.25)
		(keepout
			(tracks allowed)
			(vias allowed)
			(pads allowed)
			(copperpour allowed)
			(footprints allowed)
		)
		(placement
			(enabled no)
			(sheetname "")
		)
		(fill
			(thermal_gap 0.5)
			(thermal_bridge_width 0.5)
			(island_removal_mode 0)
		)
		(polygon
			(pts
				(xy 187.627514 -247.714516) (xy 187.627514 -245.561358) (xy 188.203078 -245.561358) (xy 188.203078 -247.714516)
			)
		)
	)
	(zone
		(layer "In6.Cu")
		(hatch none 0.5)
		(connect_pads
			(clearance 0)
		)
		(min_thickness 0.25)
		(keepout
			(tracks allowed)
			(vias allowed)
			(pads allowed)
			(copperpour allowed)
			(footprints allowed)
		)
		(placement
			(enabled no)
			(sheetname "")
		)
		(fill
			(thermal_gap 0.5)
			(thermal_bridge_width 0.5)
			(island_removal_mode 0)
		)
		(polygon
			(pts
				(xy 302.151034 -245.149878) (xy 302.151034 -243.766086) (xy 302.781208 -243.766086) (xy 302.781208 -245.149878)
			)
		)
	)
	(zone
		(layer "In6.Cu")
		(hatch none 0.5)
		(connect_pads
			(clearance 0)
		)
		(min_thickness 0.25)
		(keepout
			(tracks allowed)
			(vias allowed)
			(pads allowed)
			(copperpour allowed)
			(footprints allowed)
		)
		(placement
			(enabled no)
			(sheetname "")
		)
		(fill
			(thermal_gap 0.5)
			(thermal_bridge_width 0.5)
			(island_removal_mode 0)
		)
		(polygon
			(pts
				(xy 35.725608 -246.006366) (xy 35.725608 -244.684296) (xy 36.253166 -244.684296) (xy 36.253166 -246.006366)
			)
		)
	)
	(zone
		(layer "In6.Cu")
		(hatch none 0.5)
		(connect_pads
			(clearance 0)
		)
		(min_thickness 0.25)
		(keepout
			(tracks allowed)
			(vias allowed)
			(pads allowed)
			(copperpour allowed)
			(footprints allowed)
		)
		(placement
			(enabled no)
			(sheetname "")
		)
		(fill
			(thermal_gap 0.5)
			(thermal_bridge_width 0.5)
			(island_removal_mode 0)
		)
		(polygon
			(pts
				(xy 52.70754 -148.689568) (xy 52.70754 -147.544028) (xy 53.93182 -147.544028) (xy 53.93182 -148.689568)
			)
		)
	)
	(zone
		(layer "In6.Cu")
		(hatch none 0.5)
		(connect_pads
			(clearance 0)
		)
		(min_thickness 0.25)
		(keepout
			(tracks allowed)
			(vias allowed)
			(pads allowed)
			(copperpour allowed)
			(footprints allowed)
		)
		(placement
			(enabled no)
			(sheetname "")
		)
		(fill
			(thermal_gap 0.5)
			(thermal_bridge_width 0.5)
			(island_removal_mode 0)
		)
		(polygon
			(pts
				(xy 100.27158 -297.988228) (xy 100.27158 -292.029388) (xy 102.65664 -292.029388) (xy 102.65664 -297.988228)
			)
		)
	)
	(zone
		(layer "In6.Cu")
		(hatch none 0.5)
		(connect_pads
			(clearance 0)
		)
		(min_thickness 0.25)
		(keepout
			(tracks allowed)
			(vias allowed)
			(pads allowed)
			(copperpour allowed)
			(footprints allowed)
		)
		(placement
			(enabled no)
			(sheetname "")
		)
		(fill
			(thermal_gap 0.5)
			(thermal_bridge_width 0.5)
			(island_removal_mode 0)
		)
		(polygon
			(pts
				(xy 333.06004 -341.473028) (xy 333.06004 -338.364068) (xy 337.12912 -338.364068) (xy 337.12912 -341.473028)
			)
		)
	)
	(zone
		(layer "In6.Cu")
		(hatch none 0.5)
		(connect_pads
			(clearance 0)
		)
		(min_thickness 0.25)
		(keepout
			(tracks allowed)
			(vias allowed)
			(pads allowed)
			(copperpour allowed)
			(footprints allowed)
		)
		(placement
			(enabled no)
			(sheetname "")
		)
		(fill
			(thermal_gap 0.5)
			(thermal_bridge_width 0.5)
			(island_removal_mode 0)
		)
		(polygon
			(pts
				(xy 287.012126 -243.478304) (xy 287.012126 -242.08105) (xy 287.697164 -242.08105) (xy 287.697164 -243.478304)
			)
		)
	)
	(zone
		(layer "In6.Cu")
		(hatch none 0.5)
		(connect_pads
			(clearance 0)
		)
		(min_thickness 0.25)
		(keepout
			(tracks allowed)
			(vias allowed)
			(pads allowed)
			(copperpour allowed)
			(footprints allowed)
		)
		(placement
			(enabled no)
			(sheetname "")
		)
		(fill
			(thermal_gap 0.5)
			(thermal_bridge_width 0.5)
			(island_removal_mode 0)
		)
		(polygon
			(pts
				(xy 100.2538 -338.922868) (xy 100.2538 -334.310228) (xy 114.46764 -334.310228) (xy 114.46764 -338.922868)
			)
		)
	)
	(zone
		(layer "In6.Cu")
		(hatch none 0.5)
		(connect_pads
			(clearance 0)
		)
		(min_thickness 0.25)
		(keepout
			(tracks allowed)
			(vias allowed)
			(pads allowed)
			(copperpour allowed)
			(footprints allowed)
		)
		(placement
			(enabled no)
			(sheetname "")
		)
		(fill
			(thermal_gap 0.5)
			(thermal_bridge_width 0.5)
			(island_removal_mode 0)
		)
		(polygon
			(pts
				(xy 283.54274 -289.414966) (xy 283.54274 -287.147508) (xy 284.227778 -287.147508) (xy 284.227778 -289.414966)
			)
		)
	)
	(zone
		(layer "In6.Cu")
		(hatch none 0.5)
		(connect_pads
			(clearance 0)
		)
		(min_thickness 0.25)
		(keepout
			(tracks allowed)
			(vias allowed)
			(pads allowed)
			(copperpour allowed)
			(footprints allowed)
		)
		(placement
			(enabled no)
			(sheetname "")
		)
		(fill
			(thermal_gap 0.5)
			(thermal_bridge_width 0.5)
			(island_removal_mode 0)
		)
		(polygon
			(pts
				(xy 180.4416 -358.188768) (xy 180.4416 -356.931468) (xy 182.17896 -356.931468) (xy 182.17896 -358.188768)
			)
		)
	)
	(zone
		(layer "In6.Cu")
		(hatch none 0.5)
		(connect_pads
			(clearance 0)
		)
		(min_thickness 0.25)
		(keepout
			(tracks allowed)
			(vias allowed)
			(pads allowed)
			(copperpour allowed)
			(footprints allowed)
		)
		(placement
			(enabled no)
			(sheetname "")
		)
		(fill
			(thermal_gap 0.5)
			(thermal_bridge_width 0.5)
			(island_removal_mode 0)
		)
		(polygon
			(pts
				(xy 191.727582 -246.854218) (xy 191.727582 -244.662452) (xy 192.303146 -244.662452) (xy 192.303146 -246.854218)
			)
		)
	)
	(zone
		(layer "In6.Cu")
		(hatch none 0.5)
		(connect_pads
			(clearance 0)
		)
		(min_thickness 0.25)
		(keepout
			(tracks allowed)
			(vias allowed)
			(pads allowed)
			(copperpour allowed)
			(footprints allowed)
		)
		(placement
			(enabled no)
			(sheetname "")
		)
		(fill
			(thermal_gap 0.5)
			(thermal_bridge_width 0.5)
			(island_removal_mode 0)
		)
		(polygon
			(pts
				(xy 46.71314 -243.45646) (xy 46.71314 -242.13439) (xy 47.240698 -242.13439) (xy 47.240698 -243.45646)
			)
		)
	)
	(zone
		(layer "In6.Cu")
		(hatch none 0.5)
		(connect_pads
			(clearance 0)
		)
		(min_thickness 0.25)
		(keepout
			(tracks allowed)
			(vias allowed)
			(pads allowed)
			(copperpour allowed)
			(footprints allowed)
		)
		(placement
			(enabled no)
			(sheetname "")
		)
		(fill
			(thermal_gap 0.5)
			(thermal_bridge_width 0.5)
			(island_removal_mode 0)
		)
		(polygon
			(pts
				(xy 104.04856 -352.232468) (xy 104.04856 -351.338388) (xy 105.61828 -351.338388) (xy 105.61828 -352.232468)
			)
		)
	)
	(zone
		(layer "In6.Cu")
		(hatch none 0.5)
		(connect_pads
			(clearance 0)
		)
		(min_thickness 0.25)
		(keepout
			(tracks allowed)
			(vias allowed)
			(pads allowed)
			(copperpour allowed)
			(footprints allowed)
		)
		(placement
			(enabled no)
			(sheetname "")
		)
		(fill
			(thermal_gap 0.5)
			(thermal_bridge_width 0.5)
			(island_removal_mode 0)
		)
		(polygon
			(pts
				(xy 157.452314 -225.614484) (xy 157.452314 -224.262442) (xy 158.027878 -224.262442) (xy 158.027878 -225.614484)
			)
		)
	)
	(zone
		(layer "In6.Cu")
		(hatch none 0.5)
		(connect_pads
			(clearance 0)
		)
		(min_thickness 0.25)
		(keepout
			(tracks allowed)
			(vias allowed)
			(pads allowed)
			(copperpour allowed)
			(footprints allowed)
		)
		(placement
			(enabled no)
			(sheetname "")
		)
		(fill
			(thermal_gap 0.5)
			(thermal_bridge_width 0.5)
			(island_removal_mode 0)
		)
		(polygon
			(pts
				(xy 187.535566 -201.243438) (xy 187.535566 -197.896226) (xy 188.16574 -197.896226) (xy 188.16574 -201.243438)
			)
		)
	)
	(zone
		(layer "In6.Cu")
		(hatch none 0.5)
		(connect_pads
			(clearance 0)
		)
		(min_thickness 0.25)
		(keepout
			(tracks allowed)
			(vias allowed)
			(pads allowed)
			(copperpour allowed)
			(footprints allowed)
		)
		(placement
			(enabled no)
			(sheetname "")
		)
		(fill
			(thermal_gap 0.5)
			(thermal_bridge_width 0.5)
			(island_removal_mode 0)
		)
		(polygon
			(pts
				(xy 35.602672 -304.71491) (xy 35.602672 -302.447452) (xy 36.28771 -302.447452) (xy 36.28771 -304.71491)
			)
		)
	)
	(zone
		(layer "In6.Cu")
		(hatch none 0.5)
		(connect_pads
			(clearance 0)
		)
		(min_thickness 0.25)
		(keepout
			(tracks allowed)
			(vias allowed)
			(pads allowed)
			(copperpour allowed)
			(footprints allowed)
		)
		(placement
			(enabled no)
			(sheetname "")
		)
		(fill
			(thermal_gap 0.5)
			(thermal_bridge_width 0.5)
			(island_removal_mode 0)
		)
		(polygon
			(pts
				(xy 35.725608 -229.856284) (xy 35.725608 -228.534214) (xy 36.253166 -228.534214) (xy 36.253166 -229.856284)
			)
		)
	)
	(zone
		(layer "In6.Cu")
		(hatch none 0.5)
		(connect_pads
			(clearance 0)
		)
		(min_thickness 0.25)
		(keepout
			(tracks allowed)
			(vias allowed)
			(pads allowed)
			(copperpour allowed)
			(footprints allowed)
		)
		(placement
			(enabled no)
			(sheetname "")
		)
		(fill
			(thermal_gap 0.5)
			(thermal_bridge_width 0.5)
			(island_removal_mode 0)
		)
		(polygon
			(pts
				(xy 435.475634 -201.243438) (xy 435.475634 -197.896226) (xy 436.105808 -197.896226) (xy 436.105808 -201.243438)
			)
		)
	)
	(zone
		(layer "In6.Cu")
		(hatch none 0.5)
		(connect_pads
			(clearance 0)
		)
		(min_thickness 0.25)
		(keepout
			(tracks allowed)
			(vias allowed)
			(pads allowed)
			(copperpour allowed)
			(footprints allowed)
		)
		(placement
			(enabled no)
			(sheetname "")
		)
		(fill
			(thermal_gap 0.5)
			(thermal_bridge_width 0.5)
			(island_removal_mode 0)
		)
		(polygon
			(pts
				(xy 129.813558 -253.038356) (xy 129.813558 -252.517656) (xy 130.537204 -251.79401) (xy 142.785338 -251.79401)
				(xy 142.823438 -251.75591) (xy 142.947898 -251.75591) (xy 144.840198 -249.86361) (xy 147.872958 -249.86361)
				(xy 148.817838 -248.91873) (xy 148.817838 -247.69445) (xy 148.769578 -247.64619) (xy 143.458184 -247.64619)
				(xy 140.672058 -250.432316) (xy 138.765788 -250.432316) (xy 138.765788 -250.6726) (xy 138.744198 -250.69419)
				(xy 138.617198 -250.69419) (xy 130.014218 -250.69419) (xy 130.002534 -250.682506) (xy 128.796034 -250.682506)
				(xy 127.806958 -251.671836) (xy 127.806958 -253.581916) (xy 128.408938 -254.183896) (xy 128.615694 -254.183896)
				(xy 128.925066 -253.874524) (xy 128.925066 -253.58852) (xy 128.839468 -253.502922) (xy 128.839468 -253.119128)
				(xy 128.92024 -253.038356)
			)
		)
	)
	(zone
		(layer "In6.Cu")
		(hatch none 0.5)
		(connect_pads
			(clearance 0)
		)
		(min_thickness 0.25)
		(keepout
			(tracks allowed)
			(vias allowed)
			(pads allowed)
			(copperpour allowed)
			(footprints allowed)
		)
		(placement
			(enabled no)
			(sheetname "")
		)
		(fill
			(thermal_gap 0.5)
			(thermal_bridge_width 0.5)
			(island_removal_mode 0)
		)
		(polygon
			(pts
				(xy 303.945798 -243.437156) (xy 303.945798 -241.3) (xy 304.699162 -241.3) (xy 304.699162 -243.437156)
			)
		)
	)
	(zone
		(layer "In6.Cu")
		(hatch none 0.5)
		(connect_pads
			(clearance 0)
		)
		(min_thickness 0.25)
		(keepout
			(tracks allowed)
			(vias allowed)
			(pads allowed)
			(copperpour allowed)
			(footprints allowed)
		)
		(placement
			(enabled no)
			(sheetname "")
		)
		(fill
			(thermal_gap 0.5)
			(thermal_bridge_width 0.5)
			(island_removal_mode 0)
		)
		(polygon
			(pts
				(xy 268.578076 -211.156296) (xy 268.578076 -209.834226) (xy 269.105634 -209.834226) (xy 269.105634 -211.156296)
			)
		)
	)
	(zone
		(layer "In6.Cu")
		(hatch none 0.5)
		(connect_pads
			(clearance 0)
		)
		(min_thickness 0.25)
		(keepout
			(tracks allowed)
			(vias allowed)
			(pads allowed)
			(copperpour allowed)
			(footprints allowed)
		)
		(placement
			(enabled no)
			(sheetname "")
		)
		(fill
			(thermal_gap 0.5)
			(thermal_bridge_width 0.5)
			(island_removal_mode 0)
		)
		(polygon
			(pts
				(xy 157.452314 -229.864666) (xy 157.452314 -228.512624) (xy 158.027878 -228.512624) (xy 158.027878 -229.864666)
			)
		)
	)
	(zone
		(layer "In6.Cu")
		(hatch none 0.5)
		(connect_pads
			(clearance 0)
		)
		(min_thickness 0.25)
		(keepout
			(tracks allowed)
			(vias allowed)
			(pads allowed)
			(copperpour allowed)
			(footprints allowed)
		)
		(placement
			(enabled no)
			(sheetname "")
		)
		(fill
			(thermal_gap 0.5)
			(thermal_bridge_width 0.5)
			(island_removal_mode 0)
		)
		(polygon
			(pts
				(xy 61.834522 -307.570632) (xy 61.834522 -306.262024) (xy 62.368938 -306.262024) (xy 62.368938 -307.570632)
			)
		)
	)
	(zone
		(layer "In6.Cu")
		(hatch none 0.5)
		(connect_pads
			(clearance 0)
		)
		(min_thickness 0.25)
		(keepout
			(tracks allowed)
			(vias allowed)
			(pads allowed)
			(copperpour allowed)
			(footprints allowed)
		)
		(placement
			(enabled no)
			(sheetname "")
		)
		(fill
			(thermal_gap 0.5)
			(thermal_bridge_width 0.5)
			(island_removal_mode 0)
		)
		(polygon
			(pts
				(xy 79.29372 -347.868748) (xy 79.29372 -346.497148) (xy 80.59166 -346.497148) (xy 80.59166 -347.868748)
			)
		)
	)
	(zone
		(layer "In6.Cu")
		(hatch none 0.5)
		(connect_pads
			(clearance 0)
		)
		(min_thickness 0.25)
		(keepout
			(tracks allowed)
			(vias allowed)
			(pads allowed)
			(copperpour allowed)
			(footprints allowed)
		)
		(placement
			(enabled no)
			(sheetname "")
		)
		(fill
			(thermal_gap 0.5)
			(thermal_bridge_width 0.5)
			(island_removal_mode 0)
		)
		(polygon
			(pts
				(xy 420.479982 -243.464588) (xy 420.479982 -242.112546) (xy 421.055546 -242.112546) (xy 421.055546 -243.464588)
			)
		)
	)
	(zone
		(layer "In6.Cu")
		(hatch none 0.5)
		(connect_pads
			(clearance 0)
		)
		(min_thickness 0.25)
		(keepout
			(tracks allowed)
			(vias allowed)
			(pads allowed)
			(copperpour allowed)
			(footprints allowed)
		)
		(placement
			(enabled no)
			(sheetname "")
		)
		(fill
			(thermal_gap 0.5)
			(thermal_bridge_width 0.5)
			(island_removal_mode 0)
		)
		(polygon
			(pts
				(xy 283.665676 -216.256362) (xy 283.665676 -214.934292) (xy 284.193234 -214.934292) (xy 284.193234 -216.256362)
			)
		)
	)
	(zone
		(layer "In6.Cu")
		(hatch none 0.5)
		(connect_pads
			(clearance 0)
		)
		(min_thickness 0.25)
		(keepout
			(tracks allowed)
			(vias allowed)
			(pads allowed)
			(copperpour allowed)
			(footprints allowed)
		)
		(placement
			(enabled no)
			(sheetname "")
		)
		(fill
			(thermal_gap 0.5)
			(thermal_bridge_width 0.5)
			(island_removal_mode 0)
		)
		(polygon
			(pts
				(xy 35.725608 -219.656406) (xy 35.725608 -218.334336) (xy 36.253166 -218.334336) (xy 36.253166 -219.656406)
			)
		)
	)
	(zone
		(layer "In6.Cu")
		(hatch none 0.5)
		(connect_pads
			(clearance 0)
		)
		(min_thickness 0.25)
		(keepout
			(tracks allowed)
			(vias allowed)
			(pads allowed)
			(copperpour allowed)
			(footprints allowed)
		)
		(placement
			(enabled no)
			(sheetname "")
		)
		(fill
			(thermal_gap 0.5)
			(thermal_bridge_width 0.5)
			(island_removal_mode 0)
		)
		(polygon
			(pts
				(xy 35.725608 -227.306378) (xy 35.725608 -225.984308) (xy 36.253166 -225.984308) (xy 36.253166 -227.306378)
			)
		)
	)
	(zone
		(layer "In6.Cu")
		(hatch none 0.5)
		(connect_pads
			(clearance 0)
		)
		(min_thickness 0.25)
		(keepout
			(tracks allowed)
			(vias allowed)
			(pads allowed)
			(copperpour allowed)
			(footprints allowed)
		)
		(placement
			(enabled no)
			(sheetname "")
		)
		(fill
			(thermal_gap 0.5)
			(thermal_bridge_width 0.5)
			(island_removal_mode 0)
		)
		(polygon
			(pts
				(xy 50.813208 -248.556272) (xy 50.813208 -247.234202) (xy 51.340766 -247.234202) (xy 51.340766 -248.556272)
			)
		)
	)
	(zone
		(layer "In6.Cu")
		(hatch none 0.5)
		(connect_pads
			(clearance 0)
		)
		(min_thickness 0.25)
		(keepout
			(tracks allowed)
			(vias allowed)
			(pads allowed)
			(copperpour allowed)
			(footprints allowed)
		)
		(placement
			(enabled no)
			(sheetname "")
		)
		(fill
			(thermal_gap 0.5)
			(thermal_bridge_width 0.5)
			(island_removal_mode 0)
		)
		(polygon
			(pts
				(xy 450.655182 -312.302398) (xy 450.655182 -309.351426) (xy 450.572886 -309.351426) (xy 450.572886 -308.412642)
				(xy 450.572886 -308.082442) (xy 451.230746 -308.082442) (xy 451.230746 -308.412642) (xy 451.230746 -312.302398)
			)
		)
	)
	(zone
		(layer "In6.Cu")
		(hatch none 0.5)
		(connect_pads
			(clearance 0)
		)
		(min_thickness 0.25)
		(keepout
			(tracks allowed)
			(vias allowed)
			(pads allowed)
			(copperpour allowed)
			(footprints allowed)
		)
		(placement
			(enabled no)
			(sheetname "")
		)
		(fill
			(thermal_gap 0.5)
			(thermal_bridge_width 0.5)
			(island_removal_mode 0)
		)
		(polygon
			(pts
				(xy 176.548034 -207.118458) (xy 176.548034 -204.696314) (xy 177.178208 -204.696314) (xy 177.178208 -207.118458)
			)
		)
	)
	(zone
		(layer "In6.Cu")
		(hatch none 0.5)
		(connect_pads
			(clearance 0)
		)
		(min_thickness 0.25)
		(keepout
			(tracks allowed)
			(vias allowed)
			(pads allowed)
			(copperpour allowed)
			(footprints allowed)
		)
		(placement
			(enabled no)
			(sheetname "")
		)
		(fill
			(thermal_gap 0.5)
			(thermal_bridge_width 0.5)
			(island_removal_mode 0)
		)
		(polygon
			(pts
				(xy 298.753276 -248.556272) (xy 298.753276 -247.234202) (xy 299.280834 -247.234202) (xy 299.280834 -248.556272)
			)
		)
	)
	(zone
		(layer "In6.Cu")
		(hatch none 0.5)
		(connect_pads
			(clearance 0)
		)
		(min_thickness 0.25)
		(keepout
			(tracks allowed)
			(vias allowed)
			(pads allowed)
			(copperpour allowed)
			(footprints allowed)
		)
		(placement
			(enabled no)
			(sheetname "")
		)
		(fill
			(thermal_gap 0.5)
			(thermal_bridge_width 0.5)
			(island_removal_mode 0)
		)
		(polygon
			(pts
				(xy 161.526982 -231.564688) (xy 161.526982 -230.212646) (xy 162.102546 -230.212646) (xy 162.102546 -231.564688)
			)
		)
	)
	(zone
		(layer "In6.Cu")
		(hatch none 0.5)
		(connect_pads
			(clearance 0)
		)
		(min_thickness 0.25)
		(keepout
			(tracks allowed)
			(vias allowed)
			(pads allowed)
			(copperpour allowed)
			(footprints allowed)
		)
		(placement
			(enabled no)
			(sheetname "")
		)
		(fill
			(thermal_gap 0.5)
			(thermal_bridge_width 0.5)
			(island_removal_mode 0)
		)
		(polygon
			(pts
				(xy 20.638008 -210.306412) (xy 20.638008 -208.984342) (xy 21.165566 -208.984342) (xy 21.165566 -210.306412)
			)
		)
	)
	(zone
		(layer "In6.Cu")
		(hatch none 0.5)
		(connect_pads
			(clearance 0)
		)
		(min_thickness 0.25)
		(keepout
			(tracks allowed)
			(vias allowed)
			(pads allowed)
			(copperpour allowed)
			(footprints allowed)
		)
		(placement
			(enabled no)
			(sheetname "")
		)
		(fill
			(thermal_gap 0.5)
			(thermal_bridge_width 0.5)
			(island_removal_mode 0)
		)
		(polygon
			(pts
				(xy 20.638008 -314.00623) (xy 20.638008 -312.68416) (xy 21.165566 -312.68416) (xy 21.165566 -314.00623)
			)
		)
	)
	(zone
		(layer "In6.Cu")
		(hatch none 0.5)
		(connect_pads
			(clearance 0)
		)
		(min_thickness 0.25)
		(keepout
			(tracks allowed)
			(vias allowed)
			(pads allowed)
			(copperpour allowed)
			(footprints allowed)
		)
		(placement
			(enabled no)
			(sheetname "")
		)
		(fill
			(thermal_gap 0.5)
			(thermal_bridge_width 0.5)
			(island_removal_mode 0)
		)
		(polygon
			(pts
				(xy 291.122354 -243.382546) (xy 291.122354 -241.272568) (xy 291.821108 -241.272568) (xy 291.821108 -243.382546)
			)
		)
	)
	(zone
		(layer "In6.Cu")
		(hatch none 0.5)
		(connect_pads
			(clearance 0)
		)
		(min_thickness 0.25)
		(keepout
			(tracks allowed)
			(vias allowed)
			(pads allowed)
			(copperpour allowed)
			(footprints allowed)
		)
		(placement
			(enabled no)
			(sheetname "")
		)
		(fill
			(thermal_gap 0.5)
			(thermal_bridge_width 0.5)
			(island_removal_mode 0)
		)
		(polygon
			(pts
				(xy 372.9863 -341.531448) (xy 372.9863 -339.819488) (xy 377.81992 -339.819488) (xy 377.81992 -341.531448)
			)
		)
	)
	(zone
		(layer "In6.Cu")
		(hatch none 0.5)
		(connect_pads
			(clearance 0)
		)
		(min_thickness 0.25)
		(keepout
			(tracks allowed)
			(vias allowed)
			(pads allowed)
			(copperpour allowed)
			(footprints allowed)
		)
		(placement
			(enabled no)
			(sheetname "")
		)
		(fill
			(thermal_gap 0.5)
			(thermal_bridge_width 0.5)
			(island_removal_mode 0)
		)
		(polygon
			(pts
				(xy 61.80074 -243.464842) (xy 61.80074 -242.163346) (xy 62.376304 -242.163346) (xy 62.376304 -243.464842)
			)
		)
	)
	(zone
		(layer "In6.Cu")
		(hatch none 0.5)
		(connect_pads
			(clearance 0)
		)
		(min_thickness 0.25)
		(keepout
			(tracks allowed)
			(vias allowed)
			(pads allowed)
			(copperpour allowed)
			(footprints allowed)
		)
		(placement
			(enabled no)
			(sheetname "")
		)
		(fill
			(thermal_gap 0.5)
			(thermal_bridge_width 0.5)
			(island_removal_mode 0)
		)
		(polygon
			(pts
				(xy 8.52678 -92.62872) (xy 8.52678 -91.4019) (xy 11.0617 -91.4019) (xy 11.0617 -92.62872)
			)
		)
	)
	(zone
		(layer "In6.Cu")
		(hatch none 0.5)
		(connect_pads
			(clearance 0)
		)
		(min_thickness 0.25)
		(keepout
			(tracks allowed)
			(vias allowed)
			(pads allowed)
			(copperpour allowed)
			(footprints allowed)
		)
		(placement
			(enabled no)
			(sheetname "")
		)
		(fill
			(thermal_gap 0.5)
			(thermal_bridge_width 0.5)
			(island_removal_mode 0)
		)
		(polygon
			(pts
				(xy 20.638008 -315.706252) (xy 20.638008 -314.384182) (xy 21.165566 -314.384182) (xy 21.165566 -315.706252)
			)
		)
	)
	(zone
		(layer "In6.Cu")
		(hatch none 0.5)
		(connect_pads
			(clearance 0)
		)
		(min_thickness 0.25)
		(keepout
			(tracks allowed)
			(vias allowed)
			(pads allowed)
			(copperpour allowed)
			(footprints allowed)
		)
		(placement
			(enabled no)
			(sheetname "")
		)
		(fill
			(thermal_gap 0.5)
			(thermal_bridge_width 0.5)
			(island_removal_mode 0)
		)
		(polygon
			(pts
				(xy 187.535566 -203.502768) (xy 187.535566 -202.146408) (xy 188.16574 -202.146408) (xy 188.16574 -203.502768)
			)
		)
	)
	(zone
		(layer "In6.Cu")
		(hatch none 0.5)
		(connect_pads
			(clearance 0)
		)
		(min_thickness 0.25)
		(keepout
			(tracks allowed)
			(vias allowed)
			(pads allowed)
			(copperpour allowed)
			(footprints allowed)
		)
		(placement
			(enabled no)
			(sheetname "")
		)
		(fill
			(thermal_gap 0.5)
			(thermal_bridge_width 0.5)
			(island_removal_mode 0)
		)
		(polygon
			(pts
				(xy 283.54274 -269.014956) (xy 283.54274 -266.747498) (xy 284.227778 -266.747498) (xy 284.227778 -269.014956)
			)
		)
	)
	(zone
		(layer "In6.Cu")
		(hatch none 0.5)
		(connect_pads
			(clearance 0)
		)
		(min_thickness 0.25)
		(keepout
			(tracks allowed)
			(vias allowed)
			(pads allowed)
			(copperpour allowed)
			(footprints allowed)
		)
		(placement
			(enabled no)
			(sheetname "")
		)
		(fill
			(thermal_gap 0.5)
			(thermal_bridge_width 0.5)
			(island_removal_mode 0)
		)
		(polygon
			(pts
				(xy 425.8818 -129.301748) (xy 431.4444 -129.301748) (xy 432.1302 -128.615948) (xy 432.1302 -126.583948)
				(xy 430.3268 -124.780548) (xy 430.3268 -120.995948) (xy 431.2666 -120.056148) (xy 431.2666 -119.217948)
				(xy 431.038 -118.989348) (xy 425.7802 -118.989348) (xy 425.6786 -119.090948) (xy 425.6786 -129.022348)
				(xy 425.8818 -129.225548)
			)
		)
	)
	(zone
		(layer "In6.Cu")
		(hatch none 0.5)
		(connect_pads
			(clearance 0)
		)
		(min_thickness 0.25)
		(keepout
			(tracks allowed)
			(vias allowed)
			(pads allowed)
			(copperpour allowed)
			(footprints allowed)
		)
		(placement
			(enabled no)
			(sheetname "")
		)
		(fill
			(thermal_gap 0.5)
			(thermal_bridge_width 0.5)
			(island_removal_mode 0)
		)
		(polygon
			(pts
				(xy 435.567582 -272.364708) (xy 435.567582 -271.012666) (xy 436.143146 -271.012666) (xy 436.143146 -272.364708)
			)
		)
	)
	(zone
		(layer "In6.Cu")
		(hatch none 0.5)
		(connect_pads
			(clearance 0)
		)
		(min_thickness 0.25)
		(keepout
			(tracks allowed)
			(vias allowed)
			(pads allowed)
			(copperpour allowed)
			(footprints allowed)
		)
		(placement
			(enabled no)
			(sheetname "")
		)
		(fill
			(thermal_gap 0.5)
			(thermal_bridge_width 0.5)
			(island_removal_mode 0)
		)
		(polygon
			(pts
				(xy 405.392382 -229.864666) (xy 405.392382 -228.512624) (xy 405.967946 -228.512624) (xy 405.967946 -229.864666)
			)
		)
	)
	(zone
		(layer "In6.Cu")
		(hatch none 0.5)
		(connect_pads
			(clearance 0)
		)
		(min_thickness 0.25)
		(keepout
			(tracks allowed)
			(vias allowed)
			(pads allowed)
			(copperpour allowed)
			(footprints allowed)
		)
		(placement
			(enabled no)
			(sheetname "")
		)
		(fill
			(thermal_gap 0.5)
			(thermal_bridge_width 0.5)
			(island_removal_mode 0)
		)
		(polygon
			(pts
				(xy 8.99414 -246.006366) (xy 8.99414 -244.684296) (xy 9.521698 -244.684296) (xy 9.521698 -246.006366)
			)
		)
	)
	(zone
		(layer "In6.Cu")
		(hatch none 0.5)
		(connect_pads
			(clearance 0)
		)
		(min_thickness 0.25)
		(keepout
			(tracks allowed)
			(vias allowed)
			(pads allowed)
			(copperpour allowed)
			(footprints allowed)
		)
		(placement
			(enabled no)
			(sheetname "")
		)
		(fill
			(thermal_gap 0.5)
			(thermal_bridge_width 0.5)
			(island_removal_mode 0)
		)
		(polygon
			(pts
				(xy 76.0603 -35.9537) (xy 76.0603 -33.22828) (xy 61.34862 -33.22828) (xy 61.34862 -35.9537)
			)
		)
	)
	(zone
		(layer "In6.Cu")
		(hatch none 0.5)
		(connect_pads
			(clearance 0)
		)
		(min_thickness 0.25)
		(keepout
			(tracks allowed)
			(vias allowed)
			(pads allowed)
			(copperpour allowed)
			(footprints allowed)
		)
		(placement
			(enabled no)
			(sheetname "")
		)
		(fill
			(thermal_gap 0.5)
			(thermal_bridge_width 0.5)
			(island_removal_mode 0)
		)
		(polygon
			(pts
				(xy 424.488102 -215.402668) (xy 424.488102 -214.046308) (xy 425.118276 -214.046308) (xy 425.118276 -215.402668)
			)
		)
	)
	(zone
		(layer "In6.Cu")
		(hatch none 0.5)
		(connect_pads
			(clearance 0)
		)
		(min_thickness 0.25)
		(keepout
			(tracks allowed)
			(vias allowed)
			(pads allowed)
			(copperpour allowed)
			(footprints allowed)
		)
		(placement
			(enabled no)
			(sheetname "")
		)
		(fill
			(thermal_gap 0.5)
			(thermal_bridge_width 0.5)
			(island_removal_mode 0)
		)
		(polygon
			(pts
				(xy 283.54274 -288.564828) (xy 283.54274 -286.29737) (xy 284.227778 -286.29737) (xy 284.227778 -288.564828)
			)
		)
	)
	(zone
		(layer "In6.Cu")
		(hatch none 0.5)
		(connect_pads
			(clearance 0)
		)
		(min_thickness 0.25)
		(keepout
			(tracks allowed)
			(vias allowed)
			(pads allowed)
			(copperpour allowed)
			(footprints allowed)
		)
		(placement
			(enabled no)
			(sheetname "")
		)
		(fill
			(thermal_gap 0.5)
			(thermal_bridge_width 0.5)
			(island_removal_mode 0)
		)
		(polygon
			(pts
				(xy 49.99736 -358.374188) (xy 49.99736 -357.546148) (xy 51.55184 -357.546148) (xy 51.55184 -358.374188)
			)
		)
	)
	(zone
		(layer "In6.Cu")
		(hatch none 0.5)
		(connect_pads
			(clearance 0)
		)
		(min_thickness 0.25)
		(keepout
			(tracks allowed)
			(vias allowed)
			(pads allowed)
			(copperpour allowed)
			(footprints allowed)
		)
		(placement
			(enabled no)
			(sheetname "")
		)
		(fill
			(thermal_gap 0.5)
			(thermal_bridge_width 0.5)
			(island_removal_mode 0)
		)
		(polygon
			(pts
				(xy 328.203814 -257.328416) (xy 327.513188 -258.019042) (xy 325.460614 -258.019042) (xy 325.382382 -257.94081)
				(xy 325.382382 -257.750564) (xy 325.653146 -257.4798) (xy 325.814182 -257.4798) (xy 325.861934 -257.432048)
				(xy 325.861934 -257.189224) (xy 326.08266 -256.968498) (xy 326.174354 -256.968498) (xy 326.288654 -256.854198)
				(xy 326.288654 -256.530602) (xy 326.380602 -256.438654) (xy 326.757538 -256.438654) (xy 326.869552 -256.32664)
				(xy 326.869552 -256.048764) (xy 326.189086 -256.048764) (xy 326.189086 -255.547622) (xy 323.902578 -255.547622)
				(xy 323.883782 -255.528826) (xy 323.652896 -255.528826) (xy 323.471286 -255.347216) (xy 323.471286 -254.674878)
				(xy 323.590158 -254.556006) (xy 323.98716 -254.556006) (xy 324.075552 -254.644398) (xy 324.35419 -254.36576)
				(xy 324.35419 -254.328422) (xy 324.584822 -254.09779) (xy 324.932802 -254.09779) (xy 324.932802 -251.25553)
				(xy 324.739254 -251.449078) (xy 323.296026 -251.449078) (xy 322.907406 -251.837698) (xy 322.655692 -251.585984)
				(xy 322.655692 -250.862846) (xy 322.83908 -250.679458) (xy 322.83908 -250.11253) (xy 322.93687 -250.01474)
				(xy 322.93687 -249.514868) (xy 322.845176 -249.423174) (xy 322.555362 -249.423174) (xy 322.190618 -249.787918)
				(xy 320.94424 -249.787918) (xy 320.94424 -248.578878) (xy 321.36334 -248.159778) (xy 321.892168 -247.63095)
				(xy 321.892168 -247.28551) (xy 321.820286 -247.28551) (xy 321.548252 -247.013476) (xy 321.548252 -246.81053)
				(xy 321.259962 -246.52224) (xy 320.459354 -245.721632) (xy 320.459354 -244.712998) (xy 320.459354 -244.557804)
				(xy 320.459354 -244.3099) (xy 320.510408 -244.258846) (xy 320.758312 -244.258846) (xy 328.99985 -244.258846)
				(xy 329.148948 -244.407944) (xy 329.77582 -245.034816) (xy 330.973684 -245.034562) (xy 330.973684 -246.777764)
				(xy 331.038454 -246.842534) (xy 331.228446 -246.842534) (xy 331.25918 -246.873268) (xy 331.25918 -250.408694)
				(xy 331.371448 -250.520962) (xy 331.460602 -250.520962) (xy 336.108802 -250.520962) (xy 336.108802 -252.571504)
				(xy 332.760066 -252.571504) (xy 332.048104 -252.571504) (xy 331.990446 -252.629162) (xy 329.631802 -252.629416)
				(xy 329.631802 -255.118616) (xy 329.073002 -255.118616) (xy 329.073002 -257.328416)
			)
		)
	)
	(zone
		(layer "In6.Cu")
		(hatch none 0.5)
		(connect_pads
			(clearance 0)
		)
		(min_thickness 0.25)
		(keepout
			(tracks allowed)
			(vias allowed)
			(pads allowed)
			(copperpour allowed)
			(footprints allowed)
		)
		(placement
			(enabled no)
			(sheetname "")
		)
		(fill
			(thermal_gap 0.5)
			(thermal_bridge_width 0.5)
			(island_removal_mode 0)
		)
		(polygon
			(pts
				(xy 188.203078 -278.662638) (xy 188.203078 -280.01468) (xy 187.627514 -280.01468) (xy 187.546234 -280.01468)
				(xy 187.546234 -278.398478) (xy 188.203078 -278.398478) (xy 188.203078 -278.512778)
			)
		)
	)
	(zone
		(layer "In6.Cu")
		(hatch none 0.5)
		(connect_pads
			(clearance 0)
		)
		(min_thickness 0.25)
		(keepout
			(tracks allowed)
			(vias allowed)
			(pads allowed)
			(copperpour allowed)
			(footprints allowed)
		)
		(placement
			(enabled no)
			(sheetname "")
		)
		(fill
			(thermal_gap 0.5)
			(thermal_bridge_width 0.5)
			(island_removal_mode 0)
		)
		(polygon
			(pts
				(xy 283.54274 -307.264816) (xy 283.54274 -304.997358) (xy 284.227778 -304.997358) (xy 284.227778 -307.264816)
				(xy 284.227778 -308.065932) (xy 283.54274 -308.065932)
			)
		)
	)
	(zone
		(layer "In6.Cu")
		(hatch none 0.5)
		(connect_pads
			(clearance 0)
		)
		(min_thickness 0.25)
		(keepout
			(tracks allowed)
			(vias allowed)
			(pads allowed)
			(copperpour allowed)
			(footprints allowed)
		)
		(placement
			(enabled no)
			(sheetname "")
		)
		(fill
			(thermal_gap 0.5)
			(thermal_bridge_width 0.5)
			(island_removal_mode 0)
		)
		(polygon
			(pts
				(xy 157.426914 -232.414572) (xy 157.426914 -231.06253) (xy 158.002478 -231.06253) (xy 158.002478 -232.414572)
			)
		)
	)
	(zone
		(layer "In6.Cu")
		(hatch none 0.5)
		(connect_pads
			(clearance 0)
		)
		(min_thickness 0.25)
		(keepout
			(tracks allowed)
			(vias allowed)
			(pads allowed)
			(copperpour allowed)
			(footprints allowed)
		)
		(placement
			(enabled no)
			(sheetname "")
		)
		(fill
			(thermal_gap 0.5)
			(thermal_bridge_width 0.5)
			(island_removal_mode 0)
		)
		(polygon
			(pts
				(xy 435.592982 -224.944178) (xy 435.592982 -223.412304) (xy 436.168546 -223.412304) (xy 436.168546 -224.944178)
			)
		)
	)
	(zone
		(layer "In6.Cu")
		(hatch none 0.5)
		(connect_pads
			(clearance 0)
		)
		(min_thickness 0.25)
		(keepout
			(tracks allowed)
			(vias allowed)
			(pads allowed)
			(copperpour allowed)
			(footprints allowed)
		)
		(placement
			(enabled no)
			(sheetname "")
		)
		(fill
			(thermal_gap 0.5)
			(thermal_bridge_width 0.5)
			(island_removal_mode 0)
		)
		(polygon
			(pts
				(xy 187.627514 -281.714702) (xy 187.627514 -280.36266) (xy 188.203078 -280.36266) (xy 188.203078 -281.714702)
			)
		)
	)
	(zone
		(layer "In6.Cu")
		(hatch none 0.5)
		(connect_pads
			(clearance 0)
		)
		(min_thickness 0.25)
		(keepout
			(tracks allowed)
			(vias allowed)
			(pads allowed)
			(copperpour allowed)
			(footprints allowed)
		)
		(placement
			(enabled no)
			(sheetname "")
		)
		(fill
			(thermal_gap 0.5)
			(thermal_bridge_width 0.5)
			(island_removal_mode 0)
		)
		(polygon
			(pts
				(xy 172.539914 -312.31459) (xy 172.539914 -303.346358) (xy 173.115478 -303.346358) (xy 173.115478 -312.31459)
			)
		)
	)
	(zone
		(layer "In6.Cu")
		(hatch none 0.5)
		(connect_pads
			(clearance 0)
		)
		(min_thickness 0.25)
		(keepout
			(tracks allowed)
			(vias allowed)
			(pads allowed)
			(copperpour allowed)
			(footprints allowed)
		)
		(placement
			(enabled no)
			(sheetname "")
		)
		(fill
			(thermal_gap 0.5)
			(thermal_bridge_width 0.5)
			(island_removal_mode 0)
		)
		(polygon
			(pts
				(xy 405.366982 -232.414572) (xy 405.366982 -231.06253) (xy 405.942546 -231.06253) (xy 405.942546 -232.414572)
			)
		)
	)
	(zone
		(layer "In6.Cu")
		(hatch none 0.5)
		(connect_pads
			(clearance 0)
		)
		(min_thickness 0.25)
		(keepout
			(tracks allowed)
			(vias allowed)
			(pads allowed)
			(copperpour allowed)
			(footprints allowed)
		)
		(placement
			(enabled no)
			(sheetname "")
		)
		(fill
			(thermal_gap 0.5)
			(thermal_bridge_width 0.5)
			(island_removal_mode 0)
		)
		(polygon
			(pts
				(xy 283.665676 -225.606356) (xy 283.665676 -224.284286) (xy 284.193234 -224.284286) (xy 284.193234 -225.606356)
			)
		)
	)
	(zone
		(layer "In6.Cu")
		(hatch none 0.5)
		(connect_pads
			(clearance 0)
		)
		(min_thickness 0.25)
		(keepout
			(tracks allowed)
			(vias allowed)
			(pads allowed)
			(copperpour allowed)
			(footprints allowed)
		)
		(placement
			(enabled no)
			(sheetname "")
		)
		(fill
			(thermal_gap 0.5)
			(thermal_bridge_width 0.5)
			(island_removal_mode 0)
		)
		(polygon
			(pts
				(xy 420.479982 -246.864632) (xy 420.479982 -245.51259) (xy 421.055546 -245.51259) (xy 421.055546 -246.864632)
			)
		)
	)
	(zone
		(layer "In6.Cu")
		(hatch none 0.5)
		(connect_pads
			(clearance 0)
		)
		(min_thickness 0.25)
		(keepout
			(tracks allowed)
			(vias allowed)
			(pads allowed)
			(copperpour allowed)
			(footprints allowed)
		)
		(placement
			(enabled no)
			(sheetname "")
		)
		(fill
			(thermal_gap 0.5)
			(thermal_bridge_width 0.5)
			(island_removal_mode 0)
		)
		(polygon
			(pts
				(xy 44.415202 -195.732146) (xy 44.415202 -194.512946) (xy 45.03166 -194.512946) (xy 45.03166 -195.732146)
			)
		)
	)
	(zone
		(layer "In6.Cu")
		(hatch none 0.5)
		(connect_pads
			(clearance 0)
		)
		(min_thickness 0.25)
		(keepout
			(tracks allowed)
			(vias allowed)
			(pads allowed)
			(copperpour allowed)
			(footprints allowed)
		)
		(placement
			(enabled no)
			(sheetname "")
		)
		(fill
			(thermal_gap 0.5)
			(thermal_bridge_width 0.5)
			(island_removal_mode 0)
		)
		(polygon
			(pts
				(xy 187.652914 -224.944178) (xy 187.652914 -223.412304) (xy 188.228478 -223.412304) (xy 188.228478 -224.944178)
			)
		)
	)
	(zone
		(layer "In6.Cu")
		(hatch none 0.5)
		(connect_pads
			(clearance 0)
		)
		(min_thickness 0.25)
		(keepout
			(tracks allowed)
			(vias allowed)
			(pads allowed)
			(copperpour allowed)
			(footprints allowed)
		)
		(placement
			(enabled no)
			(sheetname "")
		)
		(fill
			(thermal_gap 0.5)
			(thermal_bridge_width 0.5)
			(island_removal_mode 0)
		)
		(polygon
			(pts
				(xy 187.652914 -223.054164) (xy 187.652914 -221.760796) (xy 187.147708 -221.760796) (xy 187.147708 -220.586046)
				(xy 187.652914 -220.586046) (xy 187.652914 -216.244678) (xy 188.228478 -216.244678) (xy 188.228478 -220.862398)
				(xy 188.228478 -223.054164)
			)
		)
	)
	(zone
		(layer "In6.Cu")
		(hatch none 0.5)
		(connect_pads
			(clearance 0)
		)
		(min_thickness 0.25)
		(keepout
			(tracks allowed)
			(vias allowed)
			(pads allowed)
			(copperpour allowed)
			(footprints allowed)
		)
		(placement
			(enabled no)
			(sheetname "")
		)
		(fill
			(thermal_gap 0.5)
			(thermal_bridge_width 0.5)
			(island_removal_mode 0)
		)
		(polygon
			(pts
				(xy 326.76338 -348.003368) (xy 326.76338 -346.217748) (xy 329.19924 -346.217748) (xy 329.19924 -348.003368)
			)
		)
	)
	(zone
		(layer "In6.Cu")
		(hatch none 0.5)
		(connect_pads
			(clearance 0)
		)
		(min_thickness 0.25)
		(keepout
			(tracks allowed)
			(vias allowed)
			(pads allowed)
			(copperpour allowed)
			(footprints allowed)
		)
		(placement
			(enabled no)
			(sheetname "")
		)
		(fill
			(thermal_gap 0.5)
			(thermal_bridge_width 0.5)
			(island_removal_mode 0)
		)
		(polygon
			(pts
				(xy 35.725608 -216.256362) (xy 35.725608 -214.934292) (xy 36.253166 -214.934292) (xy 36.253166 -216.256362)
			)
		)
	)
	(zone
		(layer "In6.Cu")
		(hatch none 0.5)
		(connect_pads
			(clearance 0)
		)
		(min_thickness 0.25)
		(keepout
			(tracks allowed)
			(vias allowed)
			(pads allowed)
			(copperpour allowed)
			(footprints allowed)
		)
		(placement
			(enabled no)
			(sheetname "")
		)
		(fill
			(thermal_gap 0.5)
			(thermal_bridge_width 0.5)
			(island_removal_mode 0)
		)
		(polygon
			(pts
				(xy 88.2269 -34.671) (xy 88.2269 -33.19018) (xy 87.09152 -33.19018) (xy 87.09152 -34.671)
			)
		)
	)
	(zone
		(layer "In6.Cu")
		(hatch none 0.5)
		(connect_pads
			(clearance 0)
		)
		(min_thickness 0.25)
		(keepout
			(tracks allowed)
			(vias allowed)
			(pads allowed)
			(copperpour allowed)
			(footprints allowed)
		)
		(placement
			(enabled no)
			(sheetname "")
		)
		(fill
			(thermal_gap 0.5)
			(thermal_bridge_width 0.5)
			(island_removal_mode 0)
		)
		(polygon
			(pts
				(xy 450.680582 -213.894416) (xy 450.680582 -212.362542) (xy 451.256146 -212.362542) (xy 451.256146 -213.894416)
			)
		)
	)
	(zone
		(layer "In6.Cu")
		(hatch none 0.5)
		(connect_pads
			(clearance 0)
		)
		(min_thickness 0.25)
		(keepout
			(tracks allowed)
			(vias allowed)
			(pads allowed)
			(copperpour allowed)
			(footprints allowed)
		)
		(placement
			(enabled no)
			(sheetname "")
		)
		(fill
			(thermal_gap 0.5)
			(thermal_bridge_width 0.5)
			(island_removal_mode 0)
		)
		(polygon
			(pts
				(xy 268.578076 -212.856318) (xy 268.578076 -211.534248) (xy 269.105634 -211.534248) (xy 269.105634 -212.856318)
			)
		)
	)
	(zone
		(layer "In6.Cu")
		(hatch none 0.5)
		(connect_pads
			(clearance 0)
		)
		(min_thickness 0.25)
		(keepout
			(tracks allowed)
			(vias allowed)
			(pads allowed)
			(copperpour allowed)
			(footprints allowed)
		)
		(placement
			(enabled no)
			(sheetname "")
		)
		(fill
			(thermal_gap 0.5)
			(thermal_bridge_width 0.5)
			(island_removal_mode 0)
		)
		(polygon
			(pts
				(xy 65.856358 -232.353612) (xy 65.856358 -223.366076) (xy 66.59626 -223.366076) (xy 66.59626 -232.353612)
			)
		)
	)
	(zone
		(layer "In6.Cu")
		(hatch none 0.5)
		(connect_pads
			(clearance 0)
		)
		(min_thickness 0.25)
		(keepout
			(tracks allowed)
			(vias allowed)
			(pads allowed)
			(copperpour allowed)
			(footprints allowed)
		)
		(placement
			(enabled no)
			(sheetname "")
		)
		(fill
			(thermal_gap 0.5)
			(thermal_bridge_width 0.5)
			(island_removal_mode 0)
		)
		(polygon
			(pts
				(xy 28.001976 -243.464842) (xy 28.001976 -241.272568) (xy 28.782772 -241.272568) (xy 28.782772 -243.464842)
			)
		)
	)
	(zone
		(layer "In6.Cu")
		(hatch none 0.5)
		(connect_pads
			(clearance 0)
		)
		(min_thickness 0.25)
		(keepout
			(tracks allowed)
			(vias allowed)
			(pads allowed)
			(copperpour allowed)
			(footprints allowed)
		)
		(placement
			(enabled no)
			(sheetname "")
		)
		(fill
			(thermal_gap 0.5)
			(thermal_bridge_width 0.5)
			(island_removal_mode 0)
		)
		(polygon
			(pts
				(xy 56.00573 -243.437156) (xy 56.00573 -241.3) (xy 56.759094 -241.3) (xy 56.759094 -243.437156)
			)
		)
	)
	(zone
		(layer "In6.Cu")
		(hatch none 0.5)
		(connect_pads
			(clearance 0)
		)
		(min_thickness 0.25)
		(keepout
			(tracks allowed)
			(vias allowed)
			(pads allowed)
			(copperpour allowed)
			(footprints allowed)
		)
		(placement
			(enabled no)
			(sheetname "")
		)
		(fill
			(thermal_gap 0.5)
			(thermal_bridge_width 0.5)
			(island_removal_mode 0)
		)
		(polygon
			(pts
				(xy 35.602672 -286.864806) (xy 35.602672 -284.597348) (xy 36.28771 -284.597348) (xy 36.28771 -286.864806)
			)
		)
	)
	(zone
		(layer "In6.Cu")
		(hatch none 0.5)
		(connect_pads
			(clearance 0)
		)
		(min_thickness 0.25)
		(keepout
			(tracks allowed)
			(vias allowed)
			(pads allowed)
			(copperpour allowed)
			(footprints allowed)
		)
		(placement
			(enabled no)
			(sheetname "")
		)
		(fill
			(thermal_gap 0.5)
			(thermal_bridge_width 0.5)
			(island_removal_mode 0)
		)
		(polygon
			(pts
				(xy 143.473678 -252.37059) (xy 143.439388 -252.3363) (xy 142.840964 -252.3363) (xy 131.023106 -252.336554)
				(xy 130.983736 -252.375924) (xy 130.983736 -252.516386) (xy 131.293362 -252.826012) (xy 131.501388 -252.826012)
				(xy 131.771644 -253.096268) (xy 132.007864 -253.096268) (xy 132.065522 -253.153926) (xy 132.173218 -253.04623)
				(xy 135.922258 -253.04623) (xy 135.941054 -253.027434) (xy 136.144762 -253.027434) (xy 136.22274 -253.027434)
				(xy 136.263634 -253.068328) (xy 136.263634 -253.317756) (xy 136.277858 -253.33198) (xy 137.78103 -253.33198)
				(xy 137.852912 -253.403862) (xy 137.852912 -253.61392) (xy 137.852912 -253.713488) (xy 137.889488 -253.750064)
				(xy 142.236444 -253.750064) (xy 144.32661 -255.84023) (xy 148.419058 -255.84023) (xy 148.921978 -255.33731)
				(xy 147.075398 -253.49073) (xy 144.593818 -253.49073)
			)
		)
	)
	(zone
		(layer "In6.Cu")
		(hatch none 0.5)
		(connect_pads
			(clearance 0)
		)
		(min_thickness 0.25)
		(keepout
			(tracks allowed)
			(vias allowed)
			(pads allowed)
			(copperpour allowed)
			(footprints allowed)
		)
		(placement
			(enabled no)
			(sheetname "")
		)
		(fill
			(thermal_gap 0.5)
			(thermal_bridge_width 0.5)
			(island_removal_mode 0)
		)
		(polygon
			(pts
				(xy 20.638008 -313.156346) (xy 20.638008 -311.834276) (xy 21.165566 -311.834276) (xy 21.165566 -313.156346)
			)
		)
	)
	(zone
		(layer "In6.Cu")
		(hatch none 0.5)
		(connect_pads
			(clearance 0)
		)
		(min_thickness 0.25)
		(keepout
			(tracks allowed)
			(vias allowed)
			(pads allowed)
			(copperpour allowed)
			(footprints allowed)
		)
		(placement
			(enabled no)
			(sheetname "")
		)
		(fill
			(thermal_gap 0.5)
			(thermal_bridge_width 0.5)
			(island_removal_mode 0)
		)
		(polygon
			(pts
				(xy 420.479982 -217.114628) (xy 420.479982 -215.762586) (xy 421.055546 -215.762586) (xy 421.055546 -217.114628)
			)
		)
	)
	(zone
		(layer "In6.Cu")
		(hatch none 0.5)
		(connect_pads
			(clearance 0)
		)
		(min_thickness 0.25)
		(keepout
			(tracks allowed)
			(vias allowed)
			(pads allowed)
			(copperpour allowed)
			(footprints allowed)
		)
		(placement
			(enabled no)
			(sheetname "")
		)
		(fill
			(thermal_gap 0.5)
			(thermal_bridge_width 0.5)
			(island_removal_mode 0)
		)
		(polygon
			(pts
				(xy 187.627514 -272.364708) (xy 187.627514 -271.012666) (xy 188.203078 -271.012666) (xy 188.203078 -272.364708)
			)
		)
	)
	(zone
		(layer "In6.Cu")
		(hatch none 0.5)
		(connect_pads
			(clearance 0)
		)
		(min_thickness 0.25)
		(keepout
			(tracks allowed)
			(vias allowed)
			(pads allowed)
			(copperpour allowed)
			(footprints allowed)
		)
		(placement
			(enabled no)
			(sheetname "")
		)
		(fill
			(thermal_gap 0.5)
			(thermal_bridge_width 0.5)
			(island_removal_mode 0)
		)
		(polygon
			(pts
				(xy 292.35527 -195.732146) (xy 292.35527 -194.512946) (xy 292.971728 -194.512946) (xy 292.971728 -195.732146)
			)
		)
	)
	(zone
		(layer "In6.Cu")
		(hatch none 0.5)
		(connect_pads
			(clearance 0)
		)
		(min_thickness 0.25)
		(keepout
			(tracks allowed)
			(vias allowed)
			(pads allowed)
			(copperpour allowed)
			(footprints allowed)
		)
		(placement
			(enabled no)
			(sheetname "")
		)
		(fill
			(thermal_gap 0.5)
			(thermal_bridge_width 0.5)
			(island_removal_mode 0)
		)
		(polygon
			(pts
				(xy 161.552382 -224.7646) (xy 161.552382 -223.412558) (xy 162.127946 -223.412558) (xy 162.127946 -224.7646)
			)
		)
	)
	(zone
		(layer "In6.Cu")
		(hatch none 0.5)
		(connect_pads
			(clearance 0)
		)
		(min_thickness 0.25)
		(keepout
			(tracks allowed)
			(vias allowed)
			(pads allowed)
			(copperpour allowed)
			(footprints allowed)
		)
		(placement
			(enabled no)
			(sheetname "")
		)
		(fill
			(thermal_gap 0.5)
			(thermal_bridge_width 0.5)
			(island_removal_mode 0)
		)
		(polygon
			(pts
				(xy 279.551892 -307.250592) (xy 279.551892 -306.700174) (xy 279.931876 -306.32019) (xy 280.487628 -306.32019)
				(xy 280.487628 -306.97678) (xy 280.213816 -307.250592) (xy 280.110692 -307.250592)
			)
		)
	)
	(zone
		(layer "In6.Cu")
		(hatch none 0.5)
		(connect_pads
			(clearance 0)
		)
		(min_thickness 0.25)
		(keepout
			(tracks allowed)
			(vias allowed)
			(pads allowed)
			(copperpour allowed)
			(footprints allowed)
		)
		(placement
			(enabled no)
			(sheetname "")
		)
		(fill
			(thermal_gap 0.5)
			(thermal_bridge_width 0.5)
			(island_removal_mode 0)
		)
		(polygon
			(pts
				(xy 187.627514 -303.81448) (xy 187.627514 -301.328074) (xy 187.314586 -301.328074) (xy 187.314586 -300.346364)
				(xy 187.469018 -300.346364) (xy 187.627514 -300.346364) (xy 188.203078 -300.346364) (xy 188.203078 -300.765718)
				(xy 188.203078 -303.81448)
			)
		)
	)
	(zone
		(layer "In6.Cu")
		(hatch none 0.5)
		(connect_pads
			(clearance 0)
		)
		(min_thickness 0.25)
		(keepout
			(tracks allowed)
			(vias allowed)
			(pads allowed)
			(copperpour allowed)
			(footprints allowed)
		)
		(placement
			(enabled no)
			(sheetname "")
		)
		(fill
			(thermal_gap 0.5)
			(thermal_bridge_width 0.5)
			(island_removal_mode 0)
		)
		(polygon
			(pts
				(xy 202.740514 -213.894416) (xy 202.740514 -212.362542) (xy 203.316078 -212.362542) (xy 203.316078 -213.894416)
			)
		)
	)
	(zone
		(layer "In6.Cu")
		(hatch none 0.5)
		(connect_pads
			(clearance 0)
		)
		(min_thickness 0.25)
		(keepout
			(tracks allowed)
			(vias allowed)
			(pads allowed)
			(copperpour allowed)
			(footprints allowed)
		)
		(placement
			(enabled no)
			(sheetname "")
		)
		(fill
			(thermal_gap 0.5)
			(thermal_bridge_width 0.5)
			(island_removal_mode 0)
		)
		(polygon
			(pts
				(xy 436.143146 -278.662638) (xy 436.143146 -280.01468) (xy 435.567582 -280.01468) (xy 435.486302 -280.01468)
				(xy 435.486302 -278.398478) (xy 436.143146 -278.398478) (xy 436.143146 -278.512778)
			)
		)
	)
	(zone
		(layer "In6.Cu")
		(hatch none 0.5)
		(connect_pads
			(clearance 0)
		)
		(min_thickness 0.25)
		(keepout
			(tracks allowed)
			(vias allowed)
			(pads allowed)
			(copperpour allowed)
			(footprints allowed)
		)
		(placement
			(enabled no)
			(sheetname "")
		)
		(fill
			(thermal_gap 0.5)
			(thermal_bridge_width 0.5)
			(island_removal_mode 0)
		)
		(polygon
			(pts
				(xy 283.665676 -231.556306) (xy 283.665676 -230.234236) (xy 284.193234 -230.234236) (xy 284.193234 -231.556306)
			)
		)
	)
	(zone
		(layer "In6.Cu")
		(hatch none 0.5)
		(connect_pads
			(clearance 0)
		)
		(min_thickness 0.25)
		(keepout
			(tracks allowed)
			(vias allowed)
			(pads allowed)
			(copperpour allowed)
			(footprints allowed)
		)
		(placement
			(enabled no)
			(sheetname "")
		)
		(fill
			(thermal_gap 0.5)
			(thermal_bridge_width 0.5)
			(island_removal_mode 0)
		)
		(polygon
			(pts
				(xy 391.413746 -252.37059) (xy 391.379456 -252.3363) (xy 390.781032 -252.3363) (xy 378.963174 -252.336554)
				(xy 378.923804 -252.375924) (xy 378.923804 -252.516386) (xy 379.23343 -252.826012) (xy 379.441456 -252.826012)
				(xy 379.711712 -253.096268) (xy 379.947932 -253.096268) (xy 380.00559 -253.153926) (xy 380.113286 -253.04623)
				(xy 383.862326 -253.04623) (xy 383.881122 -253.027434) (xy 384.08483 -253.027434) (xy 384.162808 -253.027434)
				(xy 384.203702 -253.068328) (xy 384.203702 -253.317756) (xy 384.217926 -253.33198) (xy 385.721098 -253.33198)
				(xy 385.79298 -253.403862) (xy 385.79298 -253.61392) (xy 385.79298 -253.713488) (xy 385.829556 -253.750064)
				(xy 390.176512 -253.750064) (xy 392.266678 -255.84023) (xy 396.359126 -255.84023) (xy 396.862046 -255.33731)
				(xy 395.015466 -253.49073) (xy 392.533886 -253.49073)
			)
		)
	)
	(zone
		(layer "In6.Cu")
		(hatch none 0.5)
		(connect_pads
			(clearance 0)
		)
		(min_thickness 0.25)
		(keepout
			(tracks allowed)
			(vias allowed)
			(pads allowed)
			(copperpour allowed)
			(footprints allowed)
		)
		(placement
			(enabled no)
			(sheetname "")
		)
		(fill
			(thermal_gap 0.5)
			(thermal_bridge_width 0.5)
			(island_removal_mode 0)
		)
		(polygon
			(pts
				(xy 80.263746 -257.328416) (xy 79.57312 -258.019042) (xy 77.520546 -258.019042) (xy 77.442314 -257.94081)
				(xy 77.442314 -257.750564) (xy 77.713078 -257.4798) (xy 77.874114 -257.4798) (xy 77.921866 -257.432048)
				(xy 77.921866 -257.189224) (xy 78.142592 -256.968498) (xy 78.234286 -256.968498) (xy 78.348586 -256.854198)
				(xy 78.348586 -256.530602) (xy 78.440534 -256.438654) (xy 78.81747 -256.438654) (xy 78.929484 -256.32664)
				(xy 78.929484 -256.048764) (xy 78.249018 -256.048764) (xy 78.249018 -255.547622) (xy 75.96251 -255.547622)
				(xy 75.943714 -255.528826) (xy 75.712828 -255.528826) (xy 75.531218 -255.347216) (xy 75.531218 -254.674878)
				(xy 75.65009 -254.556006) (xy 76.047092 -254.556006) (xy 76.135484 -254.644398) (xy 76.414122 -254.36576)
				(xy 76.414122 -254.328422) (xy 76.644754 -254.09779) (xy 76.992734 -254.09779) (xy 76.992734 -251.25553)
				(xy 76.799186 -251.449078) (xy 75.355958 -251.449078) (xy 74.967338 -251.837698) (xy 74.715624 -251.585984)
				(xy 74.715624 -250.862846) (xy 74.899012 -250.679458) (xy 74.899012 -250.11253) (xy 74.996802 -250.01474)
				(xy 74.996802 -249.514868) (xy 74.905108 -249.423174) (xy 74.615294 -249.423174) (xy 74.25055 -249.787918)
				(xy 73.004172 -249.787918) (xy 73.004172 -248.578878) (xy 73.423272 -248.159778) (xy 73.9521 -247.63095)
				(xy 73.9521 -247.28551) (xy 73.880218 -247.28551) (xy 73.608184 -247.013476) (xy 73.608184 -246.81053)
				(xy 73.319894 -246.52224) (xy 72.519286 -245.721632) (xy 72.519286 -244.712998) (xy 72.519286 -244.557804)
				(xy 72.519286 -244.3099) (xy 72.57034 -244.258846) (xy 72.818244 -244.258846) (xy 81.059782 -244.258846)
				(xy 81.20888 -244.407944) (xy 81.835752 -245.034816) (xy 83.033616 -245.034562) (xy 83.033616 -246.777764)
				(xy 83.098386 -246.842534) (xy 83.288378 -246.842534) (xy 83.319112 -246.873268) (xy 83.319112 -250.408694)
				(xy 83.43138 -250.520962) (xy 83.520534 -250.520962) (xy 88.168734 -250.520962) (xy 88.168734 -252.571504)
				(xy 84.819998 -252.571504) (xy 84.108036 -252.571504) (xy 84.050378 -252.629162) (xy 81.691734 -252.629416)
				(xy 81.691734 -255.118616) (xy 81.132934 -255.118616) (xy 81.132934 -257.328416)
			)
		)
	)
	(zone
		(layer "In6.Cu")
		(hatch none 0.5)
		(connect_pads
			(clearance 0)
		)
		(min_thickness 0.25)
		(keepout
			(tracks allowed)
			(vias allowed)
			(pads allowed)
			(copperpour allowed)
			(footprints allowed)
		)
		(placement
			(enabled no)
			(sheetname "")
		)
		(fill
			(thermal_gap 0.5)
			(thermal_bridge_width 0.5)
			(island_removal_mode 0)
		)
		(polygon
			(pts
				(xy 279.53843 -317.372492) (xy 279.53843 -316.063884) (xy 280.072846 -316.063884) (xy 280.072846 -317.372492)
			)
		)
	)
	(zone
		(layer "In6.Cu")
		(hatch none 0.5)
		(connect_pads
			(clearance 0)
		)
		(min_thickness 0.25)
		(keepout
			(tracks allowed)
			(vias allowed)
			(pads allowed)
			(copperpour allowed)
			(footprints allowed)
		)
		(placement
			(enabled no)
			(sheetname "")
		)
		(fill
			(thermal_gap 0.5)
			(thermal_bridge_width 0.5)
			(island_removal_mode 0)
		)
		(polygon
			(pts
				(xy 35.602672 -274.964906) (xy 35.602672 -272.697448) (xy 36.28771 -272.697448) (xy 36.28771 -274.964906)
			)
		)
	)
	(zone
		(layer "In6.Cu")
		(hatch none 0.5)
		(connect_pads
			(clearance 0)
		)
		(min_thickness 0.25)
		(keepout
			(tracks allowed)
			(vias allowed)
			(pads allowed)
			(copperpour allowed)
			(footprints allowed)
		)
		(placement
			(enabled no)
			(sheetname "")
		)
		(fill
			(thermal_gap 0.5)
			(thermal_bridge_width 0.5)
			(island_removal_mode 0)
		)
		(polygon
			(pts
				(xy 50.813208 -246.85625) (xy 50.813208 -245.53418) (xy 51.340766 -245.53418) (xy 51.340766 -246.85625)
			)
		)
	)
	(zone
		(layer "In6.Cu")
		(hatch none 0.5)
		(connect_pads
			(clearance 0)
		)
		(min_thickness 0.25)
		(keepout
			(tracks allowed)
			(vias allowed)
			(pads allowed)
			(copperpour allowed)
			(footprints allowed)
		)
		(placement
			(enabled no)
			(sheetname "")
		)
		(fill
			(thermal_gap 0.5)
			(thermal_bridge_width 0.5)
			(island_removal_mode 0)
		)
		(polygon
			(pts
				(xy 435.567582 -299.564552) (xy 435.567582 -298.21251) (xy 436.143146 -298.21251) (xy 436.143146 -299.564552)
			)
		)
	)
	(zone
		(layer "In6.Cu")
		(hatch none 0.5)
		(connect_pads
			(clearance 0)
		)
		(min_thickness 0.25)
		(keepout
			(tracks allowed)
			(vias allowed)
			(pads allowed)
			(copperpour allowed)
			(footprints allowed)
		)
		(placement
			(enabled no)
			(sheetname "")
		)
		(fill
			(thermal_gap 0.5)
			(thermal_bridge_width 0.5)
			(island_removal_mode 0)
		)
		(polygon
			(pts
				(xy 124.72924 -18.67662) (xy 124.72924 -16.96212) (xy 123.75642 -16.96212) (xy 123.75642 -18.67662)
			)
		)
	)
	(zone
		(layer "In6.Cu")
		(hatch none 0.5)
		(connect_pads
			(clearance 0)
		)
		(min_thickness 0.25)
		(keepout
			(tracks allowed)
			(vias allowed)
			(pads allowed)
			(copperpour allowed)
			(footprints allowed)
		)
		(placement
			(enabled no)
			(sheetname "")
		)
		(fill
			(thermal_gap 0.5)
			(thermal_bridge_width 0.5)
			(island_removal_mode 0)
		)
		(polygon
			(pts
				(xy 340.17966 -339.090508) (xy 340.17966 -335.539588) (xy 353.21494 -335.539588) (xy 353.21494 -339.090508)
			)
		)
	)
	(zone
		(layer "In6.Cu")
		(hatch none 0.5)
		(connect_pads
			(clearance 0)
		)
		(min_thickness 0.25)
		(keepout
			(tracks allowed)
			(vias allowed)
			(pads allowed)
			(copperpour allowed)
			(footprints allowed)
		)
		(placement
			(enabled no)
			(sheetname "")
		)
		(fill
			(thermal_gap 0.5)
			(thermal_bridge_width 0.5)
			(island_removal_mode 0)
		)
		(polygon
			(pts
				(xy 409.46705 -231.564688) (xy 409.46705 -230.212646) (xy 410.042614 -230.212646) (xy 410.042614 -231.564688)
			)
		)
	)
	(zone
		(layer "In6.Cu")
		(hatch none 0.5)
		(connect_pads
			(clearance 0)
		)
		(min_thickness 0.25)
		(keepout
			(tracks allowed)
			(vias allowed)
			(pads allowed)
			(copperpour allowed)
			(footprints allowed)
		)
		(placement
			(enabled no)
			(sheetname "")
		)
		(fill
			(thermal_gap 0.5)
			(thermal_bridge_width 0.5)
			(island_removal_mode 0)
		)
		(polygon
			(pts
				(xy 61.677804 -270.714978) (xy 61.677804 -268.44752) (xy 62.362842 -268.44752) (xy 62.362842 -270.714978)
			)
		)
	)
	(zone
		(layer "In6.Cu")
		(hatch none 0.5)
		(connect_pads
			(clearance 0)
		)
		(min_thickness 0.25)
		(keepout
			(tracks allowed)
			(vias allowed)
			(pads allowed)
			(copperpour allowed)
			(footprints allowed)
		)
		(placement
			(enabled no)
			(sheetname "")
		)
		(fill
			(thermal_gap 0.5)
			(thermal_bridge_width 0.5)
			(island_removal_mode 0)
		)
		(polygon
			(pts
				(xy 61.739272 -304.609754) (xy 61.739272 -299.047408) (xy 62.35573 -299.047408) (xy 62.35573 -304.609754)
			)
		)
	)
	(zone
		(layer "In6.Cu")
		(hatch none 0.5)
		(connect_pads
			(clearance 0)
		)
		(min_thickness 0.25)
		(keepout
			(tracks allowed)
			(vias allowed)
			(pads allowed)
			(copperpour allowed)
			(footprints allowed)
		)
		(placement
			(enabled no)
			(sheetname "")
		)
		(fill
			(thermal_gap 0.5)
			(thermal_bridge_width 0.5)
			(island_removal_mode 0)
		)
		(polygon
			(pts
				(xy 187.627514 -287.664652) (xy 187.627514 -286.31261) (xy 188.203078 -286.31261) (xy 188.203078 -287.664652)
			)
		)
	)
	(zone
		(layer "In6.Cu")
		(hatch none 0.5)
		(connect_pads
			(clearance 0)
		)
		(min_thickness 0.25)
		(keepout
			(tracks allowed)
			(vias allowed)
			(pads allowed)
			(copperpour allowed)
			(footprints allowed)
		)
		(placement
			(enabled no)
			(sheetname "")
		)
		(fill
			(thermal_gap 0.5)
			(thermal_bridge_width 0.5)
			(island_removal_mode 0)
		)
		(polygon
			(pts
				(xy 283.54274 -274.964906) (xy 283.54274 -272.697448) (xy 284.227778 -272.697448) (xy 284.227778 -274.964906)
			)
		)
	)
	(zone
		(layer "In6.Cu")
		(hatch none 0.5)
		(connect_pads
			(clearance 0)
		)
		(min_thickness 0.25)
		(keepout
			(tracks allowed)
			(vias allowed)
			(pads allowed)
			(copperpour allowed)
			(footprints allowed)
		)
		(placement
			(enabled no)
			(sheetname "")
		)
		(fill
			(thermal_gap 0.5)
			(thermal_bridge_width 0.5)
			(island_removal_mode 0)
		)
		(polygon
			(pts
				(xy 283.665676 -200.956418) (xy 283.665676 -199.634348) (xy 284.193234 -199.634348) (xy 284.193234 -200.956418)
				(xy 284.193234 -203.461112) (xy 283.665676 -203.461112)
			)
		)
	)
	(zone
		(layer "In6.Cu")
		(hatch none 0.5)
		(connect_pads
			(clearance 0)
		)
		(min_thickness 0.25)
		(keepout
			(tracks allowed)
			(vias allowed)
			(pads allowed)
			(copperpour allowed)
			(footprints allowed)
		)
		(placement
			(enabled no)
			(sheetname "")
		)
		(fill
			(thermal_gap 0.5)
			(thermal_bridge_width 0.5)
			(island_removal_mode 0)
		)
		(polygon
			(pts
				(xy 356.11562 -338.292948) (xy 356.11562 -335.156048) (xy 369.92814 -335.156048) (xy 369.92814 -338.292948)
			)
		)
	)
	(zone
		(layer "In6.Cu")
		(hatch none 0.5)
		(connect_pads
			(clearance 0)
		)
		(min_thickness 0.25)
		(keepout
			(tracks allowed)
			(vias allowed)
			(pads allowed)
			(copperpour allowed)
			(footprints allowed)
		)
		(placement
			(enabled no)
			(sheetname "")
		)
		(fill
			(thermal_gap 0.5)
			(thermal_bridge_width 0.5)
			(island_removal_mode 0)
		)
		(polygon
			(pts
				(xy 279.565608 -246.85625) (xy 279.565608 -245.53418) (xy 280.093166 -245.53418) (xy 280.093166 -246.85625)
			)
		)
	)
	(zone
		(layer "In6.Cu")
		(hatch none 0.5)
		(connect_pads
			(clearance 0)
		)
		(min_thickness 0.25)
		(keepout
			(tracks allowed)
			(vias allowed)
			(pads allowed)
			(copperpour allowed)
			(footprints allowed)
		)
		(placement
			(enabled no)
			(sheetname "")
		)
		(fill
			(thermal_gap 0.5)
			(thermal_bridge_width 0.5)
			(island_removal_mode 0)
		)
		(polygon
			(pts
				(xy 420.479982 -314.864496) (xy 420.479982 -312.680858) (xy 421.055546 -312.680858) (xy 421.055546 -314.864496)
			)
		)
	)
	(zone
		(layer "In6.Cu")
		(hatch none 0.5)
		(connect_pads
			(clearance 0)
		)
		(min_thickness 0.25)
		(keepout
			(tracks allowed)
			(vias allowed)
			(pads allowed)
			(copperpour allowed)
			(footprints allowed)
		)
		(placement
			(enabled no)
			(sheetname "")
		)
		(fill
			(thermal_gap 0.5)
			(thermal_bridge_width 0.5)
			(island_removal_mode 0)
		)
		(polygon
			(pts
				(xy 202.740514 -245.154196) (xy 202.740514 -242.96243) (xy 203.316078 -242.96243) (xy 203.316078 -245.154196)
			)
		)
	)
	(zone
		(layer "In6.Cu")
		(hatch none 0.5)
		(connect_pads
			(clearance 0)
		)
		(min_thickness 0.25)
		(keepout
			(tracks allowed)
			(vias allowed)
			(pads allowed)
			(copperpour allowed)
			(footprints allowed)
		)
		(placement
			(enabled no)
			(sheetname "")
		)
		(fill
			(thermal_gap 0.5)
			(thermal_bridge_width 0.5)
			(island_removal_mode 0)
		)
		(polygon
			(pts
				(xy 296.95394 -367.566448) (xy 296.95394 -366.265968) (xy 298.73702 -366.265968) (xy 298.73702 -367.566448)
			)
		)
	)
	(zone
		(layer "In6.Cu")
		(hatch none 0.5)
		(connect_pads
			(clearance 0)
		)
		(min_thickness 0.25)
		(keepout
			(tracks allowed)
			(vias allowed)
			(pads allowed)
			(copperpour allowed)
			(footprints allowed)
		)
		(placement
			(enabled no)
			(sheetname "")
		)
		(fill
			(thermal_gap 0.5)
			(thermal_bridge_width 0.5)
			(island_removal_mode 0)
		)
		(polygon
			(pts
				(xy 268.578076 -317.406274) (xy 268.578076 -316.084204) (xy 269.105634 -316.084204) (xy 269.105634 -317.406274)
			)
		)
	)
	(zone
		(layer "In6.Cu")
		(hatch none 0.5)
		(connect_pads
			(clearance 0)
		)
		(min_thickness 0.25)
		(keepout
			(tracks allowed)
			(vias allowed)
			(pads allowed)
			(copperpour allowed)
			(footprints allowed)
		)
		(placement
			(enabled no)
			(sheetname "")
		)
		(fill
			(thermal_gap 0.5)
			(thermal_bridge_width 0.5)
			(island_removal_mode 0)
		)
		(polygon
			(pts
				(xy 187.627514 -276.614636) (xy 187.627514 -272.724118) (xy 188.203078 -272.724118) (xy 188.203078 -276.614636)
			)
		)
	)
	(zone
		(layer "In6.Cu")
		(hatch none 0.5)
		(connect_pads
			(clearance 0)
		)
		(min_thickness 0.25)
		(keepout
			(tracks allowed)
			(vias allowed)
			(pads allowed)
			(copperpour allowed)
			(footprints allowed)
		)
		(placement
			(enabled no)
			(sheetname "")
		)
		(fill
			(thermal_gap 0.5)
			(thermal_bridge_width 0.5)
			(island_removal_mode 0)
		)
		(polygon
			(pts
				(xy 20.638008 -207.756252) (xy 20.638008 -206.434182) (xy 21.165566 -206.434182) (xy 21.165566 -207.756252)
			)
		)
	)
	(zone
		(layer "In6.Cu")
		(hatch none 0.5)
		(connect_pads
			(clearance 0)
		)
		(min_thickness 0.25)
		(keepout
			(tracks allowed)
			(vias allowed)
			(pads allowed)
			(copperpour allowed)
			(footprints allowed)
		)
		(placement
			(enabled no)
			(sheetname "")
		)
		(fill
			(thermal_gap 0.5)
			(thermal_bridge_width 0.5)
			(island_removal_mode 0)
		)
		(polygon
			(pts
				(xy 268.578076 -246.006366) (xy 268.578076 -244.684296) (xy 269.105634 -244.684296) (xy 269.105634 -246.006366)
			)
		)
	)
	(zone
		(layer "In6.Cu")
		(hatch none 0.5)
		(connect_pads
			(clearance 0)
		)
		(min_thickness 0.25)
		(keepout
			(tracks allowed)
			(vias allowed)
			(pads allowed)
			(copperpour allowed)
			(footprints allowed)
		)
		(placement
			(enabled no)
			(sheetname "")
		)
		(fill
			(thermal_gap 0.5)
			(thermal_bridge_width 0.5)
			(island_removal_mode 0)
		)
		(polygon
			(pts
				(xy 435.567582 -287.664652) (xy 435.567582 -286.31261) (xy 436.143146 -286.31261) (xy 436.143146 -287.664652)
			)
		)
	)
	(zone
		(layer "In6.Cu")
		(hatch none 0.5)
		(connect_pads
			(clearance 0)
		)
		(min_thickness 0.25)
		(keepout
			(tracks allowed)
			(vias allowed)
			(pads allowed)
			(copperpour allowed)
			(footprints allowed)
		)
		(placement
			(enabled no)
			(sheetname "")
		)
		(fill
			(thermal_gap 0.5)
			(thermal_bridge_width 0.5)
			(island_removal_mode 0)
		)
		(polygon
			(pts
				(xy 424.60926 -367.091468) (xy 424.60926 -365.684308) (xy 426.20184 -365.684308) (xy 426.20184 -367.091468)
			)
		)
	)
	(zone
		(layer "In6.Cu")
		(hatch none 0.5)
		(connect_pads
			(clearance 0)
		)
		(min_thickness 0.25)
		(keepout
			(tracks allowed)
			(vias allowed)
			(pads allowed)
			(copperpour allowed)
			(footprints allowed)
		)
		(placement
			(enabled no)
			(sheetname "")
		)
		(fill
			(thermal_gap 0.5)
			(thermal_bridge_width 0.5)
			(island_removal_mode 0)
		)
		(polygon
			(pts
				(xy 268.578076 -310.60644) (xy 268.578076 -309.28437) (xy 269.105634 -309.28437) (xy 269.105634 -310.60644)
			)
		)
	)
	(zone
		(layer "In6.Cu")
		(hatch none 0.5)
		(connect_pads
			(clearance 0)
		)
		(min_thickness 0.25)
		(keepout
			(tracks allowed)
			(vias allowed)
			(pads allowed)
			(copperpour allowed)
			(footprints allowed)
		)
		(placement
			(enabled no)
			(sheetname "")
		)
		(fill
			(thermal_gap 0.5)
			(thermal_bridge_width 0.5)
			(island_removal_mode 0)
		)
		(polygon
			(pts
				(xy 31.62554 -246.85625) (xy 31.62554 -245.53418) (xy 32.153098 -245.53418) (xy 32.153098 -246.85625)
			)
		)
	)
	(zone
		(layer "In6.Cu")
		(hatch none 0.5)
		(connect_pads
			(clearance 0)
		)
		(min_thickness 0.25)
		(keepout
			(tracks allowed)
			(vias allowed)
			(pads allowed)
			(copperpour allowed)
			(footprints allowed)
		)
		(placement
			(enabled no)
			(sheetname "")
		)
		(fill
			(thermal_gap 0.5)
			(thermal_bridge_width 0.5)
			(island_removal_mode 0)
		)
		(polygon
			(pts
				(xy 35.04184 -203.982828) (xy 35.04184 -201.745088) (xy 37.16274 -201.745088) (xy 37.16274 -203.982828)
			)
		)
	)
	(zone
		(layer "In6.Cu")
		(hatch none 0.5)
		(connect_pads
			(clearance 0)
		)
		(min_thickness 0.25)
		(keepout
			(tracks allowed)
			(vias allowed)
			(pads allowed)
			(copperpour allowed)
			(footprints allowed)
		)
		(placement
			(enabled no)
			(sheetname "")
		)
		(fill
			(thermal_gap 0.5)
			(thermal_bridge_width 0.5)
			(island_removal_mode 0)
		)
		(polygon
			(pts
				(xy 313.796426 -232.353612) (xy 313.796426 -223.366076) (xy 314.536328 -223.366076) (xy 314.536328 -232.353612)
			)
		)
	)
	(zone
		(layer "In6.Cu")
		(hatch none 0.5)
		(connect_pads
			(clearance 0)
		)
		(min_thickness 0.25)
		(keepout
			(tracks allowed)
			(vias allowed)
			(pads allowed)
			(copperpour allowed)
			(footprints allowed)
		)
		(placement
			(enabled no)
			(sheetname "")
		)
		(fill
			(thermal_gap 0.5)
			(thermal_bridge_width 0.5)
			(island_removal_mode 0)
		)
		(polygon
			(pts
				(xy 424.488102 -207.118458) (xy 424.488102 -204.696314) (xy 425.118276 -204.696314) (xy 425.118276 -207.118458)
			)
		)
	)
	(zone
		(layer "In6.Cu")
		(hatch none 0.5)
		(connect_pads
			(clearance 0)
		)
		(min_thickness 0.25)
		(keepout
			(tracks allowed)
			(vias allowed)
			(pads allowed)
			(copperpour allowed)
			(footprints allowed)
		)
		(placement
			(enabled no)
			(sheetname "")
		)
		(fill
			(thermal_gap 0.5)
			(thermal_bridge_width 0.5)
			(island_removal_mode 0)
		)
		(polygon
			(pts
				(xy 351.46742 -38.30828) (xy 351.46742 -35.57524) (xy 353.51212 -35.57524) (xy 353.51212 -38.30828)
			)
		)
	)
	(zone
		(layer "In6.Cu")
		(hatch none 0.5)
		(connect_pads
			(clearance 0)
		)
		(min_thickness 0.25)
		(keepout
			(tracks allowed)
			(vias allowed)
			(pads allowed)
			(copperpour allowed)
			(footprints allowed)
		)
		(placement
			(enabled no)
			(sheetname "")
		)
		(fill
			(thermal_gap 0.5)
			(thermal_bridge_width 0.5)
			(island_removal_mode 0)
		)
		(polygon
			(pts
				(xy 30.6451 -216.390728) (xy 30.6451 -214.048848) (xy 33.37306 -214.048848) (xy 33.37306 -216.390728)
			)
		)
	)
	(zone
		(layer "In6.Cu")
		(hatch none 0.5)
		(connect_pads
			(clearance 0)
		)
		(min_thickness 0.25)
		(keepout
			(tracks allowed)
			(vias allowed)
			(pads allowed)
			(copperpour allowed)
			(footprints allowed)
		)
		(placement
			(enabled no)
			(sheetname "")
		)
		(fill
			(thermal_gap 0.5)
			(thermal_bridge_width 0.5)
			(island_removal_mode 0)
		)
		(polygon
			(pts
				(xy 283.665676 -198.406258) (xy 283.665676 -197.084188) (xy 284.193234 -197.084188) (xy 284.193234 -198.406258)
			)
		)
	)
	(zone
		(layer "In6.Cu")
		(hatch none 0.5)
		(connect_pads
			(clearance 0)
		)
		(min_thickness 0.25)
		(keepout
			(tracks allowed)
			(vias allowed)
			(pads allowed)
			(copperpour allowed)
			(footprints allowed)
		)
		(placement
			(enabled no)
			(sheetname "")
		)
		(fill
			(thermal_gap 0.5)
			(thermal_bridge_width 0.5)
			(island_removal_mode 0)
		)
		(polygon
			(pts
				(xy 450.680582 -207.805782) (xy 450.680582 -207.262476) (xy 451.256146 -207.262476) (xy 451.256146 -208.79435)
				(xy 450.680582 -208.79435) (xy 450.553836 -208.79435) (xy 450.553836 -207.805782)
			)
		)
	)
	(zone
		(layer "In6.Cu")
		(hatch none 0.5)
		(connect_pads
			(clearance 0)
		)
		(min_thickness 0.25)
		(keepout
			(tracks allowed)
			(vias allowed)
			(pads allowed)
			(copperpour allowed)
			(footprints allowed)
		)
		(placement
			(enabled no)
			(sheetname "")
		)
		(fill
			(thermal_gap 0.5)
			(thermal_bridge_width 0.5)
			(island_removal_mode 0)
		)
		(polygon
			(pts
				(xy 283.665676 -233.256328) (xy 283.665676 -231.934258) (xy 284.193234 -231.934258) (xy 284.193234 -233.256328)
			)
		)
	)
	(zone
		(layer "In6.Cu")
		(hatch none 0.5)
		(connect_pads
			(clearance 0)
		)
		(min_thickness 0.25)
		(keepout
			(tracks allowed)
			(vias allowed)
			(pads allowed)
			(copperpour allowed)
			(footprints allowed)
		)
		(placement
			(enabled no)
			(sheetname "")
		)
		(fill
			(thermal_gap 0.5)
			(thermal_bridge_width 0.5)
			(island_removal_mode 0)
		)
		(polygon
			(pts
				(xy 435.475634 -197.552564) (xy 435.475634 -196.196204) (xy 436.105808 -196.196204) (xy 436.105808 -197.552564)
			)
		)
	)
	(zone
		(layer "In6.Cu")
		(hatch none 0.5)
		(connect_pads
			(clearance 0)
		)
		(min_thickness 0.25)
		(keepout
			(tracks allowed)
			(vias allowed)
			(pads allowed)
			(copperpour allowed)
			(footprints allowed)
		)
		(placement
			(enabled no)
			(sheetname "")
		)
		(fill
			(thermal_gap 0.5)
			(thermal_bridge_width 0.5)
			(island_removal_mode 0)
		)
		(polygon
			(pts
				(xy 20.638008 -211.156296) (xy 20.638008 -209.834226) (xy 21.165566 -209.834226) (xy 21.165566 -211.156296)
			)
		)
	)
	(zone
		(layer "In6.Cu")
		(hatch none 0.5)
		(connect_pads
			(clearance 0)
		)
		(min_thickness 0.25)
		(keepout
			(tracks allowed)
			(vias allowed)
			(pads allowed)
			(copperpour allowed)
			(footprints allowed)
		)
		(placement
			(enabled no)
			(sheetname "")
		)
		(fill
			(thermal_gap 0.5)
			(thermal_bridge_width 0.5)
			(island_removal_mode 0)
		)
		(polygon
			(pts
				(xy 202.715114 -316.564518) (xy 202.715114 -314.364878) (xy 203.290678 -314.364878) (xy 203.290678 -316.564518)
			)
		)
	)
	(zone
		(layer "In6.Cu")
		(hatch none 0.5)
		(connect_pads
			(clearance 0)
		)
		(min_thickness 0.25)
		(keepout
			(tracks allowed)
			(vias allowed)
			(pads allowed)
			(copperpour allowed)
			(footprints allowed)
		)
		(placement
			(enabled no)
			(sheetname "")
		)
		(fill
			(thermal_gap 0.5)
			(thermal_bridge_width 0.5)
			(island_removal_mode 0)
		)
		(polygon
			(pts
				(xy 450.680582 -245.154196) (xy 450.680582 -242.96243) (xy 451.256146 -242.96243) (xy 451.256146 -245.154196)
			)
		)
	)
	(zone
		(layer "In6.Cu")
		(hatch none 0.5)
		(connect_pads
			(clearance 0)
		)
		(min_thickness 0.25)
		(keepout
			(tracks allowed)
			(vias allowed)
			(pads allowed)
			(copperpour allowed)
			(footprints allowed)
		)
		(placement
			(enabled no)
			(sheetname "")
		)
		(fill
			(thermal_gap 0.5)
			(thermal_bridge_width 0.5)
			(island_removal_mode 0)
		)
		(polygon
			(pts
				(xy 279.565608 -248.556272) (xy 279.565608 -247.234202) (xy 280.093166 -247.234202) (xy 280.093166 -248.556272)
			)
		)
	)
	(zone
		(layer "In6.Cu")
		(hatch none 0.5)
		(connect_pads
			(clearance 0)
		)
		(min_thickness 0.25)
		(keepout
			(tracks allowed)
			(vias allowed)
			(pads allowed)
			(copperpour allowed)
			(footprints allowed)
		)
		(placement
			(enabled no)
			(sheetname "")
		)
		(fill
			(thermal_gap 0.5)
			(thermal_bridge_width 0.5)
			(island_removal_mode 0)
		)
		(polygon
			(pts
				(xy 321.73418 -349.067628) (xy 321.73418 -347.083888) (xy 322.79336 -347.083888) (xy 322.79336 -349.067628)
			)
		)
	)
	(zone
		(layer "In6.Cu")
		(hatch none 0.5)
		(connect_pads
			(clearance 0)
		)
		(min_thickness 0.25)
		(keepout
			(tracks allowed)
			(vias allowed)
			(pads allowed)
			(copperpour allowed)
			(footprints allowed)
		)
		(placement
			(enabled no)
			(sheetname "")
		)
		(fill
			(thermal_gap 0.5)
			(thermal_bridge_width 0.5)
			(island_removal_mode 0)
		)
		(polygon
			(pts
				(xy 35.725608 -198.406258) (xy 35.725608 -197.084188) (xy 36.253166 -197.084188) (xy 36.253166 -198.406258)
			)
		)
	)
	(zone
		(layer "In6.Cu")
		(hatch none 0.5)
		(connect_pads
			(clearance 0)
		)
		(min_thickness 0.25)
		(keepout
			(tracks allowed)
			(vias allowed)
			(pads allowed)
			(copperpour allowed)
			(footprints allowed)
		)
		(placement
			(enabled no)
			(sheetname "")
		)
		(fill
			(thermal_gap 0.5)
			(thermal_bridge_width 0.5)
			(island_removal_mode 0)
		)
		(polygon
			(pts
				(xy 202.740514 -250.254262) (xy 202.740514 -248.062496) (xy 203.316078 -248.062496) (xy 203.316078 -250.254262)
			)
		)
	)
	(zone
		(layer "In6.Cu")
		(hatch none 0.5)
		(connect_pads
			(clearance 0)
		)
		(min_thickness 0.25)
		(keepout
			(tracks allowed)
			(vias allowed)
			(pads allowed)
			(copperpour allowed)
			(footprints allowed)
		)
		(placement
			(enabled no)
			(sheetname "")
		)
		(fill
			(thermal_gap 0.5)
			(thermal_bridge_width 0.5)
			(island_removal_mode 0)
		)
		(polygon
			(pts
				(xy 92.47124 -31.62046) (xy 92.47124 -30.05074) (xy 91.17076 -30.05074) (xy 91.17076 -31.62046)
			)
		)
	)
	(zone
		(layer "In6.Cu")
		(hatch none 0.5)
		(connect_pads
			(clearance 0)
		)
		(min_thickness 0.25)
		(keepout
			(tracks allowed)
			(vias allowed)
			(pads allowed)
			(copperpour allowed)
			(footprints allowed)
		)
		(placement
			(enabled no)
			(sheetname "")
		)
		(fill
			(thermal_gap 0.5)
			(thermal_bridge_width 0.5)
			(island_removal_mode 0)
		)
		(polygon
			(pts
				(xy 155.63596 -49.28362) (xy 155.63596 -46.79442) (xy 160.3756 -46.79442) (xy 160.3756 -49.28362)
			)
		)
	)
	(zone
		(layer "In6.Cu")
		(hatch none 0.5)
		(connect_pads
			(clearance 0)
		)
		(min_thickness 0.25)
		(keepout
			(tracks allowed)
			(vias allowed)
			(pads allowed)
			(copperpour allowed)
			(footprints allowed)
		)
		(placement
			(enabled no)
			(sheetname "")
		)
		(fill
			(thermal_gap 0.5)
			(thermal_bridge_width 0.5)
			(island_removal_mode 0)
		)
		(polygon
			(pts
				(xy 172.539914 -246.864632) (xy 172.539914 -245.51259) (xy 173.115478 -245.51259) (xy 173.115478 -246.864632)
			)
		)
	)
	(zone
		(layer "In6.Cu")
		(hatch none 0.5)
		(connect_pads
			(clearance 0)
		)
		(min_thickness 0.25)
		(keepout
			(tracks allowed)
			(vias allowed)
			(pads allowed)
			(copperpour allowed)
			(footprints allowed)
		)
		(placement
			(enabled no)
			(sheetname "")
		)
		(fill
			(thermal_gap 0.5)
			(thermal_bridge_width 0.5)
			(island_removal_mode 0)
		)
		(polygon
			(pts
				(xy 39.072058 -243.478304) (xy 39.072058 -242.08105) (xy 39.757096 -242.08105) (xy 39.757096 -243.478304)
			)
		)
	)
	(zone
		(layer "In6.Cu")
		(hatch none 0.5)
		(connect_pads
			(clearance 0)
		)
		(min_thickness 0.25)
		(keepout
			(tracks allowed)
			(vias allowed)
			(pads allowed)
			(copperpour allowed)
			(footprints allowed)
		)
		(placement
			(enabled no)
			(sheetname "")
		)
		(fill
			(thermal_gap 0.5)
			(thermal_bridge_width 0.5)
			(island_removal_mode 0)
		)
		(polygon
			(pts
				(xy 35.602672 -269.014956) (xy 35.602672 -266.747498) (xy 36.28771 -266.747498) (xy 36.28771 -269.014956)
			)
		)
	)
	(zone
		(layer "In6.Cu")
		(hatch none 0.5)
		(connect_pads
			(clearance 0)
		)
		(min_thickness 0.25)
		(keepout
			(tracks allowed)
			(vias allowed)
			(pads allowed)
			(copperpour allowed)
			(footprints allowed)
		)
		(placement
			(enabled no)
			(sheetname "")
		)
		(fill
			(thermal_gap 0.5)
			(thermal_bridge_width 0.5)
			(island_removal_mode 0)
		)
		(polygon
			(pts
				(xy 435.567582 -284.264608) (xy 435.567582 -282.114498) (xy 436.143146 -282.114498) (xy 436.143146 -284.264608)
			)
		)
	)
	(zone
		(layer "In6.Cu")
		(hatch none 0.5)
		(connect_pads
			(clearance 0)
		)
		(min_thickness 0.25)
		(keepout
			(tracks allowed)
			(vias allowed)
			(pads allowed)
			(copperpour allowed)
			(footprints allowed)
		)
		(placement
			(enabled no)
			(sheetname "")
		)
		(fill
			(thermal_gap 0.5)
			(thermal_bridge_width 0.5)
			(island_removal_mode 0)
		)
		(polygon
			(pts
				(xy 20.638008 -206.05623) (xy 20.638008 -204.73416) (xy 21.165566 -204.73416) (xy 21.165566 -206.05623)
			)
		)
	)
	(zone
		(layer "In6.Cu")
		(hatch none 0.5)
		(connect_pads
			(clearance 0)
		)
		(min_thickness 0.25)
		(keepout
			(tracks allowed)
			(vias allowed)
			(pads allowed)
			(copperpour allowed)
			(footprints allowed)
		)
		(placement
			(enabled no)
			(sheetname "")
		)
		(fill
			(thermal_gap 0.5)
			(thermal_bridge_width 0.5)
			(island_removal_mode 0)
		)
		(polygon
			(pts
				(xy 298.753276 -246.85625) (xy 298.753276 -245.53418) (xy 299.280834 -245.53418) (xy 299.280834 -246.85625)
			)
		)
	)
	(zone
		(layer "In6.Cu")
		(hatch none 0.5)
		(connect_pads
			(clearance 0)
		)
		(min_thickness 0.25)
		(keepout
			(tracks allowed)
			(vias allowed)
			(pads allowed)
			(copperpour allowed)
			(footprints allowed)
		)
		(placement
			(enabled no)
			(sheetname "")
		)
		(fill
			(thermal_gap 0.5)
			(thermal_bridge_width 0.5)
			(island_removal_mode 0)
		)
		(polygon
			(pts
				(xy 435.567582 -306.36464) (xy 435.567582 -305.012598) (xy 436.143146 -305.012598) (xy 436.143146 -306.36464)
			)
		)
	)
	(zone
		(layer "In6.Cu")
		(hatch none 0.5)
		(connect_pads
			(clearance 0)
		)
		(min_thickness 0.25)
		(keepout
			(tracks allowed)
			(vias allowed)
			(pads allowed)
			(copperpour allowed)
			(footprints allowed)
		)
		(placement
			(enabled no)
			(sheetname "")
		)
		(fill
			(thermal_gap 0.5)
			(thermal_bridge_width 0.5)
			(island_removal_mode 0)
		)
		(polygon
			(pts
				(xy 268.578076 -207.756252) (xy 268.578076 -206.434182) (xy 269.105634 -206.434182) (xy 269.105634 -207.756252)
			)
		)
	)
	(zone
		(layer "In6.Cu")
		(hatch none 0.5)
		(connect_pads
			(clearance 0)
		)
		(min_thickness 0.25)
		(keepout
			(tracks allowed)
			(vias allowed)
			(pads allowed)
			(copperpour allowed)
			(footprints allowed)
		)
		(placement
			(enabled no)
			(sheetname "")
		)
		(fill
			(thermal_gap 0.5)
			(thermal_bridge_width 0.5)
			(island_removal_mode 0)
		)
		(polygon
			(pts
				(xy 424.488102 -208.60258) (xy 424.488102 -207.24622) (xy 425.118276 -207.24622) (xy 425.118276 -208.60258)
			)
		)
	)
	(zone
		(layer "In6.Cu")
		(hatch none 0.5)
		(connect_pads
			(clearance 0)
		)
		(min_thickness 0.25)
		(keepout
			(tracks allowed)
			(vias allowed)
			(pads allowed)
			(copperpour allowed)
			(footprints allowed)
		)
		(placement
			(enabled no)
			(sheetname "")
		)
		(fill
			(thermal_gap 0.5)
			(thermal_bridge_width 0.5)
			(island_removal_mode 0)
		)
		(polygon
			(pts
				(xy 35.725608 -223.906334) (xy 35.725608 -222.584264) (xy 36.253166 -222.584264) (xy 36.253166 -223.906334)
			)
		)
	)
	(zone
		(layer "In6.Cu")
		(hatch none 0.5)
		(connect_pads
			(clearance 0)
		)
		(min_thickness 0.25)
		(keepout
			(tracks allowed)
			(vias allowed)
			(pads allowed)
			(copperpour allowed)
			(footprints allowed)
		)
		(placement
			(enabled no)
			(sheetname "")
		)
		(fill
			(thermal_gap 0.5)
			(thermal_bridge_width 0.5)
			(island_removal_mode 0)
		)
		(polygon
			(pts
				(xy 35.602672 -272.415) (xy 35.602672 -270.147542) (xy 36.28771 -270.147542) (xy 36.28771 -272.415)
			)
		)
	)
	(zone
		(layer "In6.Cu")
		(hatch none 0.5)
		(connect_pads
			(clearance 0)
		)
		(min_thickness 0.25)
		(keepout
			(tracks allowed)
			(vias allowed)
			(pads allowed)
			(copperpour allowed)
			(footprints allowed)
		)
		(placement
			(enabled no)
			(sheetname "")
		)
		(fill
			(thermal_gap 0.5)
			(thermal_bridge_width 0.5)
			(island_removal_mode 0)
		)
		(polygon
			(pts
				(xy 435.567582 -247.714516) (xy 435.567582 -245.561358) (xy 436.143146 -245.561358) (xy 436.143146 -247.714516)
			)
		)
	)
	(zone
		(layer "In6.Cu")
		(hatch none 0.5)
		(connect_pads
			(clearance 0)
		)
		(min_thickness 0.25)
		(keepout
			(tracks allowed)
			(vias allowed)
			(pads allowed)
			(copperpour allowed)
			(footprints allowed)
		)
		(placement
			(enabled no)
			(sheetname "")
		)
		(fill
			(thermal_gap 0.5)
			(thermal_bridge_width 0.5)
			(island_removal_mode 0)
		)
		(polygon
			(pts
				(xy 176.639982 -311.464452) (xy 176.639982 -305.926998) (xy 177.215546 -305.926998) (xy 177.215546 -311.464452)
			)
		)
	)
	(zone
		(layer "In7.Cu")
		(hatch none 0.5)
		(connect_pads
			(clearance 0)
		)
		(min_thickness 0.25)
		(keepout
			(tracks not_allowed)
			(vias allowed)
			(pads allowed)
			(copperpour not_allowed)
			(footprints allowed)
		)
		(placement
			(enabled no)
			(sheetname "")
		)
		(fill
			(thermal_gap 0.5)
			(thermal_bridge_width 0.5)
			(island_removal_mode 0)
		)
		(polygon
			(pts
				(arc
					(start 387.24205 -439.76036)
					(mid 387.264368 -439.814242)
					(end 387.31825 -439.83656)
				)
				(arc
					(start 388.25805 -439.83656)
					(mid 388.311932 -439.814242)
					(end 388.33425 -439.76036)
				)
				(arc
					(start 388.33425 -437.218836)
					(mid 388.311932 -437.164954)
					(end 388.25805 -437.142636)
				)
				(arc
					(start 387.31825 -437.142636)
					(mid 387.264368 -437.164954)
					(end 387.24205 -437.218836)
				)
			)
		)
	)
	(zone
		(layer "In7.Cu")
		(hatch none 0.5)
		(connect_pads
			(clearance 0)
		)
		(min_thickness 0.25)
		(keepout
			(tracks not_allowed)
			(vias allowed)
			(pads allowed)
			(copperpour not_allowed)
			(footprints allowed)
		)
		(placement
			(enabled no)
			(sheetname "")
		)
		(fill
			(thermal_gap 0.5)
			(thermal_bridge_width 0.5)
			(island_removal_mode 0)
		)
		(polygon
			(pts
				(arc
					(start 393.242038 -438.760362)
					(mid 393.264356 -438.814244)
					(end 393.318238 -438.836562)
				)
				(arc
					(start 394.258038 -438.836562)
					(mid 394.31192 -438.814244)
					(end 394.334238 -438.760362)
				)
				(arc
					(start 394.334238 -436.218838)
					(mid 394.31192 -436.164956)
					(end 394.258038 -436.142638)
				)
				(arc
					(start 393.318238 -436.142638)
					(mid 393.264356 -436.164956)
					(end 393.242038 -436.218838)
				)
			)
		)
	)
	(zone
		(layer "In7.Cu")
		(hatch none 0.5)
		(connect_pads
			(clearance 0)
		)
		(min_thickness 0.25)
		(keepout
			(tracks not_allowed)
			(vias allowed)
			(pads allowed)
			(copperpour not_allowed)
			(footprints allowed)
		)
		(placement
			(enabled no)
			(sheetname "")
		)
		(fill
			(thermal_gap 0.5)
			(thermal_bridge_width 0.5)
			(island_removal_mode 0)
		)
		(polygon
			(pts
				(arc
					(start 412.242 -439.76036)
					(mid 412.264318 -439.814242)
					(end 412.3182 -439.83656)
				)
				(arc
					(start 413.258 -439.83656)
					(mid 413.311882 -439.814242)
					(end 413.3342 -439.76036)
				)
				(arc
					(start 413.3342 -437.218836)
					(mid 413.311882 -437.164954)
					(end 413.258 -437.142636)
				)
				(arc
					(start 412.3182 -437.142636)
					(mid 412.264318 -437.164954)
					(end 412.242 -437.218836)
				)
			)
		)
	)
	(zone
		(layer "In7.Cu")
		(hatch none 0.5)
		(connect_pads
			(clearance 0)
		)
		(min_thickness 0.25)
		(keepout
			(tracks not_allowed)
			(vias allowed)
			(pads allowed)
			(copperpour not_allowed)
			(footprints allowed)
		)
		(placement
			(enabled no)
			(sheetname "")
		)
		(fill
			(thermal_gap 0.5)
			(thermal_bridge_width 0.5)
			(island_removal_mode 0)
		)
		(polygon
			(pts
				(arc
					(start 127.242062 -439.76036)
					(mid 127.26438 -439.814242)
					(end 127.318262 -439.83656)
				)
				(arc
					(start 128.258062 -439.83656)
					(mid 128.311944 -439.814242)
					(end 128.334262 -439.76036)
				)
				(arc
					(start 128.334262 -437.218836)
					(mid 128.311944 -437.164954)
					(end 128.258062 -437.142636)
				)
				(arc
					(start 127.318262 -437.142636)
					(mid 127.26438 -437.164954)
					(end 127.242062 -437.218836)
				)
			)
		)
	)
	(zone
		(layer "In7.Cu")
		(hatch none 0.5)
		(connect_pads
			(clearance 0)
		)
		(min_thickness 0.25)
		(keepout
			(tracks not_allowed)
			(vias allowed)
			(pads allowed)
			(copperpour not_allowed)
			(footprints allowed)
		)
		(placement
			(enabled no)
			(sheetname "")
		)
		(fill
			(thermal_gap 0.5)
			(thermal_bridge_width 0.5)
			(island_removal_mode 0)
		)
		(polygon
			(pts
				(arc
					(start 383.242058 -439.76036)
					(mid 383.264376 -439.814242)
					(end 383.318258 -439.83656)
				)
				(arc
					(start 384.258058 -439.83656)
					(mid 384.31194 -439.814242)
					(end 384.334258 -439.76036)
				)
				(arc
					(start 384.334258 -437.218836)
					(mid 384.31194 -437.164954)
					(end 384.258058 -437.142636)
				)
				(arc
					(start 383.318258 -437.142636)
					(mid 383.264376 -437.164954)
					(end 383.242058 -437.218836)
				)
			)
		)
	)
	(zone
		(layer "In7.Cu")
		(hatch none 0.5)
		(connect_pads
			(clearance 0)
		)
		(min_thickness 0.25)
		(keepout
			(tracks not_allowed)
			(vias allowed)
			(pads allowed)
			(copperpour not_allowed)
			(footprints allowed)
		)
		(placement
			(enabled no)
			(sheetname "")
		)
		(fill
			(thermal_gap 0.5)
			(thermal_bridge_width 0.5)
			(island_removal_mode 0)
		)
		(polygon
			(pts
				(arc
					(start 125.242066 -438.760362)
					(mid 125.264384 -438.814244)
					(end 125.318266 -438.836562)
				)
				(arc
					(start 126.258066 -438.836562)
					(mid 126.311948 -438.814244)
					(end 126.334266 -438.760362)
				)
				(arc
					(start 126.334266 -436.218838)
					(mid 126.311948 -436.164956)
					(end 126.258066 -436.142638)
				)
				(arc
					(start 125.318266 -436.142638)
					(mid 125.264384 -436.164956)
					(end 125.242066 -436.218838)
				)
			)
		)
	)
	(zone
		(layer "In7.Cu")
		(hatch none 0.5)
		(connect_pads
			(clearance 0)
		)
		(min_thickness 0.25)
		(keepout
			(tracks not_allowed)
			(vias allowed)
			(pads allowed)
			(copperpour not_allowed)
			(footprints allowed)
		)
		(placement
			(enabled no)
			(sheetname "")
		)
		(fill
			(thermal_gap 0.5)
			(thermal_bridge_width 0.5)
			(island_removal_mode 0)
		)
		(polygon
			(pts
				(arc
					(start 146.242024 -438.760362)
					(mid 146.264342 -438.814244)
					(end 146.318224 -438.836562)
				)
				(arc
					(start 147.258024 -438.836562)
					(mid 147.311906 -438.814244)
					(end 147.334224 -438.760362)
				)
				(arc
					(start 147.334224 -436.218838)
					(mid 147.311906 -436.164956)
					(end 147.258024 -436.142638)
				)
				(arc
					(start 146.318224 -436.142638)
					(mid 146.264342 -436.164956)
					(end 146.242024 -436.218838)
				)
			)
		)
	)
	(zone
		(layer "In7.Cu")
		(hatch none 0.5)
		(connect_pads
			(clearance 0)
		)
		(min_thickness 0.25)
		(keepout
			(tracks not_allowed)
			(vias allowed)
			(pads allowed)
			(copperpour not_allowed)
			(footprints allowed)
		)
		(placement
			(enabled no)
			(sheetname "")
		)
		(fill
			(thermal_gap 0.5)
			(thermal_bridge_width 0.5)
			(island_removal_mode 0)
		)
		(polygon
			(pts
				(arc
					(start 381.242062 -438.760362)
					(mid 381.26438 -438.814244)
					(end 381.318262 -438.836562)
				)
				(arc
					(start 382.258062 -438.836562)
					(mid 382.311944 -438.814244)
					(end 382.334262 -438.760362)
				)
				(arc
					(start 382.334262 -436.218838)
					(mid 382.311944 -436.164956)
					(end 382.258062 -436.142638)
				)
				(arc
					(start 381.318262 -436.142638)
					(mid 381.26438 -436.164956)
					(end 381.242062 -436.218838)
				)
			)
		)
	)
	(zone
		(layer "In7.Cu")
		(hatch none 0.5)
		(connect_pads
			(clearance 0)
		)
		(min_thickness 0.25)
		(keepout
			(tracks not_allowed)
			(vias allowed)
			(pads allowed)
			(copperpour not_allowed)
			(footprints allowed)
		)
		(placement
			(enabled no)
			(sheetname "")
		)
		(fill
			(thermal_gap 0.5)
			(thermal_bridge_width 0.5)
			(island_removal_mode 0)
		)
		(polygon
			(pts
				(arc
					(start 398.242028 -438.760362)
					(mid 398.264346 -438.814244)
					(end 398.318228 -438.836562)
				)
				(arc
					(start 399.258028 -438.836562)
					(mid 399.31191 -438.814244)
					(end 399.334228 -438.760362)
				)
				(arc
					(start 399.334228 -436.218838)
					(mid 399.31191 -436.164956)
					(end 399.258028 -436.142638)
				)
				(arc
					(start 398.318228 -436.142638)
					(mid 398.264346 -436.164956)
					(end 398.242028 -436.218838)
				)
			)
		)
	)
	(zone
		(layer "In7.Cu")
		(hatch none 0.5)
		(connect_pads
			(clearance 0)
		)
		(min_thickness 0.25)
		(keepout
			(tracks not_allowed)
			(vias allowed)
			(pads allowed)
			(copperpour not_allowed)
			(footprints allowed)
		)
		(placement
			(enabled no)
			(sheetname "")
		)
		(fill
			(thermal_gap 0.5)
			(thermal_bridge_width 0.5)
			(island_removal_mode 0)
		)
		(polygon
			(pts
				(arc
					(start 135.242046 -439.76036)
					(mid 135.264364 -439.814242)
					(end 135.318246 -439.83656)
				)
				(arc
					(start 136.258046 -439.83656)
					(mid 136.311928 -439.814242)
					(end 136.334246 -439.76036)
				)
				(arc
					(start 136.334246 -437.218836)
					(mid 136.311928 -437.164954)
					(end 136.258046 -437.142636)
				)
				(arc
					(start 135.318246 -437.142636)
					(mid 135.264364 -437.164954)
					(end 135.242046 -437.218836)
				)
			)
		)
	)
	(zone
		(layer "In7.Cu")
		(hatch none 0.5)
		(connect_pads
			(clearance 0)
		)
		(min_thickness 0.25)
		(keepout
			(tracks not_allowed)
			(vias allowed)
			(pads allowed)
			(copperpour not_allowed)
			(footprints allowed)
		)
		(placement
			(enabled no)
			(sheetname "")
		)
		(fill
			(thermal_gap 0.5)
			(thermal_bridge_width 0.5)
			(island_removal_mode 0)
		)
		(polygon
			(pts
				(arc
					(start 408.242008 -439.76036)
					(mid 408.264326 -439.814242)
					(end 408.318208 -439.83656)
				)
				(arc
					(start 409.258008 -439.83656)
					(mid 409.31189 -439.814242)
					(end 409.334208 -439.76036)
				)
				(arc
					(start 409.334208 -437.218836)
					(mid 409.31189 -437.164954)
					(end 409.258008 -437.142636)
				)
				(arc
					(start 408.318208 -437.142636)
					(mid 408.264326 -437.164954)
					(end 408.242008 -437.218836)
				)
			)
		)
	)
	(zone
		(layer "In7.Cu")
		(hatch none 0.5)
		(connect_pads
			(clearance 0)
		)
		(min_thickness 0.25)
		(keepout
			(tracks not_allowed)
			(vias allowed)
			(pads allowed)
			(copperpour not_allowed)
			(footprints allowed)
		)
		(placement
			(enabled no)
			(sheetname "")
		)
		(fill
			(thermal_gap 0.5)
			(thermal_bridge_width 0.5)
			(island_removal_mode 0)
		)
		(polygon
			(pts
				(arc
					(start 406.242012 -438.760362)
					(mid 406.26433 -438.814244)
					(end 406.318212 -438.836562)
				)
				(arc
					(start 407.258012 -438.836562)
					(mid 407.311894 -438.814244)
					(end 407.334212 -438.760362)
				)
				(arc
					(start 407.334212 -436.218838)
					(mid 407.311894 -436.164956)
					(end 407.258012 -436.142638)
				)
				(arc
					(start 406.318212 -436.142638)
					(mid 406.26433 -436.164956)
					(end 406.242012 -436.218838)
				)
			)
		)
	)
	(zone
		(layer "In7.Cu")
		(hatch none 0.5)
		(connect_pads
			(clearance 0)
		)
		(min_thickness 0.25)
		(keepout
			(tracks not_allowed)
			(vias allowed)
			(pads allowed)
			(copperpour not_allowed)
			(footprints allowed)
		)
		(placement
			(enabled no)
			(sheetname "")
		)
		(fill
			(thermal_gap 0.5)
			(thermal_bridge_width 0.5)
			(island_removal_mode 0)
		)
		(polygon
			(pts
				(arc
					(start 400.242024 -439.76036)
					(mid 400.264342 -439.814242)
					(end 400.318224 -439.83656)
				)
				(arc
					(start 401.258024 -439.83656)
					(mid 401.311906 -439.814242)
					(end 401.334224 -439.76036)
				)
				(arc
					(start 401.334224 -437.218836)
					(mid 401.311906 -437.164954)
					(end 401.258024 -437.142636)
				)
				(arc
					(start 400.318224 -437.142636)
					(mid 400.264342 -437.164954)
					(end 400.242024 -437.218836)
				)
			)
		)
	)
	(zone
		(layer "In7.Cu")
		(hatch none 0.5)
		(connect_pads
			(clearance 0)
		)
		(min_thickness 0.25)
		(keepout
			(tracks not_allowed)
			(vias allowed)
			(pads allowed)
			(copperpour not_allowed)
			(footprints allowed)
		)
		(placement
			(enabled no)
			(sheetname "")
		)
		(fill
			(thermal_gap 0.5)
			(thermal_bridge_width 0.5)
			(island_removal_mode 0)
		)
		(polygon
			(pts
				(arc
					(start 402.24202 -438.760362)
					(mid 402.264338 -438.814244)
					(end 402.31822 -438.836562)
				)
				(arc
					(start 403.25802 -438.836562)
					(mid 403.311902 -438.814244)
					(end 403.33422 -438.760362)
				)
				(arc
					(start 403.33422 -436.218838)
					(mid 403.311902 -436.164956)
					(end 403.25802 -436.142638)
				)
				(arc
					(start 402.31822 -436.142638)
					(mid 402.264338 -436.164956)
					(end 402.24202 -436.218838)
				)
			)
		)
	)
	(zone
		(layer "In7.Cu")
		(hatch none 0.5)
		(connect_pads
			(clearance 0)
		)
		(min_thickness 0.25)
		(keepout
			(tracks not_allowed)
			(vias allowed)
			(pads allowed)
			(copperpour not_allowed)
			(footprints allowed)
		)
		(placement
			(enabled no)
			(sheetname "")
		)
		(fill
			(thermal_gap 0.5)
			(thermal_bridge_width 0.5)
			(island_removal_mode 0)
		)
		(polygon
			(pts
				(arc
					(start 154.242008 -438.760362)
					(mid 154.264326 -438.814244)
					(end 154.318208 -438.836562)
				)
				(arc
					(start 155.258008 -438.836562)
					(mid 155.31189 -438.814244)
					(end 155.334208 -438.760362)
				)
				(arc
					(start 155.334208 -436.218838)
					(mid 155.31189 -436.164956)
					(end 155.258008 -436.142638)
				)
				(arc
					(start 154.318208 -436.142638)
					(mid 154.264326 -436.164956)
					(end 154.242008 -436.218838)
				)
			)
		)
	)
	(zone
		(layer "In7.Cu")
		(hatch none 0.5)
		(connect_pads
			(clearance 0)
		)
		(min_thickness 0.25)
		(keepout
			(tracks not_allowed)
			(vias allowed)
			(pads allowed)
			(copperpour not_allowed)
			(footprints allowed)
		)
		(placement
			(enabled no)
			(sheetname "")
		)
		(fill
			(thermal_gap 0.5)
			(thermal_bridge_width 0.5)
			(island_removal_mode 0)
		)
		(polygon
			(pts
				(arc
					(start 131.242054 -439.76036)
					(mid 131.264372 -439.814242)
					(end 131.318254 -439.83656)
				)
				(arc
					(start 132.258054 -439.83656)
					(mid 132.311936 -439.814242)
					(end 132.334254 -439.76036)
				)
				(arc
					(start 132.334254 -437.218836)
					(mid 132.311936 -437.164954)
					(end 132.258054 -437.142636)
				)
				(arc
					(start 131.318254 -437.142636)
					(mid 131.264372 -437.164954)
					(end 131.242054 -437.218836)
				)
			)
		)
	)
	(zone
		(layer "In7.Cu")
		(hatch none 0.5)
		(connect_pads
			(clearance 0)
		)
		(min_thickness 0.25)
		(keepout
			(tracks not_allowed)
			(vias allowed)
			(pads allowed)
			(copperpour not_allowed)
			(footprints allowed)
		)
		(placement
			(enabled no)
			(sheetname "")
		)
		(fill
			(thermal_gap 0.5)
			(thermal_bridge_width 0.5)
			(island_removal_mode 0)
		)
		(polygon
			(pts
				(arc
					(start 389.242046 -438.760362)
					(mid 389.264364 -438.814244)
					(end 389.318246 -438.836562)
				)
				(arc
					(start 390.258046 -438.836562)
					(mid 390.311928 -438.814244)
					(end 390.334246 -438.760362)
				)
				(arc
					(start 390.334246 -436.218838)
					(mid 390.311928 -436.164956)
					(end 390.258046 -436.142638)
				)
				(arc
					(start 389.318246 -436.142638)
					(mid 389.264364 -436.164956)
					(end 389.242046 -436.218838)
				)
			)
		)
	)
	(zone
		(layer "In7.Cu")
		(hatch none 0.5)
		(connect_pads
			(clearance 0)
		)
		(min_thickness 0.25)
		(keepout
			(tracks not_allowed)
			(vias allowed)
			(pads allowed)
			(copperpour not_allowed)
			(footprints allowed)
		)
		(placement
			(enabled no)
			(sheetname "")
		)
		(fill
			(thermal_gap 0.5)
			(thermal_bridge_width 0.5)
			(island_removal_mode 0)
		)
		(polygon
			(pts
				(arc
					(start 152.242012 -439.76036)
					(mid 152.26433 -439.814242)
					(end 152.318212 -439.83656)
				)
				(arc
					(start 153.258012 -439.83656)
					(mid 153.311894 -439.814242)
					(end 153.334212 -439.76036)
				)
				(arc
					(start 153.334212 -437.218836)
					(mid 153.311894 -437.164954)
					(end 153.258012 -437.142636)
				)
				(arc
					(start 152.318212 -437.142636)
					(mid 152.26433 -437.164954)
					(end 152.242012 -437.218836)
				)
			)
		)
	)
	(zone
		(layer "In7.Cu")
		(hatch none 0.5)
		(connect_pads
			(clearance 0)
		)
		(min_thickness 0.25)
		(keepout
			(tracks not_allowed)
			(vias allowed)
			(pads allowed)
			(copperpour not_allowed)
			(footprints allowed)
		)
		(placement
			(enabled no)
			(sheetname "")
		)
		(fill
			(thermal_gap 0.5)
			(thermal_bridge_width 0.5)
			(island_removal_mode 0)
		)
		(polygon
			(pts
				(arc
					(start 137.242042 -438.760362)
					(mid 137.26436 -438.814244)
					(end 137.318242 -438.836562)
				)
				(arc
					(start 138.258042 -438.836562)
					(mid 138.311924 -438.814244)
					(end 138.334242 -438.760362)
				)
				(arc
					(start 138.334242 -436.218838)
					(mid 138.311924 -436.164956)
					(end 138.258042 -436.142638)
				)
				(arc
					(start 137.318242 -436.142638)
					(mid 137.26436 -436.164956)
					(end 137.242042 -436.218838)
				)
			)
		)
	)
	(zone
		(layer "In7.Cu")
		(hatch none 0.5)
		(connect_pads
			(clearance 0)
		)
		(min_thickness 0.25)
		(keepout
			(tracks not_allowed)
			(vias allowed)
			(pads allowed)
			(copperpour not_allowed)
			(footprints allowed)
		)
		(placement
			(enabled no)
			(sheetname "")
		)
		(fill
			(thermal_gap 0.5)
			(thermal_bridge_width 0.5)
			(island_removal_mode 0)
		)
		(polygon
			(pts
				(arc
					(start 139.242038 -439.76036)
					(mid 139.264356 -439.814242)
					(end 139.318238 -439.83656)
				)
				(arc
					(start 140.258038 -439.83656)
					(mid 140.31192 -439.814242)
					(end 140.334238 -439.76036)
				)
				(arc
					(start 140.334238 -437.218836)
					(mid 140.31192 -437.164954)
					(end 140.258038 -437.142636)
				)
				(arc
					(start 139.318238 -437.142636)
					(mid 139.264356 -437.164954)
					(end 139.242038 -437.218836)
				)
			)
		)
	)
	(zone
		(layer "In7.Cu")
		(hatch none 0.5)
		(connect_pads
			(clearance 0)
		)
		(min_thickness 0.25)
		(keepout
			(tracks not_allowed)
			(vias allowed)
			(pads allowed)
			(copperpour not_allowed)
			(footprints allowed)
		)
		(placement
			(enabled no)
			(sheetname "")
		)
		(fill
			(thermal_gap 0.5)
			(thermal_bridge_width 0.5)
			(island_removal_mode 0)
		)
		(polygon
			(pts
				(arc
					(start 156.242004 -439.76036)
					(mid 156.264322 -439.814242)
					(end 156.318204 -439.83656)
				)
				(arc
					(start 157.258004 -439.83656)
					(mid 157.311886 -439.814242)
					(end 157.334204 -439.76036)
				)
				(arc
					(start 157.334204 -437.218836)
					(mid 157.311886 -437.164954)
					(end 157.258004 -437.142636)
				)
				(arc
					(start 156.318204 -437.142636)
					(mid 156.264322 -437.164954)
					(end 156.242004 -437.218836)
				)
			)
		)
	)
	(zone
		(layer "In7.Cu")
		(hatch none 0.5)
		(connect_pads
			(clearance 0)
		)
		(min_thickness 0.25)
		(keepout
			(tracks not_allowed)
			(vias allowed)
			(pads allowed)
			(copperpour not_allowed)
			(footprints allowed)
		)
		(placement
			(enabled no)
			(sheetname "")
		)
		(fill
			(thermal_gap 0.5)
			(thermal_bridge_width 0.5)
			(island_removal_mode 0)
		)
		(polygon
			(pts
				(arc
					(start 410.242004 -438.760362)
					(mid 410.264322 -438.814244)
					(end 410.318204 -438.836562)
				)
				(arc
					(start 411.258004 -438.836562)
					(mid 411.311886 -438.814244)
					(end 411.334204 -438.760362)
				)
				(arc
					(start 411.334204 -436.218838)
					(mid 411.311886 -436.164956)
					(end 411.258004 -436.142638)
				)
				(arc
					(start 410.318204 -436.142638)
					(mid 410.264322 -436.164956)
					(end 410.242004 -436.218838)
				)
			)
		)
	)
	(zone
		(layer "In7.Cu")
		(hatch none 0.5)
		(connect_pads
			(clearance 0)
		)
		(min_thickness 0.25)
		(keepout
			(tracks not_allowed)
			(vias allowed)
			(pads allowed)
			(copperpour not_allowed)
			(footprints allowed)
		)
		(placement
			(enabled no)
			(sheetname "")
		)
		(fill
			(thermal_gap 0.5)
			(thermal_bridge_width 0.5)
			(island_removal_mode 0)
		)
		(polygon
			(pts
				(arc
					(start 391.242042 -439.76036)
					(mid 391.26436 -439.814242)
					(end 391.318242 -439.83656)
				)
				(arc
					(start 392.258042 -439.83656)
					(mid 392.311924 -439.814242)
					(end 392.334242 -439.76036)
				)
				(arc
					(start 392.334242 -437.218836)
					(mid 392.311924 -437.164954)
					(end 392.258042 -437.142636)
				)
				(arc
					(start 391.318242 -437.142636)
					(mid 391.26436 -437.164954)
					(end 391.242042 -437.218836)
				)
			)
		)
	)
	(zone
		(layer "In7.Cu")
		(hatch none 0.5)
		(connect_pads
			(clearance 0)
		)
		(min_thickness 0.25)
		(keepout
			(tracks not_allowed)
			(vias allowed)
			(pads allowed)
			(copperpour not_allowed)
			(footprints allowed)
		)
		(placement
			(enabled no)
			(sheetname "")
		)
		(fill
			(thermal_gap 0.5)
			(thermal_bridge_width 0.5)
			(island_removal_mode 0)
		)
		(polygon
			(pts
				(arc
					(start 395.242034 -439.76036)
					(mid 395.264352 -439.814242)
					(end 395.318234 -439.83656)
				)
				(arc
					(start 396.258034 -439.83656)
					(mid 396.311916 -439.814242)
					(end 396.334234 -439.76036)
				)
				(arc
					(start 396.334234 -437.218836)
					(mid 396.311916 -437.164954)
					(end 396.258034 -437.142636)
				)
				(arc
					(start 395.318234 -437.142636)
					(mid 395.264352 -437.164954)
					(end 395.242034 -437.218836)
				)
			)
		)
	)
	(zone
		(layer "In7.Cu")
		(hatch none 0.5)
		(connect_pads
			(clearance 0)
		)
		(min_thickness 0.25)
		(keepout
			(tracks not_allowed)
			(vias allowed)
			(pads allowed)
			(copperpour not_allowed)
			(footprints allowed)
		)
		(placement
			(enabled no)
			(sheetname "")
		)
		(fill
			(thermal_gap 0.5)
			(thermal_bridge_width 0.5)
			(island_removal_mode 0)
		)
		(polygon
			(pts
				(arc
					(start 148.24202 -439.76036)
					(mid 148.264338 -439.814242)
					(end 148.31822 -439.83656)
				)
				(arc
					(start 149.25802 -439.83656)
					(mid 149.311902 -439.814242)
					(end 149.33422 -439.76036)
				)
				(arc
					(start 149.33422 -437.218836)
					(mid 149.311902 -437.164954)
					(end 149.25802 -437.142636)
				)
				(arc
					(start 148.31822 -437.142636)
					(mid 148.264338 -437.164954)
					(end 148.24202 -437.218836)
				)
			)
		)
	)
	(zone
		(layer "In7.Cu")
		(hatch none 0.5)
		(connect_pads
			(clearance 0)
		)
		(min_thickness 0.25)
		(keepout
			(tracks not_allowed)
			(vias allowed)
			(pads allowed)
			(copperpour not_allowed)
			(footprints allowed)
		)
		(placement
			(enabled no)
			(sheetname "")
		)
		(fill
			(thermal_gap 0.5)
			(thermal_bridge_width 0.5)
			(island_removal_mode 0)
		)
		(polygon
			(pts
				(arc
					(start 144.242028 -439.76036)
					(mid 144.264346 -439.814242)
					(end 144.318228 -439.83656)
				)
				(arc
					(start 145.258028 -439.83656)
					(mid 145.31191 -439.814242)
					(end 145.334228 -439.76036)
				)
				(arc
					(start 145.334228 -437.218836)
					(mid 145.31191 -437.164954)
					(end 145.258028 -437.142636)
				)
				(arc
					(start 144.318228 -437.142636)
					(mid 144.264346 -437.164954)
					(end 144.242028 -437.218836)
				)
			)
		)
	)
	(zone
		(layer "In7.Cu")
		(hatch none 0.5)
		(connect_pads
			(clearance 0)
		)
		(min_thickness 0.25)
		(keepout
			(tracks not_allowed)
			(vias allowed)
			(pads allowed)
			(copperpour not_allowed)
			(footprints allowed)
		)
		(placement
			(enabled no)
			(sheetname "")
		)
		(fill
			(thermal_gap 0.5)
			(thermal_bridge_width 0.5)
			(island_removal_mode 0)
		)
		(polygon
			(pts
				(arc
					(start 133.24205 -438.760362)
					(mid 133.264368 -438.814244)
					(end 133.31825 -438.836562)
				)
				(arc
					(start 134.25805 -438.836562)
					(mid 134.311932 -438.814244)
					(end 134.33425 -438.760362)
				)
				(arc
					(start 134.33425 -436.218838)
					(mid 134.311932 -436.164956)
					(end 134.25805 -436.142638)
				)
				(arc
					(start 133.31825 -436.142638)
					(mid 133.264368 -436.164956)
					(end 133.24205 -436.218838)
				)
			)
		)
	)
	(zone
		(layer "In7.Cu")
		(hatch none 0.5)
		(connect_pads
			(clearance 0)
		)
		(min_thickness 0.25)
		(keepout
			(tracks not_allowed)
			(vias allowed)
			(pads allowed)
			(copperpour not_allowed)
			(footprints allowed)
		)
		(placement
			(enabled no)
			(sheetname "")
		)
		(fill
			(thermal_gap 0.5)
			(thermal_bridge_width 0.5)
			(island_removal_mode 0)
		)
		(polygon
			(pts
				(arc
					(start 150.242016 -438.760362)
					(mid 150.264334 -438.814244)
					(end 150.318216 -438.836562)
				)
				(arc
					(start 151.258016 -438.836562)
					(mid 151.311898 -438.814244)
					(end 151.334216 -438.760362)
				)
				(arc
					(start 151.334216 -436.218838)
					(mid 151.311898 -436.164956)
					(end 151.258016 -436.142638)
				)
				(arc
					(start 150.318216 -436.142638)
					(mid 150.264334 -436.164956)
					(end 150.242016 -436.218838)
				)
			)
		)
	)
	(zone
		(layer "In7.Cu")
		(hatch none 0.5)
		(connect_pads
			(clearance 0)
		)
		(min_thickness 0.25)
		(keepout
			(tracks not_allowed)
			(vias allowed)
			(pads allowed)
			(copperpour not_allowed)
			(footprints allowed)
		)
		(placement
			(enabled no)
			(sheetname "")
		)
		(fill
			(thermal_gap 0.5)
			(thermal_bridge_width 0.5)
			(island_removal_mode 0)
		)
		(polygon
			(pts
				(arc
					(start 404.242016 -439.76036)
					(mid 404.264334 -439.814242)
					(end 404.318216 -439.83656)
				)
				(arc
					(start 405.258016 -439.83656)
					(mid 405.311898 -439.814242)
					(end 405.334216 -439.76036)
				)
				(arc
					(start 405.334216 -437.218836)
					(mid 405.311898 -437.164954)
					(end 405.258016 -437.142636)
				)
				(arc
					(start 404.318216 -437.142636)
					(mid 404.264334 -437.164954)
					(end 404.242016 -437.218836)
				)
			)
		)
	)
	(zone
		(layer "In7.Cu")
		(hatch none 0.5)
		(connect_pads
			(clearance 0)
		)
		(min_thickness 0.25)
		(keepout
			(tracks not_allowed)
			(vias allowed)
			(pads allowed)
			(copperpour not_allowed)
			(footprints allowed)
		)
		(placement
			(enabled no)
			(sheetname "")
		)
		(fill
			(thermal_gap 0.5)
			(thermal_bridge_width 0.5)
			(island_removal_mode 0)
		)
		(polygon
			(pts
				(arc
					(start 142.242032 -438.760362)
					(mid 142.26435 -438.814244)
					(end 142.318232 -438.836562)
				)
				(arc
					(start 143.258032 -438.836562)
					(mid 143.311914 -438.814244)
					(end 143.334232 -438.760362)
				)
				(arc
					(start 143.334232 -436.218838)
					(mid 143.311914 -436.164956)
					(end 143.258032 -436.142638)
				)
				(arc
					(start 142.318232 -436.142638)
					(mid 142.26435 -436.164956)
					(end 142.242032 -436.218838)
				)
			)
		)
	)
	(zone
		(layer "In7.Cu")
		(hatch none 0.5)
		(connect_pads
			(clearance 0)
		)
		(min_thickness 0.25)
		(keepout
			(tracks not_allowed)
			(vias allowed)
			(pads allowed)
			(copperpour not_allowed)
			(footprints allowed)
		)
		(placement
			(enabled no)
			(sheetname "")
		)
		(fill
			(thermal_gap 0.5)
			(thermal_bridge_width 0.5)
			(island_removal_mode 0)
		)
		(polygon
			(pts
				(arc
					(start 385.242054 -438.760362)
					(mid 385.264372 -438.814244)
					(end 385.318254 -438.836562)
				)
				(arc
					(start 386.258054 -438.836562)
					(mid 386.311936 -438.814244)
					(end 386.334254 -438.760362)
				)
				(arc
					(start 386.334254 -436.218838)
					(mid 386.311936 -436.164956)
					(end 386.258054 -436.142638)
				)
				(arc
					(start 385.318254 -436.142638)
					(mid 385.264372 -436.164956)
					(end 385.242054 -436.218838)
				)
			)
		)
	)
	(zone
		(layer "In7.Cu")
		(hatch none 0.5)
		(connect_pads
			(clearance 0)
		)
		(min_thickness 0.25)
		(keepout
			(tracks not_allowed)
			(vias allowed)
			(pads allowed)
			(copperpour not_allowed)
			(footprints allowed)
		)
		(placement
			(enabled no)
			(sheetname "")
		)
		(fill
			(thermal_gap 0.5)
			(thermal_bridge_width 0.5)
			(island_removal_mode 0)
		)
		(polygon
			(pts
				(arc
					(start 129.242058 -438.760362)
					(mid 129.264376 -438.814244)
					(end 129.318258 -438.836562)
				)
				(arc
					(start 130.258058 -438.836562)
					(mid 130.31194 -438.814244)
					(end 130.334258 -438.760362)
				)
				(arc
					(start 130.334258 -436.218838)
					(mid 130.31194 -436.164956)
					(end 130.258058 -436.142638)
				)
				(arc
					(start 129.318258 -436.142638)
					(mid 129.264376 -436.164956)
					(end 129.242058 -436.218838)
				)
			)
		)
	)
	(zone
		(layer "In8.Cu")
		(hatch none 0.5)
		(connect_pads
			(clearance 0)
		)
		(min_thickness 0.25)
		(keepout
			(tracks not_allowed)
			(vias allowed)
			(pads allowed)
			(copperpour not_allowed)
			(footprints allowed)
		)
		(placement
			(enabled no)
			(sheetname "")
		)
		(fill
			(thermal_gap 0.5)
			(thermal_bridge_width 0.5)
			(island_removal_mode 0)
		)
		(polygon
			(pts
				(xy 7.39902 -440.540648) (xy 7.39902 -437.766968) (xy 10.72896 -437.766968) (xy 10.72896 -440.540648)
			)
		)
	)
	(zone
		(layer "In8.Cu")
		(hatch none 0.5)
		(connect_pads
			(clearance 0)
		)
		(min_thickness 0.25)
		(keepout
			(tracks not_allowed)
			(vias allowed)
			(pads allowed)
			(copperpour not_allowed)
			(footprints allowed)
		)
		(placement
			(enabled no)
			(sheetname "")
		)
		(fill
			(thermal_gap 0.5)
			(thermal_bridge_width 0.5)
			(island_removal_mode 0)
		)
		(polygon
			(pts
				(xy 461.11668 -441.170568) (xy 461.11668 -437.594248) (xy 464.74888 -437.594248) (xy 464.74888 -441.170568)
			)
		)
	)
	(zone
		(layers "In8.Cu" "In9.Cu")
		(hatch none 0.5)
		(connect_pads
			(clearance 0)
		)
		(min_thickness 0.25)
		(keepout
			(tracks not_allowed)
			(vias allowed)
			(pads allowed)
			(copperpour not_allowed)
			(footprints allowed)
		)
		(placement
			(enabled no)
			(sheetname "")
		)
		(fill yes
			(thermal_gap 0.5)
			(thermal_bridge_width 0.5)
			(island_removal_mode 0)
		)
		(polygon
			(pts
				(arc
					(start 84.955126 -353.52482)
					(mid 78.874874 -353.52482)
					(end 84.955126 -353.52482)
				)
			)
		)
	)
	(zone
		(layers "In8.Cu" "In9.Cu")
		(hatch none 0.5)
		(connect_pads
			(clearance 0)
		)
		(min_thickness 0.25)
		(keepout
			(tracks not_allowed)
			(vias allowed)
			(pads allowed)
			(copperpour not_allowed)
			(footprints allowed)
		)
		(placement
			(enabled no)
			(sheetname "")
		)
		(fill yes
			(thermal_gap 0.5)
			(thermal_bridge_width 0.5)
			(island_removal_mode 0)
		)
		(polygon
			(pts
				(arc
					(start 45.13199 -161.891218)
					(mid 43.60799 -161.891218)
					(end 45.13199 -161.891218)
				)
			)
		)
	)
	(zone
		(layers "In8.Cu" "In9.Cu")
		(hatch none 0.5)
		(connect_pads
			(clearance 0)
		)
		(min_thickness 0.25)
		(keepout
			(tracks not_allowed)
			(vias allowed)
			(pads allowed)
			(copperpour not_allowed)
			(footprints allowed)
		)
		(placement
			(enabled no)
			(sheetname "")
		)
		(fill yes
			(thermal_gap 0.5)
			(thermal_bridge_width 0.5)
			(island_removal_mode 0)
		)
		(polygon
			(pts
				(arc
					(start 387.499098 -354.434902)
					(mid 381.418846 -354.434902)
					(end 387.499098 -354.434902)
				)
			)
		)
	)
	(zone
		(layers "In8.Cu" "In9.Cu")
		(hatch none 0.5)
		(connect_pads
			(clearance 0)
		)
		(min_thickness 0.25)
		(keepout
			(tracks not_allowed)
			(vias allowed)
			(pads allowed)
			(copperpour not_allowed)
			(footprints allowed)
		)
		(placement
			(enabled no)
			(sheetname "")
		)
		(fill yes
			(thermal_gap 0.5)
			(thermal_bridge_width 0.5)
			(island_removal_mode 0)
		)
		(polygon
			(pts
				(xy 108.56468 -440.47918) (xy 108.56468 -420.87292) (xy 115.62334 -420.87292) (xy 115.62334 -440.47918)
			)
		)
	)
	(zone
		(layers "In8.Cu" "In9.Cu")
		(hatch none 0.5)
		(connect_pads
			(clearance 0)
		)
		(min_thickness 0.25)
		(keepout
			(tracks not_allowed)
			(vias allowed)
			(pads allowed)
			(copperpour not_allowed)
			(footprints allowed)
		)
		(placement
			(enabled no)
			(sheetname "")
		)
		(fill yes
			(thermal_gap 0.5)
			(thermal_bridge_width 0.5)
			(island_removal_mode 0)
		)
		(polygon
			(pts
				(arc
					(start 263.39546 -360.76382)
					(mid 252.85446 -360.76382)
					(end 263.39546 -360.76382)
				)
			)
		)
	)
	(zone
		(layers "In8.Cu" "In9.Cu")
		(hatch none 0.5)
		(connect_pads
			(clearance 0)
		)
		(min_thickness 0.25)
		(keepout
			(tracks not_allowed)
			(vias allowed)
			(pads allowed)
			(copperpour not_allowed)
			(footprints allowed)
		)
		(placement
			(enabled no)
			(sheetname "")
		)
		(fill yes
			(thermal_gap 0.5)
			(thermal_bridge_width 0.5)
			(island_removal_mode 0)
		)
		(polygon
			(pts
				(arc
					(start 218.94546 -360.76382)
					(mid 208.40446 -360.76382)
					(end 218.94546 -360.76382)
				)
			)
		)
	)
	(zone
		(layers "In8.Cu" "In9.Cu")
		(hatch none 0.5)
		(connect_pads
			(clearance 0)
		)
		(min_thickness 0.25)
		(keepout
			(tracks not_allowed)
			(vias allowed)
			(pads allowed)
			(copperpour not_allowed)
			(footprints allowed)
		)
		(placement
			(enabled no)
			(sheetname "")
		)
		(fill yes
			(thermal_gap 0.5)
			(thermal_bridge_width 0.5)
			(island_removal_mode 0)
		)
		(polygon
			(pts
				(arc
					(start 332.895194 -353.52482)
					(mid 326.814942 -353.52482)
					(end 332.895194 -353.52482)
				)
			)
		)
	)
	(zone
		(layers "In8.Cu" "In9.Cu")
		(hatch none 0.5)
		(connect_pads
			(clearance 0)
		)
		(min_thickness 0.25)
		(keepout
			(tracks not_allowed)
			(vias allowed)
			(pads allowed)
			(copperpour not_allowed)
			(footprints allowed)
		)
		(placement
			(enabled no)
			(sheetname "")
		)
		(fill yes
			(thermal_gap 0.5)
			(thermal_bridge_width 0.5)
			(island_removal_mode 0)
		)
		(polygon
			(pts
				(arc
					(start 45.057822 -169.801794)
					(mid 43.533822 -169.801794)
					(end 45.057822 -169.801794)
				)
			)
		)
	)
	(zone
		(layers "In8.Cu" "In9.Cu")
		(hatch none 0.5)
		(connect_pads
			(clearance 0)
		)
		(min_thickness 0.25)
		(keepout
			(tracks not_allowed)
			(vias allowed)
			(pads allowed)
			(copperpour not_allowed)
			(footprints allowed)
		)
		(placement
			(enabled no)
			(sheetname "")
		)
		(fill yes
			(thermal_gap 0.5)
			(thermal_bridge_width 0.5)
			(island_removal_mode 0)
		)
		(polygon
			(pts
				(xy 356.23754 -440.4614) (xy 356.23754 -420.84244) (xy 363.2962 -420.84244) (xy 363.2962 -440.4614)
			)
		)
	)
	(zone
		(layers "In8.Cu" "In9.Cu")
		(hatch none 0.5)
		(connect_pads
			(clearance 0)
		)
		(min_thickness 0.25)
		(keepout
			(tracks not_allowed)
			(vias allowed)
			(pads allowed)
			(copperpour not_allowed)
			(footprints allowed)
		)
		(placement
			(enabled no)
			(sheetname "")
		)
		(fill yes
			(thermal_gap 0.5)
			(thermal_bridge_width 0.5)
			(island_removal_mode 0)
		)
		(polygon
			(pts
				(arc
					(start 139.559284 -354.434902)
					(mid 133.479032 -354.434902)
					(end 139.559284 -354.434902)
				)
			)
		)
	)
	(zone
		(layer "Cmts.User")
		(hatch none 0.5)
		(connect_pads
			(clearance 0)
		)
		(min_thickness 0.25)
		(keepout
			(tracks allowed)
			(vias allowed)
			(pads allowed)
			(copperpour allowed)
			(footprints allowed)
		)
		(placement
			(enabled no)
			(sheetname "")
		)
		(fill
			(thermal_gap 0.5)
			(thermal_bridge_width 0.5)
			(island_removal_mode 0)
		)
		(polygon
			(pts
				(xy 419.236652 -167.4241) (xy 419.236652 -166.88054) (xy 419.742112 -166.88054) (xy 419.742112 -167.4241)
			)
		)
	)
	(zone
		(layer "Cmts.User")
		(hatch none 0.5)
		(connect_pads
			(clearance 0)
		)
		(min_thickness 0.25)
		(keepout
			(tracks allowed)
			(vias allowed)
			(pads allowed)
			(copperpour allowed)
			(footprints allowed)
		)
		(placement
			(enabled no)
			(sheetname "")
		)
		(fill
			(thermal_gap 0.5)
			(thermal_bridge_width 0.5)
			(island_removal_mode 0)
		)
		(polygon
			(pts
				(xy 417.763452 -158.7881) (xy 417.763452 -158.24454) (xy 418.268912 -158.24454) (xy 418.268912 -158.7881)
			)
		)
	)
	(zone
		(layer "Cmts.User")
		(hatch none 0.5)
		(connect_pads
			(clearance 0)
		)
		(min_thickness 0.25)
		(keepout
			(tracks allowed)
			(vias allowed)
			(pads allowed)
			(copperpour allowed)
			(footprints allowed)
		)
		(placement
			(enabled no)
			(sheetname "")
		)
		(fill
			(thermal_gap 0.5)
			(thermal_bridge_width 0.5)
			(island_removal_mode 0)
		)
		(polygon
			(pts
				(xy 419.236652 -158.7881) (xy 419.236652 -158.24454) (xy 419.742112 -158.24454) (xy 419.742112 -158.7881)
			)
		)
	)
	(zone
		(layer "Cmts.User")
		(hatch none 0.5)
		(connect_pads
			(clearance 0)
		)
		(min_thickness 0.25)
		(keepout
			(tracks allowed)
			(vias allowed)
			(pads allowed)
			(copperpour allowed)
			(footprints allowed)
		)
		(placement
			(enabled no)
			(sheetname "")
		)
		(fill
			(thermal_gap 0.5)
			(thermal_bridge_width 0.5)
			(island_removal_mode 0)
		)
		(polygon
			(pts
				(xy 314.02274 -441.272168) (xy 314.02274 -425.110148) (xy 346.59316 -425.110148) (xy 346.59316 -441.272168)
			)
		)
	)
	(zone
		(layer "Cmts.User")
		(hatch none 0.5)
		(connect_pads
			(clearance 0)
		)
		(min_thickness 0.25)
		(keepout
			(tracks allowed)
			(vias allowed)
			(pads allowed)
			(copperpour allowed)
			(footprints allowed)
		)
		(placement
			(enabled no)
			(sheetname "")
		)
		(fill
			(thermal_gap 0.5)
			(thermal_bridge_width 0.5)
			(island_removal_mode 0)
		)
		(polygon
			(pts
				(xy 50.713132 -155.77566) (xy 50.713132 -155.26258) (xy 51.224688 -155.26258) (xy 51.224688 -155.77566)
			)
		)
	)
	(zone
		(layer "Cmts.User")
		(hatch none 0.5)
		(connect_pads
			(clearance 0)
		)
		(min_thickness 0.25)
		(keepout
			(tracks allowed)
			(vias allowed)
			(pads allowed)
			(copperpour allowed)
			(footprints allowed)
		)
		(placement
			(enabled no)
			(sheetname "")
		)
		(fill
			(thermal_gap 0.5)
			(thermal_bridge_width 0.5)
			(island_removal_mode 0)
		)
		(polygon
			(pts
				(xy 446.76822 -76.883768) (xy 446.76822 -76.352908) (xy 447.3448 -76.352908) (xy 447.3448 -76.883768)
			)
		)
	)
	(zone
		(layer "Cmts.User")
		(hatch none 0.5)
		(connect_pads
			(clearance 0)
		)
		(min_thickness 0.25)
		(keepout
			(tracks allowed)
			(vias allowed)
			(pads allowed)
			(copperpour allowed)
			(footprints allowed)
		)
		(placement
			(enabled no)
			(sheetname "")
		)
		(fill
			(thermal_gap 0.5)
			(thermal_bridge_width 0.5)
			(island_removal_mode 0)
		)
		(polygon
			(pts
				(xy 53.82133 -144.526) (xy 53.82133 -144.01292) (xy 54.332886 -144.01292) (xy 54.332886 -144.526)
			)
		)
	)
	(zone
		(layer "Cmts.User")
		(hatch none 0.5)
		(connect_pads
			(clearance 0)
		)
		(min_thickness 0.25)
		(keepout
			(tracks allowed)
			(vias allowed)
			(pads allowed)
			(copperpour allowed)
			(footprints allowed)
		)
		(placement
			(enabled no)
			(sheetname "")
		)
		(fill
			(thermal_gap 0.5)
			(thermal_bridge_width 0.5)
			(island_removal_mode 0)
		)
		(polygon
			(pts
				(xy 419.275768 -165.85565) (xy 419.275768 -165.31209) (xy 419.781228 -165.31209) (xy 419.781228 -165.85565)
			)
		)
	)
	(zone
		(layer "Cmts.User")
		(hatch none 0.5)
		(connect_pads
			(clearance 0)
		)
		(min_thickness 0.25)
		(keepout
			(tracks allowed)
			(vias allowed)
			(pads allowed)
			(copperpour allowed)
			(footprints allowed)
		)
		(placement
			(enabled no)
			(sheetname "")
		)
		(fill
			(thermal_gap 0.5)
			(thermal_bridge_width 0.5)
			(island_removal_mode 0)
		)
		(polygon
			(pts
				(xy 396.63624 -187.183268) (xy 396.63624 -185.773568) (xy 397.27632 -185.773568) (xy 397.27632 -187.183268)
			)
		)
	)
	(zone
		(layer "Cmts.User")
		(hatch none 0.5)
		(connect_pads
			(clearance 0)
		)
		(min_thickness 0.25)
		(keepout
			(tracks allowed)
			(vias allowed)
			(pads allowed)
			(copperpour allowed)
			(footprints allowed)
		)
		(placement
			(enabled no)
			(sheetname "")
		)
		(fill
			(thermal_gap 0.5)
			(thermal_bridge_width 0.5)
			(island_removal_mode 0)
		)
		(polygon
			(pts
				(xy 50.334672 -148.209) (xy 50.334672 -147.69592) (xy 50.846228 -147.69592) (xy 50.846228 -148.209)
			)
		)
	)
	(zone
		(layer "Cmts.User")
		(hatch none 0.5)
		(connect_pads
			(clearance 0)
		)
		(min_thickness 0.25)
		(keepout
			(tracks allowed)
			(vias allowed)
			(pads allowed)
			(copperpour allowed)
			(footprints allowed)
		)
		(placement
			(enabled no)
			(sheetname "")
		)
		(fill
			(thermal_gap 0.5)
			(thermal_bridge_width 0.5)
			(island_removal_mode 0)
		)
		(polygon
			(pts
				(xy 52.653184 -169.05986) (xy 52.653184 -168.54678) (xy 53.16474 -168.54678) (xy 53.16474 -169.05986)
			)
		)
	)
	(zone
		(layer "Cmts.User")
		(hatch none 0.5)
		(connect_pads
			(clearance 0)
		)
		(min_thickness 0.25)
		(keepout
			(tracks allowed)
			(vias allowed)
			(pads allowed)
			(copperpour allowed)
			(footprints allowed)
		)
		(placement
			(enabled no)
			(sheetname "")
		)
		(fill
			(thermal_gap 0.5)
			(thermal_bridge_width 0.5)
			(island_removal_mode 0)
		)
		(polygon
			(pts
				(xy 51.179984 -151.78786) (xy 51.179984 -151.27478) (xy 51.69154 -151.27478) (xy 51.69154 -151.78786)
			)
		)
	)
	(zone
		(layer "Cmts.User")
		(hatch none 0.5)
		(connect_pads
			(clearance 0)
		)
		(min_thickness 0.25)
		(keepout
			(tracks allowed)
			(vias allowed)
			(pads allowed)
			(copperpour allowed)
			(footprints allowed)
		)
		(placement
			(enabled no)
			(sheetname "")
		)
		(fill
			(thermal_gap 0.5)
			(thermal_bridge_width 0.5)
			(island_removal_mode 0)
		)
		(polygon
			(pts
				(xy 91.88196 -177.416968) (xy 91.88196 -176.007268) (xy 92.52204 -176.007268) (xy 92.52204 -177.416968)
			)
		)
	)
	(zone
		(layer "Cmts.User")
		(hatch none 0.5)
		(connect_pads
			(clearance 0)
		)
		(min_thickness 0.25)
		(keepout
			(tracks allowed)
			(vias allowed)
			(pads allowed)
			(copperpour allowed)
			(footprints allowed)
		)
		(placement
			(enabled no)
			(sheetname "")
		)
		(fill
			(thermal_gap 0.5)
			(thermal_bridge_width 0.5)
			(island_removal_mode 0)
		)
		(polygon
			(pts
				(xy 50.334672 -165.481) (xy 50.334672 -164.96792) (xy 50.846228 -164.96792) (xy 50.846228 -165.481)
			)
		)
	)
	(zone
		(layer "Cmts.User")
		(hatch none 0.5)
		(connect_pads
			(clearance 0)
		)
		(min_thickness 0.25)
		(keepout
			(tracks allowed)
			(vias allowed)
			(pads allowed)
			(copperpour allowed)
			(footprints allowed)
		)
		(placement
			(enabled no)
			(sheetname "")
		)
		(fill
			(thermal_gap 0.5)
			(thermal_bridge_width 0.5)
			(island_removal_mode 0)
		)
		(polygon
			(pts
				(xy 21.620734 -159.967676) (xy 21.620734 -159.22625) (xy 23.144734 -159.22625) (xy 23.144734 -159.967676)
			)
		)
	)
	(zone
		(layer "Cmts.User")
		(hatch none 0.5)
		(connect_pads
			(clearance 0)
		)
		(min_thickness 0.25)
		(keepout
			(tracks allowed)
			(vias allowed)
			(pads allowed)
			(copperpour allowed)
			(footprints allowed)
		)
		(placement
			(enabled no)
			(sheetname "")
		)
		(fill
			(thermal_gap 0.5)
			(thermal_bridge_width 0.5)
			(island_removal_mode 0)
		)
		(polygon
			(pts
				(xy 433.91074 -95.113348) (xy 433.91074 -93.703648) (xy 434.55082 -93.703648) (xy 434.55082 -95.113348)
			)
		)
	)
	(zone
		(layer "Cmts.User")
		(hatch none 0.5)
		(connect_pads
			(clearance 0)
		)
		(min_thickness 0.25)
		(keepout
			(tracks allowed)
			(vias allowed)
			(pads allowed)
			(copperpour allowed)
			(footprints allowed)
		)
		(placement
			(enabled no)
			(sheetname "")
		)
		(fill
			(thermal_gap 0.5)
			(thermal_bridge_width 0.5)
			(island_removal_mode 0)
		)
		(polygon
			(pts
				(xy 50.713132 -147.13966) (xy 50.713132 -146.62658) (xy 51.224688 -146.62658) (xy 51.224688 -147.13966)
			)
		)
	)
	(zone
		(layer "Cmts.User")
		(hatch none 0.5)
		(connect_pads
			(clearance 0)
		)
		(min_thickness 0.25)
		(keepout
			(tracks allowed)
			(vias allowed)
			(pads allowed)
			(copperpour allowed)
			(footprints allowed)
		)
		(placement
			(enabled no)
			(sheetname "")
		)
		(fill
			(thermal_gap 0.5)
			(thermal_bridge_width 0.5)
			(island_removal_mode 0)
		)
		(polygon
			(pts
				(xy 28.33116 -129.991104) (xy 28.33116 -129.447544) (xy 28.83662 -129.447544) (xy 28.83662 -129.991104)
			)
		)
	)
	(zone
		(layer "Cmts.User")
		(hatch none 0.5)
		(connect_pads
			(clearance 0)
		)
		(min_thickness 0.25)
		(keepout
			(tracks allowed)
			(vias allowed)
			(pads allowed)
			(copperpour allowed)
			(footprints allowed)
		)
		(placement
			(enabled no)
			(sheetname "")
		)
		(fill
			(thermal_gap 0.5)
			(thermal_bridge_width 0.5)
			(island_removal_mode 0)
		)
		(polygon
			(pts
				(xy 51.359562 -175.52035) (xy 51.359562 -175.00727) (xy 51.871118 -175.00727) (xy 51.871118 -175.52035)
			)
		)
	)
	(zone
		(layer "Cmts.User")
		(hatch none 0.5)
		(connect_pads
			(clearance 0)
		)
		(min_thickness 0.25)
		(keepout
			(tracks allowed)
			(vias allowed)
			(pads allowed)
			(copperpour allowed)
			(footprints allowed)
		)
		(placement
			(enabled no)
			(sheetname "")
		)
		(fill
			(thermal_gap 0.5)
			(thermal_bridge_width 0.5)
			(island_removal_mode 0)
		)
		(polygon
			(pts
				(xy 32.720026 -135.402574) (xy 32.720026 -134.859014) (xy 33.225486 -134.859014) (xy 33.225486 -135.402574)
			)
		)
	)
	(zone
		(layer "Cmts.User")
		(hatch none 0.5)
		(connect_pads
			(clearance 0)
		)
		(min_thickness 0.25)
		(keepout
			(tracks allowed)
			(vias allowed)
			(pads allowed)
			(copperpour allowed)
			(footprints allowed)
		)
		(placement
			(enabled no)
			(sheetname "")
		)
		(fill
			(thermal_gap 0.5)
			(thermal_bridge_width 0.5)
			(island_removal_mode 0)
		)
		(polygon
			(pts
				(xy 27.478736 -125.938788) (xy 27.478736 -125.395228) (xy 27.984196 -125.395228) (xy 27.984196 -125.938788)
			)
		)
	)
	(zone
		(layer "Cmts.User")
		(hatch none 0.5)
		(connect_pads
			(clearance 0)
		)
		(min_thickness 0.25)
		(keepout
			(tracks allowed)
			(vias allowed)
			(pads allowed)
			(copperpour allowed)
			(footprints allowed)
		)
		(placement
			(enabled no)
			(sheetname "")
		)
		(fill
			(thermal_gap 0.5)
			(thermal_bridge_width 0.5)
			(island_removal_mode 0)
		)
		(polygon
			(pts
				(xy 384.73888 -203.271628) (xy 384.73888 -201.861928) (xy 385.37896 -201.861928) (xy 385.37896 -203.271628)
			)
		)
	)
	(zone
		(layer "Cmts.User")
		(hatch none 0.5)
		(connect_pads
			(clearance 0)
		)
		(min_thickness 0.25)
		(keepout
			(tracks allowed)
			(vias allowed)
			(pads allowed)
			(copperpour allowed)
			(footprints allowed)
		)
		(placement
			(enabled no)
			(sheetname "")
		)
		(fill
			(thermal_gap 0.5)
			(thermal_bridge_width 0.5)
			(island_removal_mode 0)
		)
		(polygon
			(pts
				(xy 416.595306 -183.32196) (xy 416.595306 -182.7784) (xy 417.100766 -182.7784) (xy 417.100766 -183.32196)
			)
		)
	)
	(zone
		(layer "Cmts.User")
		(hatch none 0.5)
		(connect_pads
			(clearance 0)
		)
		(min_thickness 0.25)
		(keepout
			(tracks allowed)
			(vias allowed)
			(pads allowed)
			(copperpour allowed)
			(footprints allowed)
		)
		(placement
			(enabled no)
			(sheetname "")
		)
		(fill
			(thermal_gap 0.5)
			(thermal_bridge_width 0.5)
			(island_removal_mode 0)
		)
		(polygon
			(pts
				(xy 394.754354 -12.775184) (xy 394.754354 -9.925304) (xy 458.675994 -9.925304) (xy 458.675994 -12.775184)
				(xy 458.675994 -13.100304) (xy 458.675994 -13.495782) (xy 458.197712 -13.974064) (xy 395.953234 -13.974064)
				(xy 395.336014 -13.356844)
			)
		)
	)
	(zone
		(layer "Cmts.User")
		(hatch none 0.5)
		(connect_pads
			(clearance 0)
		)
		(min_thickness 0.25)
		(keepout
			(tracks allowed)
			(vias allowed)
			(pads allowed)
			(copperpour allowed)
			(footprints allowed)
		)
		(placement
			(enabled no)
			(sheetname "")
		)
		(fill
			(thermal_gap 0.5)
			(thermal_bridge_width 0.5)
			(island_removal_mode 0)
		)
		(polygon
			(pts
				(xy 422.2496 -140.772388) (xy 423.6593 -140.772388) (xy 423.6593 -141.412468) (xy 422.2496 -141.412468)
			)
		)
	)
	(zone
		(layer "Cmts.User")
		(hatch none 0.5)
		(connect_pads
			(clearance 0)
		)
		(min_thickness 0.25)
		(keepout
			(tracks allowed)
			(vias allowed)
			(pads allowed)
			(copperpour allowed)
			(footprints allowed)
		)
		(placement
			(enabled no)
			(sheetname "")
		)
		(fill
			(thermal_gap 0.5)
			(thermal_bridge_width 0.5)
			(island_removal_mode 0)
		)
		(polygon
			(pts
				(xy 26.6446 -125.938788) (xy 26.6446 -125.395228) (xy 27.15006 -125.395228) (xy 27.15006 -125.938788)
			)
		)
	)
	(zone
		(layer "Cmts.User")
		(hatch none 0.5)
		(connect_pads
			(clearance 0)
		)
		(min_thickness 0.25)
		(keepout
			(tracks allowed)
			(vias allowed)
			(pads allowed)
			(copperpour allowed)
			(footprints allowed)
		)
		(placement
			(enabled no)
			(sheetname "")
		)
		(fill
			(thermal_gap 0.5)
			(thermal_bridge_width 0.5)
			(island_removal_mode 0)
		)
		(polygon
			(pts
				(xy 418.881052 -176.5935) (xy 418.881052 -176.04994) (xy 419.386512 -176.04994) (xy 419.386512 -176.5935)
			)
		)
	)
	(zone
		(layer "Cmts.User")
		(hatch none 0.5)
		(connect_pads
			(clearance 0)
		)
		(min_thickness 0.25)
		(keepout
			(tracks allowed)
			(vias allowed)
			(pads allowed)
			(copperpour allowed)
			(footprints allowed)
		)
		(placement
			(enabled no)
			(sheetname "")
		)
		(fill
			(thermal_gap 0.5)
			(thermal_bridge_width 0.5)
			(island_removal_mode 0)
		)
		(polygon
			(pts
				(xy 372.3132 -410.698188) (xy 372.3132 -405.971248) (xy 420.0652 -405.971248) (xy 420.0652 -410.698188)
			)
		)
	)
	(zone
		(layer "Cmts.User")
		(hatch none 0.5)
		(connect_pads
			(clearance 0)
		)
		(min_thickness 0.25)
		(keepout
			(tracks allowed)
			(vias allowed)
			(pads allowed)
			(copperpour allowed)
			(footprints allowed)
		)
		(placement
			(enabled no)
			(sheetname "")
		)
		(fill
			(thermal_gap 0.5)
			(thermal_bridge_width 0.5)
			(island_removal_mode 0)
		)
		(polygon
			(pts
				(xy 417.632896 -160.626044) (xy 417.632896 -160.082484) (xy 418.138356 -160.082484) (xy 418.138356 -160.626044)
			)
		)
	)
	(zone
		(layer "Cmts.User")
		(hatch none 0.5)
		(connect_pads
			(clearance 0)
		)
		(min_thickness 0.25)
		(keepout
			(tracks allowed)
			(vias allowed)
			(pads allowed)
			(copperpour allowed)
			(footprints allowed)
		)
		(placement
			(enabled no)
			(sheetname "")
		)
		(fill
			(thermal_gap 0.5)
			(thermal_bridge_width 0.5)
			(island_removal_mode 0)
		)
		(polygon
			(pts
				(xy 418.500052 -158.7881) (xy 418.500052 -158.24454) (xy 419.005512 -158.24454) (xy 419.005512 -158.7881)
			)
		)
	)
	(zone
		(layer "Cmts.User")
		(hatch none 0.5)
		(connect_pads
			(clearance 0)
		)
		(min_thickness 0.25)
		(keepout
			(tracks allowed)
			(vias allowed)
			(pads allowed)
			(copperpour allowed)
			(footprints allowed)
		)
		(placement
			(enabled no)
			(sheetname "")
		)
		(fill
			(thermal_gap 0.5)
			(thermal_bridge_width 0.5)
			(island_removal_mode 0)
		)
		(polygon
			(pts
				(xy 427.8503 -142.646908) (xy 427.8503 -144.056608) (xy 427.21022 -144.056608) (xy 427.21022 -142.646908)
			)
		)
	)
	(zone
		(layer "Cmts.User")
		(hatch none 0.5)
		(connect_pads
			(clearance 0)
		)
		(min_thickness 0.25)
		(keepout
			(tracks allowed)
			(vias allowed)
			(pads allowed)
			(copperpour allowed)
			(footprints allowed)
		)
		(placement
			(enabled no)
			(sheetname "")
		)
		(fill
			(thermal_gap 0.5)
			(thermal_bridge_width 0.5)
			(island_removal_mode 0)
		)
		(polygon
			(pts
				(xy 433.41798 -129.068068) (xy 433.41798 -127.658368) (xy 434.05806 -127.658368) (xy 434.05806 -129.068068)
			)
		)
	)
	(zone
		(layer "Cmts.User")
		(hatch none 0.5)
		(connect_pads
			(clearance 0)
		)
		(min_thickness 0.25)
		(keepout
			(tracks allowed)
			(vias allowed)
			(pads allowed)
			(copperpour allowed)
			(footprints allowed)
		)
		(placement
			(enabled no)
			(sheetname "")
		)
		(fill
			(thermal_gap 0.5)
			(thermal_bridge_width 0.5)
			(island_removal_mode 0)
		)
		(polygon
			(pts
				(xy 417.230306 -183.32196) (xy 417.230306 -182.7784) (xy 417.735766 -182.7784) (xy 417.735766 -183.32196)
			)
		)
	)
	(zone
		(layer "Cmts.User")
		(hatch none 0.5)
		(connect_pads
			(clearance 0)
		)
		(min_thickness 0.25)
		(keepout
			(tracks allowed)
			(vias allowed)
			(pads allowed)
			(copperpour allowed)
			(footprints allowed)
		)
		(placement
			(enabled no)
			(sheetname "")
		)
		(fill
			(thermal_gap 0.5)
			(thermal_bridge_width 0.5)
			(island_removal_mode 0)
		)
		(polygon
			(pts
				(xy 53.18633 -153.162) (xy 53.18633 -152.64892) (xy 53.697886 -152.64892) (xy 53.697886 -153.162)
			)
		)
	)
	(zone
		(layer "Cmts.User")
		(hatch none 0.5)
		(connect_pads
			(clearance 0)
		)
		(min_thickness 0.25)
		(keepout
			(tracks allowed)
			(vias allowed)
			(pads allowed)
			(copperpour allowed)
			(footprints allowed)
		)
		(placement
			(enabled no)
			(sheetname "")
		)
		(fill
			(thermal_gap 0.5)
			(thermal_bridge_width 0.5)
			(island_removal_mode 0)
		)
		(polygon
			(pts
				(xy 397.035782 -145.708878) (xy 397.035782 -145.305018) (xy 398.262602 -145.305018) (xy 398.262602 -145.708878)
			)
		)
	)
	(zone
		(layer "Cmts.User")
		(hatch none 0.5)
		(connect_pads
			(clearance 0)
		)
		(min_thickness 0.25)
		(keepout
			(tracks allowed)
			(vias allowed)
			(pads allowed)
			(copperpour allowed)
			(footprints allowed)
		)
		(placement
			(enabled no)
			(sheetname "")
		)
		(fill
			(thermal_gap 0.5)
			(thermal_bridge_width 0.5)
			(island_removal_mode 0)
		)
		(polygon
			(pts
				(xy 74.55281 -175.16856) (xy 74.55281 -174.564294) (xy 75.136502 -174.564294) (xy 75.136502 -175.16856)
			)
		)
	)
	(zone
		(layer "Cmts.User")
		(hatch none 0.5)
		(connect_pads
			(clearance 0)
		)
		(min_thickness 0.25)
		(keepout
			(tracks allowed)
			(vias allowed)
			(pads allowed)
			(copperpour allowed)
			(footprints allowed)
		)
		(placement
			(enabled no)
			(sheetname "")
		)
		(fill
			(thermal_gap 0.5)
			(thermal_bridge_width 0.5)
			(island_removal_mode 0)
		)
		(polygon
			(pts
				(xy 26.656284 -161.271204) (xy 26.656284 -160.666938) (xy 27.239976 -160.666938) (xy 27.239976 -161.271204)
			)
		)
	)
	(zone
		(layer "Cmts.User")
		(hatch none 0.5)
		(connect_pads
			(clearance 0)
		)
		(min_thickness 0.25)
		(keepout
			(tracks allowed)
			(vias allowed)
			(pads allowed)
			(copperpour allowed)
			(footprints allowed)
		)
		(placement
			(enabled no)
			(sheetname "")
		)
		(fill
			(thermal_gap 0.5)
			(thermal_bridge_width 0.5)
			(island_removal_mode 0)
		)
		(polygon
			(pts
				(xy 51.140868 -153.35631) (xy 51.140868 -152.84323) (xy 51.652424 -152.84323) (xy 51.652424 -153.35631)
			)
		)
	)
	(zone
		(layer "Cmts.User")
		(hatch none 0.5)
		(connect_pads
			(clearance 0)
		)
		(min_thickness 0.25)
		(keepout
			(tracks allowed)
			(vias allowed)
			(pads allowed)
			(copperpour allowed)
			(footprints allowed)
		)
		(placement
			(enabled no)
			(sheetname "")
		)
		(fill
			(thermal_gap 0.5)
			(thermal_bridge_width 0.5)
			(island_removal_mode 0)
		)
		(polygon
			(pts
				(xy 429.05172 -136.929368) (xy 429.05172 -135.519668) (xy 429.6918 -135.519668) (xy 429.6918 -136.929368)
			)
		)
	)
	(zone
		(layer "Cmts.User")
		(hatch none 0.5)
		(connect_pads
			(clearance 0)
		)
		(min_thickness 0.25)
		(keepout
			(tracks allowed)
			(vias allowed)
			(pads allowed)
			(copperpour allowed)
			(footprints allowed)
		)
		(placement
			(enabled no)
			(sheetname "")
		)
		(fill
			(thermal_gap 0.5)
			(thermal_bridge_width 0.5)
			(island_removal_mode 0)
		)
		(polygon
			(pts
				(xy 419.457632 -171.376848) (xy 419.457632 -170.833288) (xy 419.963092 -170.833288) (xy 419.963092 -171.376848)
			)
		)
	)
	(zone
		(layer "Cmts.User")
		(hatch none 0.5)
		(connect_pads
			(clearance 0)
		)
		(min_thickness 0.25)
		(keepout
			(tracks allowed)
			(vias allowed)
			(pads allowed)
			(copperpour allowed)
			(footprints allowed)
		)
		(placement
			(enabled no)
			(sheetname "")
		)
		(fill
			(thermal_gap 0.5)
			(thermal_bridge_width 0.5)
			(island_removal_mode 0)
		)
		(polygon
			(pts
				(xy 53.82133 -153.162) (xy 53.82133 -152.64892) (xy 54.332886 -152.64892) (xy 54.332886 -153.162)
			)
		)
	)
	(zone
		(layer "Cmts.User")
		(hatch none 0.5)
		(connect_pads
			(clearance 0)
		)
		(min_thickness 0.25)
		(keepout
			(tracks allowed)
			(vias allowed)
			(pads allowed)
			(copperpour allowed)
			(footprints allowed)
		)
		(placement
			(enabled no)
			(sheetname "")
		)
		(fill
			(thermal_gap 0.5)
			(thermal_bridge_width 0.5)
			(island_removal_mode 0)
		)
		(polygon
			(pts
				(xy 30.541976 -165.733476) (xy 30.541976 -165.12921) (xy 31.125668 -165.12921) (xy 31.125668 -165.733476)
			)
		)
	)
	(zone
		(layer "Cmts.User")
		(hatch none 0.5)
		(connect_pads
			(clearance 0)
		)
		(min_thickness 0.25)
		(keepout
			(tracks allowed)
			(vias allowed)
			(pads allowed)
			(copperpour allowed)
			(footprints allowed)
		)
		(placement
			(enabled no)
			(sheetname "")
		)
		(fill
			(thermal_gap 0.5)
			(thermal_bridge_width 0.5)
			(island_removal_mode 0)
		)
		(polygon
			(pts
				(xy 417.763452 -167.4241) (xy 417.763452 -166.88054) (xy 418.268912 -166.88054) (xy 418.268912 -167.4241)
			)
		)
	)
	(zone
		(layer "Cmts.User")
		(hatch none 0.5)
		(connect_pads
			(clearance 0)
		)
		(min_thickness 0.25)
		(keepout
			(tracks allowed)
			(vias allowed)
			(pads allowed)
			(copperpour allowed)
			(footprints allowed)
		)
		(placement
			(enabled no)
			(sheetname "")
		)
		(fill
			(thermal_gap 0.5)
			(thermal_bridge_width 0.5)
			(island_removal_mode 0)
		)
		(polygon
			(pts
				(xy 419.275768 -174.49165) (xy 419.275768 -173.94809) (xy 419.781228 -173.94809) (xy 419.781228 -174.49165)
			)
		)
	)
	(zone
		(layer "Cmts.User")
		(hatch none 0.5)
		(connect_pads
			(clearance 0)
		)
		(min_thickness 0.25)
		(keepout
			(tracks allowed)
			(vias allowed)
			(pads allowed)
			(copperpour allowed)
			(footprints allowed)
		)
		(placement
			(enabled no)
			(sheetname "")
		)
		(fill
			(thermal_gap 0.5)
			(thermal_bridge_width 0.5)
			(island_removal_mode 0)
		)
		(polygon
			(pts
				(xy 323.110606 -351.093532) (xy 323.110606 -349.241872) (xy 324.827646 -349.241872) (xy 324.827646 -351.093532)
			)
		)
	)
	(zone
		(layer "Cmts.User")
		(hatch none 0.5)
		(connect_pads
			(clearance 0)
		)
		(min_thickness 0.25)
		(keepout
			(tracks allowed)
			(vias allowed)
			(pads allowed)
			(copperpour allowed)
			(footprints allowed)
		)
		(placement
			(enabled no)
			(sheetname "")
		)
		(fill
			(thermal_gap 0.5)
			(thermal_bridge_width 0.5)
			(island_removal_mode 0)
		)
		(polygon
			(pts
				(xy 49.1998 -174.77232) (xy 49.1998 -174.25924) (xy 49.711356 -174.25924) (xy 49.711356 -174.77232)
			)
		)
	)
	(zone
		(layer "Cmts.User")
		(hatch none 0.5)
		(connect_pads
			(clearance 0)
		)
		(min_thickness 0.25)
		(keepout
			(tracks allowed)
			(vias allowed)
			(pads allowed)
			(copperpour allowed)
			(footprints allowed)
		)
		(placement
			(enabled no)
			(sheetname "")
		)
		(fill
			(thermal_gap 0.5)
			(thermal_bridge_width 0.5)
			(island_removal_mode 0)
		)
		(polygon
			(pts
				(xy 52.653184 -151.78786) (xy 52.653184 -151.27478) (xy 53.16474 -151.27478) (xy 53.16474 -151.78786)
			)
		)
	)
	(zone
		(layer "Cmts.User")
		(hatch none 0.5)
		(connect_pads
			(clearance 0)
		)
		(min_thickness 0.25)
		(keepout
			(tracks allowed)
			(vias allowed)
			(pads allowed)
			(copperpour allowed)
			(footprints allowed)
		)
		(placement
			(enabled no)
			(sheetname "")
		)
		(fill
			(thermal_gap 0.5)
			(thermal_bridge_width 0.5)
			(island_removal_mode 0)
		)
		(polygon
			(pts
				(xy 51.179984 -160.42386) (xy 51.179984 -159.91078) (xy 51.69154 -159.91078) (xy 51.69154 -160.42386)
			)
		)
	)
	(zone
		(layer "Cmts.User")
		(hatch none 0.5)
		(connect_pads
			(clearance 0)
		)
		(min_thickness 0.25)
		(keepout
			(tracks allowed)
			(vias allowed)
			(pads allowed)
			(copperpour allowed)
			(footprints allowed)
		)
		(placement
			(enabled no)
			(sheetname "")
		)
		(fill
			(thermal_gap 0.5)
			(thermal_bridge_width 0.5)
			(island_removal_mode 0)
		)
		(polygon
			(pts
				(xy 124.95276 -441.096908) (xy 124.95276 -424.970448) (xy 157.62732 -424.970448) (xy 157.62732 -441.096908)
			)
		)
	)
	(zone
		(layer "Cmts.User")
		(hatch none 0.5)
		(connect_pads
			(clearance 0)
		)
		(min_thickness 0.25)
		(keepout
			(tracks allowed)
			(vias allowed)
			(pads allowed)
			(copperpour allowed)
			(footprints allowed)
		)
		(placement
			(enabled no)
			(sheetname "")
		)
		(fill
			(thermal_gap 0.5)
			(thermal_bridge_width 0.5)
			(island_removal_mode 0)
		)
		(polygon
			(pts
				(xy 417.763452 -176.0601) (xy 417.763452 -175.51654) (xy 418.268912 -175.51654) (xy 418.268912 -176.0601)
			)
		)
	)
	(zone
		(layer "Cmts.User")
		(hatch none 0.5)
		(connect_pads
			(clearance 0)
		)
		(min_thickness 0.25)
		(keepout
			(tracks allowed)
			(vias allowed)
			(pads allowed)
			(copperpour allowed)
			(footprints allowed)
		)
		(placement
			(enabled no)
			(sheetname "")
		)
		(fill
			(thermal_gap 0.5)
			(thermal_bridge_width 0.5)
			(island_removal_mode 0)
		)
		(polygon
			(pts
				(xy 51.916584 -169.05986) (xy 51.916584 -168.54678) (xy 52.42814 -168.54678) (xy 52.42814 -169.05986)
			)
		)
	)
	(zone
		(layer "Cmts.User")
		(hatch none 0.5)
		(connect_pads
			(clearance 0)
		)
		(min_thickness 0.25)
		(keepout
			(tracks allowed)
			(vias allowed)
			(pads allowed)
			(copperpour allowed)
			(footprints allowed)
		)
		(placement
			(enabled no)
			(sheetname "")
		)
		(fill
			(thermal_gap 0.5)
			(thermal_bridge_width 0.5)
			(island_removal_mode 0)
		)
		(polygon
			(pts
				(xy 28.3083 -134.449058) (xy 28.3083 -133.905498) (xy 28.81376 -133.905498) (xy 28.81376 -134.449058)
			)
		)
	)
	(zone
		(layer "Cmts.User")
		(hatch none 0.5)
		(connect_pads
			(clearance 0)
		)
		(min_thickness 0.25)
		(keepout
			(tracks allowed)
			(vias allowed)
			(pads allowed)
			(copperpour allowed)
			(footprints allowed)
		)
		(placement
			(enabled no)
			(sheetname "")
		)
		(fill
			(thermal_gap 0.5)
			(thermal_bridge_width 0.5)
			(island_removal_mode 0)
		)
		(polygon
			(pts
				(xy 262.8265 -78.458568) (xy 262.8265 -76.932028) (xy 263.57834 -76.932028) (xy 263.57834 -78.458568)
			)
		)
	)
	(zone
		(layer "Cmts.User")
		(hatch none 0.5)
		(connect_pads
			(clearance 0)
		)
		(min_thickness 0.25)
		(keepout
			(tracks allowed)
			(vias allowed)
			(pads allowed)
			(copperpour allowed)
			(footprints allowed)
		)
		(placement
			(enabled no)
			(sheetname "")
		)
		(fill
			(thermal_gap 0.5)
			(thermal_bridge_width 0.5)
			(island_removal_mode 0)
		)
		(polygon
			(pts
				(xy 419.457632 -180.012848) (xy 419.457632 -179.469288) (xy 419.963092 -179.469288) (xy 419.963092 -180.012848)
			)
		)
	)
	(zone
		(layer "Cmts.User")
		(hatch none 0.5)
		(connect_pads
			(clearance 0)
		)
		(min_thickness 0.25)
		(keepout
			(tracks allowed)
			(vias allowed)
			(pads allowed)
			(copperpour allowed)
			(footprints allowed)
		)
		(placement
			(enabled no)
			(sheetname "")
		)
		(fill
			(thermal_gap 0.5)
			(thermal_bridge_width 0.5)
			(island_removal_mode 0)
		)
		(polygon
			(pts
				(xy 417.632896 -161.809684) (xy 417.632896 -161.266124) (xy 418.138356 -161.266124) (xy 418.138356 -161.809684)
			)
		)
	)
	(zone
		(layer "Cmts.User")
		(hatch none 0.5)
		(connect_pads
			(clearance 0)
		)
		(min_thickness 0.25)
		(keepout
			(tracks allowed)
			(vias allowed)
			(pads allowed)
			(copperpour allowed)
			(footprints allowed)
		)
		(placement
			(enabled no)
			(sheetname "")
		)
		(fill
			(thermal_gap 0.5)
			(thermal_bridge_width 0.5)
			(island_removal_mode 0)
		)
		(polygon
			(pts
				(xy 304.55362 -410.962348) (xy 304.55362 -406.169368) (xy 352.90252 -406.169368) (xy 352.90252 -410.962348)
			)
		)
	)
	(zone
		(layer "Cmts.User")
		(hatch none 0.5)
		(connect_pads
			(clearance 0)
		)
		(min_thickness 0.25)
		(keepout
			(tracks allowed)
			(vias allowed)
			(pads allowed)
			(copperpour allowed)
			(footprints allowed)
		)
		(placement
			(enabled no)
			(sheetname "")
		)
		(fill
			(thermal_gap 0.5)
			(thermal_bridge_width 0.5)
			(island_removal_mode 0)
		)
		(polygon
			(pts
				(xy 371.09146 -404.658068) (xy 371.09146 -400.195288) (xy 418.95014 -400.195288) (xy 418.95014 -404.658068)
			)
		)
	)
	(zone
		(layer "Cmts.User")
		(hatch none 0.5)
		(connect_pads
			(clearance 0)
		)
		(min_thickness 0.25)
		(keepout
			(tracks allowed)
			(vias allowed)
			(pads allowed)
			(copperpour allowed)
			(footprints allowed)
		)
		(placement
			(enabled no)
			(sheetname "")
		)
		(fill
			(thermal_gap 0.5)
			(thermal_bridge_width 0.5)
			(island_removal_mode 0)
		)
		(polygon
			(pts
				(xy 418.558472 -159.871664) (xy 418.558472 -159.328104) (xy 419.063932 -159.328104) (xy 419.063932 -159.871664)
			)
		)
	)
	(zone
		(layer "Cmts.User")
		(hatch none 0.5)
		(connect_pads
			(clearance 0)
		)
		(min_thickness 0.25)
		(keepout
			(tracks allowed)
			(vias allowed)
			(pads allowed)
			(copperpour allowed)
			(footprints allowed)
		)
		(placement
			(enabled no)
			(sheetname "")
		)
		(fill
			(thermal_gap 0.5)
			(thermal_bridge_width 0.5)
			(island_removal_mode 0)
		)
		(polygon
			(pts
				(xy 50.334672 -156.845) (xy 50.334672 -156.33192) (xy 50.846228 -156.33192) (xy 50.846228 -156.845)
			)
		)
	)
	(zone
		(layer "Cmts.User")
		(hatch none 0.5)
		(connect_pads
			(clearance 0)
		)
		(min_thickness 0.25)
		(keepout
			(tracks allowed)
			(vias allowed)
			(pads allowed)
			(copperpour allowed)
			(footprints allowed)
		)
		(placement
			(enabled no)
			(sheetname "")
		)
		(fill
			(thermal_gap 0.5)
			(thermal_bridge_width 0.5)
			(island_removal_mode 0)
		)
		(polygon
			(pts
				(xy 29.1719 -134.449058) (xy 29.1719 -133.905498) (xy 29.67736 -133.905498) (xy 29.67736 -134.449058)
			)
		)
	)
	(zone
		(layer "Cmts.User")
		(hatch none 0.5)
		(connect_pads
			(clearance 0)
		)
		(min_thickness 0.25)
		(keepout
			(tracks allowed)
			(vias allowed)
			(pads allowed)
			(copperpour allowed)
			(footprints allowed)
		)
		(placement
			(enabled no)
			(sheetname "")
		)
		(fill
			(thermal_gap 0.5)
			(thermal_bridge_width 0.5)
			(island_removal_mode 0)
		)
		(polygon
			(pts
				(xy 417.230306 -174.68596) (xy 417.230306 -174.1424) (xy 417.735766 -174.1424) (xy 417.735766 -174.68596)
			)
		)
	)
	(zone
		(layer "Cmts.User")
		(hatch none 0.5)
		(connect_pads
			(clearance 0)
		)
		(min_thickness 0.25)
		(keepout
			(tracks allowed)
			(vias allowed)
			(pads allowed)
			(copperpour allowed)
			(footprints allowed)
		)
		(placement
			(enabled no)
			(sheetname "")
		)
		(fill
			(thermal_gap 0.5)
			(thermal_bridge_width 0.5)
			(island_removal_mode 0)
		)
		(polygon
			(pts
				(xy 51.916584 -160.42386) (xy 51.916584 -159.91078) (xy 52.42814 -159.91078) (xy 52.42814 -160.42386)
			)
		)
	)
	(zone
		(layer "Cmts.User")
		(hatch none 0.5)
		(connect_pads
			(clearance 0)
		)
		(min_thickness 0.25)
		(keepout
			(tracks allowed)
			(vias allowed)
			(pads allowed)
			(copperpour allowed)
			(footprints allowed)
		)
		(placement
			(enabled no)
			(sheetname "")
		)
		(fill
			(thermal_gap 0.5)
			(thermal_bridge_width 0.5)
			(island_removal_mode 0)
		)
		(polygon
			(pts
				(xy 47.4853 -404.823168) (xy 47.4853 -399.931128) (xy 95.61068 -399.931128) (xy 95.61068 -404.823168)
			)
		)
	)
	(zone
		(layer "Cmts.User")
		(hatch none 0.5)
		(connect_pads
			(clearance 0)
		)
		(min_thickness 0.25)
		(keepout
			(tracks allowed)
			(vias allowed)
			(pads allowed)
			(copperpour allowed)
			(footprints allowed)
		)
		(placement
			(enabled no)
			(sheetname "")
		)
		(fill
			(thermal_gap 0.5)
			(thermal_bridge_width 0.5)
			(island_removal_mode 0)
		)
		(polygon
			(pts
				(xy 25.66416 -131.886706) (xy 25.66416 -131.343146) (xy 26.16962 -131.343146) (xy 26.16962 -131.886706)
			)
		)
	)
	(zone
		(layer "Cmts.User")
		(hatch none 0.5)
		(connect_pads
			(clearance 0)
		)
		(min_thickness 0.25)
		(keepout
			(tracks allowed)
			(vias allowed)
			(pads allowed)
			(copperpour allowed)
			(footprints allowed)
		)
		(placement
			(enabled no)
			(sheetname "")
		)
		(fill
			(thermal_gap 0.5)
			(thermal_bridge_width 0.5)
			(island_removal_mode 0)
		)
		(polygon
			(pts
				(xy 418.662358 -157.937454) (xy 418.662358 -157.393894) (xy 419.167818 -157.393894) (xy 419.167818 -157.937454)
			)
		)
	)
	(zone
		(layer "Cmts.User")
		(hatch none 0.5)
		(connect_pads
			(clearance 0)
		)
		(min_thickness 0.25)
		(keepout
			(tracks allowed)
			(vias allowed)
			(pads allowed)
			(copperpour allowed)
			(footprints allowed)
		)
		(placement
			(enabled no)
			(sheetname "")
		)
		(fill
			(thermal_gap 0.5)
			(thermal_bridge_width 0.5)
			(island_removal_mode 0)
		)
		(polygon
			(pts
				(xy 419.703504 -180.7083) (xy 419.703504 -180.16474) (xy 420.208964 -180.16474) (xy 420.208964 -180.7083)
			)
		)
	)
	(zone
		(layer "Cmts.User")
		(hatch none 0.5)
		(connect_pads
			(clearance 0)
		)
		(min_thickness 0.25)
		(keepout
			(tracks allowed)
			(vias allowed)
			(pads allowed)
			(copperpour allowed)
			(footprints allowed)
		)
		(placement
			(enabled no)
			(sheetname "")
		)
		(fill
			(thermal_gap 0.5)
			(thermal_bridge_width 0.5)
			(island_removal_mode 0)
		)
		(polygon
			(pts
				(xy 421.568118 -153.266648) (xy 421.568118 -152.723088) (xy 422.073578 -152.723088) (xy 422.073578 -153.266648)
			)
		)
	)
	(zone
		(layer "Cmts.User")
		(hatch none 0.5)
		(connect_pads
			(clearance 0)
		)
		(min_thickness 0.25)
		(keepout
			(tracks allowed)
			(vias allowed)
			(pads allowed)
			(copperpour allowed)
			(footprints allowed)
		)
		(placement
			(enabled no)
			(sheetname "")
		)
		(fill
			(thermal_gap 0.5)
			(thermal_bridge_width 0.5)
			(island_removal_mode 0)
		)
		(polygon
			(pts
				(xy 381.57912 -203.835508) (xy 381.57912 -202.425808) (xy 382.2192 -202.425808) (xy 382.2192 -203.835508)
			)
		)
	)
	(zone
		(layer "Cmts.User")
		(hatch none 0.5)
		(connect_pads
			(clearance 0)
		)
		(min_thickness 0.25)
		(keepout
			(tracks allowed)
			(vias allowed)
			(pads allowed)
			(copperpour allowed)
			(footprints allowed)
		)
		(placement
			(enabled no)
			(sheetname "")
		)
		(fill
			(thermal_gap 0.5)
			(thermal_bridge_width 0.5)
			(island_removal_mode 0)
		)
		(polygon
			(pts
				(xy 51.916584 -151.78786) (xy 51.916584 -151.27478) (xy 52.42814 -151.27478) (xy 52.42814 -151.78786)
			)
		)
	)
	(zone
		(layer "Cmts.User")
		(hatch none 0.5)
		(connect_pads
			(clearance 0)
		)
		(min_thickness 0.25)
		(keepout
			(tracks allowed)
			(vias allowed)
			(pads allowed)
			(copperpour allowed)
			(footprints allowed)
		)
		(placement
			(enabled no)
			(sheetname "")
		)
		(fill
			(thermal_gap 0.5)
			(thermal_bridge_width 0.5)
			(island_removal_mode 0)
		)
		(polygon
			(pts
				(xy 420.081964 -171.00296) (xy 420.081964 -170.4594) (xy 420.587424 -170.4594) (xy 420.587424 -171.00296)
			)
		)
	)
	(zone
		(layer "Cmts.User")
		(hatch none 0.5)
		(connect_pads
			(clearance 0)
		)
		(min_thickness 0.25)
		(keepout
			(tracks allowed)
			(vias allowed)
			(pads allowed)
			(copperpour allowed)
			(footprints allowed)
		)
		(placement
			(enabled no)
			(sheetname "")
		)
		(fill
			(thermal_gap 0.5)
			(thermal_bridge_width 0.5)
			(island_removal_mode 0)
		)
		(polygon
			(pts
				(xy 395.5034 -167.726868) (xy 395.5034 -166.317168) (xy 396.14348 -166.317168) (xy 396.14348 -167.726868)
			)
		)
	)
	(zone
		(layer "Cmts.User")
		(hatch none 0.5)
		(connect_pads
			(clearance 0)
		)
		(min_thickness 0.25)
		(keepout
			(tracks allowed)
			(vias allowed)
			(pads allowed)
			(copperpour allowed)
			(footprints allowed)
		)
		(placement
			(enabled no)
			(sheetname "")
		)
		(fill
			(thermal_gap 0.5)
			(thermal_bridge_width 0.5)
			(island_removal_mode 0)
		)
		(polygon
			(pts
				(xy 27.715718 -131.170172) (xy 27.715718 -130.626612) (xy 28.221178 -130.626612) (xy 28.221178 -131.170172)
			)
		)
	)
	(zone
		(layer "Cmts.User")
		(hatch none 0.5)
		(connect_pads
			(clearance 0)
		)
		(min_thickness 0.25)
		(keepout
			(tracks allowed)
			(vias allowed)
			(pads allowed)
			(copperpour allowed)
			(footprints allowed)
		)
		(placement
			(enabled no)
			(sheetname "")
		)
		(fill
			(thermal_gap 0.5)
			(thermal_bridge_width 0.5)
			(island_removal_mode 0)
		)
		(polygon
			(pts
				(xy 303.52492 -404.724108) (xy 303.52492 -400.129248) (xy 351.65538 -400.129248) (xy 351.65538 -404.724108)
			)
		)
	)
	(zone
		(layer "Cmts.User")
		(hatch none 0.5)
		(connect_pads
			(clearance 0)
		)
		(min_thickness 0.25)
		(keepout
			(tracks allowed)
			(vias allowed)
			(pads allowed)
			(copperpour allowed)
			(footprints allowed)
		)
		(placement
			(enabled no)
			(sheetname "")
		)
		(fill
			(thermal_gap 0.5)
			(thermal_bridge_width 0.5)
			(island_removal_mode 0)
		)
		(polygon
			(pts
				(xy 120.77446 -410.853128) (xy 120.77446 -406.194768) (xy 169.0751 -406.194768) (xy 169.0751 -410.853128)
			)
		)
	)
	(zone
		(layer "Cmts.User")
		(hatch none 0.5)
		(connect_pads
			(clearance 0)
		)
		(min_thickness 0.25)
		(keepout
			(tracks allowed)
			(vias allowed)
			(pads allowed)
			(copperpour allowed)
			(footprints allowed)
		)
		(placement
			(enabled no)
			(sheetname "")
		)
		(fill
			(thermal_gap 0.5)
			(thermal_bridge_width 0.5)
			(island_removal_mode 0)
		)
		(polygon
			(pts
				(xy 73.965816 -143.475202) (xy 74.549508 -143.475202) (xy 74.549508 -143.476726) (xy 74.700384 -143.476726)
				(xy 74.733658 -143.51) (xy 74.733658 -143.92021) (xy 74.5744 -144.079468) (xy 74.549508 -144.079468)
				(xy 73.965816 -144.079468) (xy 73.82256 -144.079468) (xy 73.591674 -143.848582) (xy 73.591674 -143.686784)
				(xy 73.803256 -143.475202)
			)
		)
	)
	(zone
		(layer "Cmts.User")
		(hatch none 0.5)
		(connect_pads
			(clearance 0)
		)
		(min_thickness 0.25)
		(keepout
			(tracks allowed)
			(vias allowed)
			(pads allowed)
			(copperpour allowed)
			(footprints allowed)
		)
		(placement
			(enabled no)
			(sheetname "")
		)
		(fill
			(thermal_gap 0.5)
			(thermal_bridge_width 0.5)
			(island_removal_mode 0)
		)
		(polygon
			(pts
				(xy 25.766014 -128.654302) (xy 25.766014 -128.110742) (xy 26.271474 -128.110742) (xy 26.271474 -128.654302)
			)
		)
	)
	(zone
		(layer "Cmts.User")
		(hatch none 0.5)
		(connect_pads
			(clearance 0)
		)
		(min_thickness 0.25)
		(keepout
			(tracks allowed)
			(vias allowed)
			(pads allowed)
			(copperpour allowed)
			(footprints allowed)
		)
		(placement
			(enabled no)
			(sheetname "")
		)
		(fill
			(thermal_gap 0.5)
			(thermal_bridge_width 0.5)
			(island_removal_mode 0)
		)
		(polygon
			(pts
				(xy 33.440878 -137.569194) (xy 33.440878 -137.025634) (xy 33.946338 -137.025634) (xy 33.946338 -137.569194)
			)
		)
	)
	(zone
		(layer "Cmts.User")
		(hatch none 0.5)
		(connect_pads
			(clearance 0)
		)
		(min_thickness 0.25)
		(keepout
			(tracks allowed)
			(vias allowed)
			(pads allowed)
			(copperpour allowed)
			(footprints allowed)
		)
		(placement
			(enabled no)
			(sheetname "")
		)
		(fill
			(thermal_gap 0.5)
			(thermal_bridge_width 0.5)
			(island_removal_mode 0)
		)
		(polygon
			(pts
				(xy 416.595306 -174.68596) (xy 416.595306 -174.1424) (xy 417.100766 -174.1424) (xy 417.100766 -174.68596)
			)
		)
	)
	(zone
		(layer "Cmts.User")
		(hatch none 0.5)
		(connect_pads
			(clearance 0)
		)
		(min_thickness 0.25)
		(keepout
			(tracks allowed)
			(vias allowed)
			(pads allowed)
			(copperpour allowed)
			(footprints allowed)
		)
		(placement
			(enabled no)
			(sheetname "")
		)
		(fill
			(thermal_gap 0.5)
			(thermal_bridge_width 0.5)
			(island_removal_mode 0)
		)
		(polygon
			(pts
				(xy 417.823396 -161.217864) (xy 417.823396 -160.674304) (xy 418.328856 -160.674304) (xy 418.328856 -161.217864)
			)
		)
	)
	(zone
		(layer "Cmts.User")
		(hatch none 0.5)
		(connect_pads
			(clearance 0)
		)
		(min_thickness 0.25)
		(keepout
			(tracks allowed)
			(vias allowed)
			(pads allowed)
			(copperpour allowed)
			(footprints allowed)
		)
		(placement
			(enabled no)
			(sheetname "")
		)
		(fill
			(thermal_gap 0.5)
			(thermal_bridge_width 0.5)
			(island_removal_mode 0)
		)
		(polygon
			(pts
				(xy 88.25992 -186.990228) (xy 88.25992 -185.580528) (xy 88.9 -185.580528) (xy 88.9 -186.990228)
			)
		)
	)
	(zone
		(layer "Cmts.User")
		(hatch none 0.5)
		(connect_pads
			(clearance 0)
		)
		(min_thickness 0.25)
		(keepout
			(tracks allowed)
			(vias allowed)
			(pads allowed)
			(copperpour allowed)
			(footprints allowed)
		)
		(placement
			(enabled no)
			(sheetname "")
		)
		(fill
			(thermal_gap 0.5)
			(thermal_bridge_width 0.5)
			(island_removal_mode 0)
		)
		(polygon
			(pts
				(xy 418.500052 -176.0601) (xy 418.500052 -175.51654) (xy 419.005512 -175.51654) (xy 419.005512 -176.0601)
			)
		)
	)
	(zone
		(layer "Cmts.User")
		(hatch none 0.5)
		(connect_pads
			(clearance 0)
		)
		(min_thickness 0.25)
		(keepout
			(tracks allowed)
			(vias allowed)
			(pads allowed)
			(copperpour allowed)
			(footprints allowed)
		)
		(placement
			(enabled no)
			(sheetname "")
		)
		(fill
			(thermal_gap 0.5)
			(thermal_bridge_width 0.5)
			(island_removal_mode 0)
		)
		(polygon
			(pts
				(xy 53.18633 -144.526) (xy 53.18633 -144.01292) (xy 53.697886 -144.01292) (xy 53.697886 -144.526)
			)
		)
	)
	(zone
		(layer "Cmts.User")
		(hatch none 0.5)
		(connect_pads
			(clearance 0)
		)
		(min_thickness 0.25)
		(keepout
			(tracks allowed)
			(vias allowed)
			(pads allowed)
			(copperpour allowed)
			(footprints allowed)
		)
		(placement
			(enabled no)
			(sheetname "")
		)
		(fill
			(thermal_gap 0.5)
			(thermal_bridge_width 0.5)
			(island_removal_mode 0)
		)
		(polygon
			(pts
				(xy 417.823396 -160.034224) (xy 417.823396 -159.490664) (xy 418.328856 -159.490664) (xy 418.328856 -160.034224)
			)
		)
	)
	(zone
		(layer "Cmts.User")
		(hatch none 0.5)
		(connect_pads
			(clearance 0)
		)
		(min_thickness 0.25)
		(keepout
			(tracks allowed)
			(vias allowed)
			(pads allowed)
			(copperpour allowed)
			(footprints allowed)
		)
		(placement
			(enabled no)
			(sheetname "")
		)
		(fill
			(thermal_gap 0.5)
			(thermal_bridge_width 0.5)
			(island_removal_mode 0)
		)
		(polygon
			(pts
				(xy 119.59336 -404.749508) (xy 119.59336 -399.948908) (xy 167.58666 -399.948908) (xy 167.58666 -404.749508)
			)
		)
	)
	(zone
		(layer "Cmts.User")
		(hatch none 0.5)
		(connect_pads
			(clearance 0)
		)
		(min_thickness 0.25)
		(keepout
			(tracks allowed)
			(vias allowed)
			(pads allowed)
			(copperpour allowed)
			(footprints allowed)
		)
		(placement
			(enabled no)
			(sheetname "")
		)
		(fill
			(thermal_gap 0.5)
			(thermal_bridge_width 0.5)
			(island_removal_mode 0)
		)
		(polygon
			(pts
				(xy 30.254448 -18.175224) (xy 30.254448 -15.325344) (xy 94.176088 -15.325344) (xy 94.176088 -18.175224)
				(xy 94.176088 -18.500344) (xy 93.919548 -18.756884) (xy 30.836108 -18.756884)
			)
		)
	)
	(zone
		(layer "Cmts.User")
		(hatch none 0.5)
		(connect_pads
			(clearance 0)
		)
		(min_thickness 0.25)
		(keepout
			(tracks allowed)
			(vias allowed)
			(pads allowed)
			(copperpour allowed)
			(footprints allowed)
		)
		(placement
			(enabled no)
			(sheetname "")
		)
		(fill
			(thermal_gap 0.5)
			(thermal_bridge_width 0.5)
			(island_removal_mode 0)
		)
		(polygon
			(pts
				(xy 416.595306 -166.04996) (xy 416.595306 -165.5064) (xy 417.100766 -165.5064) (xy 417.100766 -166.04996)
			)
		)
	)
	(zone
		(layer "Cmts.User")
		(hatch none 0.5)
		(connect_pads
			(clearance 0)
		)
		(min_thickness 0.25)
		(keepout
			(tracks allowed)
			(vias allowed)
			(pads allowed)
			(copperpour allowed)
			(footprints allowed)
		)
		(placement
			(enabled no)
			(sheetname "")
		)
		(fill
			(thermal_gap 0.5)
			(thermal_bridge_width 0.5)
			(island_removal_mode 0)
		)
		(polygon
			(pts
				(xy 51.140868 -144.72031) (xy 51.140868 -144.20723) (xy 51.652424 -144.20723) (xy 51.652424 -144.72031)
			)
		)
	)
	(zone
		(layer "Cmts.User")
		(hatch none 0.5)
		(connect_pads
			(clearance 0)
		)
		(min_thickness 0.25)
		(keepout
			(tracks allowed)
			(vias allowed)
			(pads allowed)
			(copperpour allowed)
			(footprints allowed)
		)
		(placement
			(enabled no)
			(sheetname "")
		)
		(fill
			(thermal_gap 0.5)
			(thermal_bridge_width 0.5)
			(island_removal_mode 0)
		)
		(polygon
			(pts
				(xy 50.713132 -164.41166) (xy 50.713132 -163.89858) (xy 51.224688 -163.89858) (xy 51.224688 -164.41166)
			)
		)
	)
	(zone
		(layer "Cmts.User")
		(hatch none 0.5)
		(connect_pads
			(clearance 0)
		)
		(min_thickness 0.25)
		(keepout
			(tracks allowed)
			(vias allowed)
			(pads allowed)
			(copperpour allowed)
			(footprints allowed)
		)
		(placement
			(enabled no)
			(sheetname "")
		)
		(fill
			(thermal_gap 0.5)
			(thermal_bridge_width 0.5)
			(island_removal_mode 0)
		)
		(polygon
			(pts
				(xy 57.99074 -441.203588) (xy 57.99074 -425.006008) (xy 91.15552 -425.006008) (xy 91.15552 -441.203588)
			)
		)
	)
	(zone
		(layer "Cmts.User")
		(hatch none 0.5)
		(connect_pads
			(clearance 0)
		)
		(min_thickness 0.25)
		(keepout
			(tracks allowed)
			(vias allowed)
			(pads allowed)
			(copperpour allowed)
			(footprints allowed)
		)
		(placement
			(enabled no)
			(sheetname "")
		)
		(fill
			(thermal_gap 0.5)
			(thermal_bridge_width 0.5)
			(island_removal_mode 0)
		)
		(polygon
			(pts
				(xy 417.230306 -166.04996) (xy 417.230306 -165.5064) (xy 417.735766 -165.5064) (xy 417.735766 -166.04996)
			)
		)
	)
	(zone
		(layer "Cmts.User")
		(hatch none 0.5)
		(connect_pads
			(clearance 0)
		)
		(min_thickness 0.25)
		(keepout
			(tracks allowed)
			(vias allowed)
			(pads allowed)
			(copperpour allowed)
			(footprints allowed)
		)
		(placement
			(enabled no)
			(sheetname "")
		)
		(fill
			(thermal_gap 0.5)
			(thermal_bridge_width 0.5)
			(island_removal_mode 0)
		)
		(polygon
			(pts
				(xy 29.898086 -134.619746) (xy 29.898086 -134.076186) (xy 30.403546 -134.076186) (xy 30.403546 -134.619746)
			)
		)
	)
	(zone
		(layer "Cmts.User")
		(hatch none 0.5)
		(connect_pads
			(clearance 0)
		)
		(min_thickness 0.25)
		(keepout
			(tracks allowed)
			(vias allowed)
			(pads allowed)
			(copperpour allowed)
			(footprints allowed)
		)
		(placement
			(enabled no)
			(sheetname "")
		)
		(fill
			(thermal_gap 0.5)
			(thermal_bridge_width 0.5)
			(island_removal_mode 0)
		)
		(polygon
			(pts
				(xy 35.743642 -129.401062) (xy 35.743642 -128.857502) (xy 36.249102 -128.857502) (xy 36.249102 -129.401062)
			)
		)
	)
	(zone
		(layer "Cmts.User")
		(hatch none 0.5)
		(connect_pads
			(clearance 0)
		)
		(min_thickness 0.25)
		(keepout
			(tracks allowed)
			(vias allowed)
			(pads allowed)
			(copperpour allowed)
			(footprints allowed)
		)
		(placement
			(enabled no)
			(sheetname "")
		)
		(fill
			(thermal_gap 0.5)
			(thermal_bridge_width 0.5)
			(island_removal_mode 0)
		)
		(polygon
			(pts
				(xy 352.810826 -351.972372) (xy 352.810826 -350.895412) (xy 355.902006 -350.895412) (xy 355.902006 -351.972372)
			)
		)
	)
	(zone
		(layer "Cmts.User")
		(hatch none 0.5)
		(connect_pads
			(clearance 0)
		)
		(min_thickness 0.25)
		(keepout
			(tracks allowed)
			(vias allowed)
			(pads allowed)
			(copperpour allowed)
			(footprints allowed)
		)
		(placement
			(enabled no)
			(sheetname "")
		)
		(fill
			(thermal_gap 0.5)
			(thermal_bridge_width 0.5)
			(island_removal_mode 0)
		)
		(polygon
			(pts
				(xy 169.057828 -122.83313) (xy 169.057828 -103.903272) (xy 188.060584 -103.903272) (xy 188.060584 -122.83313)
			)
		)
	)
	(zone
		(layer "Cmts.User")
		(hatch none 0.5)
		(connect_pads
			(clearance 0)
		)
		(min_thickness 0.25)
		(keepout
			(tracks allowed)
			(vias allowed)
			(pads allowed)
			(copperpour allowed)
			(footprints allowed)
		)
		(placement
			(enabled no)
			(sheetname "")
		)
		(fill
			(thermal_gap 0.5)
			(thermal_bridge_width 0.5)
			(island_removal_mode 0)
		)
		(polygon
			(pts
				(xy 418.500052 -167.4241) (xy 418.500052 -166.88054) (xy 419.005512 -166.88054) (xy 419.005512 -167.4241)
			)
		)
	)
	(zone
		(layer "Cmts.User")
		(hatch none 0.5)
		(connect_pads
			(clearance 0)
		)
		(min_thickness 0.25)
		(keepout
			(tracks allowed)
			(vias allowed)
			(pads allowed)
			(copperpour allowed)
			(footprints allowed)
		)
		(placement
			(enabled no)
			(sheetname "")
		)
		(fill
			(thermal_gap 0.5)
			(thermal_bridge_width 0.5)
			(island_removal_mode 0)
		)
		(polygon
			(pts
				(xy 418.881052 -159.3215) (xy 418.881052 -158.77794) (xy 419.386512 -158.77794) (xy 419.386512 -159.3215)
			)
		)
	)
	(zone
		(layer "Cmts.User")
		(hatch none 0.5)
		(connect_pads
			(clearance 0)
		)
		(min_thickness 0.25)
		(keepout
			(tracks allowed)
			(vias allowed)
			(pads allowed)
			(copperpour allowed)
			(footprints allowed)
		)
		(placement
			(enabled no)
			(sheetname "")
		)
		(fill
			(thermal_gap 0.5)
			(thermal_bridge_width 0.5)
			(island_removal_mode 0)
		)
		(polygon
			(pts
				(xy 74.9681 -160.50387) (xy 74.9681 -159.899604) (xy 75.551792 -159.899604) (xy 75.551792 -160.50387)
			)
		)
	)
	(zone
		(layer "Cmts.User")
		(hatch none 0.5)
		(connect_pads
			(clearance 0)
		)
		(min_thickness 0.25)
		(keepout
			(tracks allowed)
			(vias allowed)
			(pads allowed)
			(copperpour allowed)
			(footprints allowed)
		)
		(placement
			(enabled no)
			(sheetname "")
		)
		(fill
			(thermal_gap 0.5)
			(thermal_bridge_width 0.5)
			(island_removal_mode 0)
		)
		(polygon
			(pts
				(xy 90.75928 -175.598328) (xy 90.75928 -174.188628) (xy 91.39936 -174.188628) (xy 91.39936 -175.598328)
			)
		)
	)
	(zone
		(layer "Cmts.User")
		(hatch none 0.5)
		(connect_pads
			(clearance 0)
		)
		(min_thickness 0.25)
		(keepout
			(tracks allowed)
			(vias allowed)
			(pads allowed)
			(copperpour allowed)
			(footprints allowed)
		)
		(placement
			(enabled no)
			(sheetname "")
		)
		(fill
			(thermal_gap 0.5)
			(thermal_bridge_width 0.5)
			(island_removal_mode 0)
		)
		(polygon
			(pts
				(xy 355.350826 -365.221012) (xy 355.350826 -363.669072) (xy 355.952806 -363.669072) (xy 355.952806 -365.221012)
			)
		)
	)
	(zone
		(layer "Cmts.User")
		(hatch none 0.5)
		(connect_pads
			(clearance 0)
		)
		(min_thickness 0.25)
		(keepout
			(tracks allowed)
			(vias allowed)
			(pads allowed)
			(copperpour allowed)
			(footprints allowed)
		)
		(placement
			(enabled no)
			(sheetname "")
		)
		(fill
			(thermal_gap 0.5)
			(thermal_bridge_width 0.5)
			(island_removal_mode 0)
		)
		(polygon
			(pts
				(xy 428.97298 -122.758708) (xy 428.97298 -121.349008) (xy 429.61306 -121.349008) (xy 429.61306 -122.758708)
			)
		)
	)
	(zone
		(layer "Cmts.User")
		(hatch none 0.5)
		(connect_pads
			(clearance 0)
		)
		(min_thickness 0.25)
		(keepout
			(tracks allowed)
			(vias allowed)
			(pads allowed)
			(copperpour allowed)
			(footprints allowed)
		)
		(placement
			(enabled no)
			(sheetname "")
		)
		(fill
			(thermal_gap 0.5)
			(thermal_bridge_width 0.5)
			(island_removal_mode 0)
		)
		(polygon
			(pts
				(xy 419.457632 -162.740848) (xy 419.457632 -162.197288) (xy 419.963092 -162.197288) (xy 419.963092 -162.740848)
			)
		)
	)
	(zone
		(layer "Cmts.User")
		(hatch none 0.5)
		(connect_pads
			(clearance 0)
		)
		(min_thickness 0.25)
		(keepout
			(tracks allowed)
			(vias allowed)
			(pads allowed)
			(copperpour allowed)
			(footprints allowed)
		)
		(placement
			(enabled no)
			(sheetname "")
		)
		(fill
			(thermal_gap 0.5)
			(thermal_bridge_width 0.5)
			(island_removal_mode 0)
		)
		(polygon
			(pts
				(xy 381.23114 -441.307728) (xy 381.23114 -425.320968) (xy 413.55518 -425.320968) (xy 413.55518 -441.307728)
			)
		)
	)
	(zone
		(layer "Cmts.User")
		(hatch none 0.5)
		(connect_pads
			(clearance 0)
		)
		(min_thickness 0.25)
		(keepout
			(tracks allowed)
			(vias allowed)
			(pads allowed)
			(copperpour allowed)
			(footprints allowed)
		)
		(placement
			(enabled no)
			(sheetname "")
		)
		(fill
			(thermal_gap 0.5)
			(thermal_bridge_width 0.5)
			(island_removal_mode 0)
		)
		(polygon
			(pts
				(xy 421.89146 -136.845548) (xy 421.89146 -135.435848) (xy 422.53154 -135.435848) (xy 422.53154 -136.845548)
			)
		)
	)
	(zone
		(layer "Cmts.User")
		(hatch none 0.5)
		(connect_pads
			(clearance 0)
		)
		(min_thickness 0.25)
		(keepout
			(tracks allowed)
			(vias allowed)
			(pads allowed)
			(copperpour allowed)
			(footprints allowed)
		)
		(placement
			(enabled no)
			(sheetname "")
		)
		(fill
			(thermal_gap 0.5)
			(thermal_bridge_width 0.5)
			(island_removal_mode 0)
		)
		(polygon
			(pts
				(xy 419.236652 -176.0601) (xy 419.236652 -175.51654) (xy 419.742112 -175.51654) (xy 419.742112 -176.0601)
			)
		)
	)
	(zone
		(layer "Cmts.User")
		(hatch none 0.5)
		(connect_pads
			(clearance 0)
		)
		(min_thickness 0.25)
		(keepout
			(tracks allowed)
			(vias allowed)
			(pads allowed)
			(copperpour allowed)
			(footprints allowed)
		)
		(placement
			(enabled no)
			(sheetname "")
		)
		(fill
			(thermal_gap 0.5)
			(thermal_bridge_width 0.5)
			(island_removal_mode 0)
		)
		(polygon
			(pts
				(xy 48.4378 -410.929328) (xy 48.4378 -406.202388) (xy 96.66224 -406.202388) (xy 96.66224 -410.929328)
			)
		)
	)
	(zone
		(layer "Cmts.User")
		(hatch none 0.5)
		(connect_pads
			(clearance 0)
		)
		(min_thickness 0.25)
		(keepout
			(tracks allowed)
			(vias allowed)
			(pads allowed)
			(copperpour allowed)
			(footprints allowed)
		)
		(placement
			(enabled no)
			(sheetname "")
		)
		(fill
			(thermal_gap 0.5)
			(thermal_bridge_width 0.5)
			(island_removal_mode 0)
		)
		(polygon
			(pts
				(xy 27.818334 -128.654302) (xy 27.818334 -128.110742) (xy 28.323794 -128.110742) (xy 28.323794 -128.654302)
			)
		)
	)
	(zone
		(layer "Cmts.User")
		(hatch none 0.5)
		(connect_pads
			(clearance 0)
		)
		(min_thickness 0.25)
		(keepout
			(tracks allowed)
			(vias allowed)
			(pads allowed)
			(copperpour allowed)
			(footprints allowed)
		)
		(placement
			(enabled no)
			(sheetname "")
		)
		(fill
			(thermal_gap 0.5)
			(thermal_bridge_width 0.5)
			(island_removal_mode 0)
		)
		(polygon
			(pts
				(xy 418.119052 -159.3469) (xy 418.119052 -158.80334) (xy 418.624512 -158.80334) (xy 418.624512 -159.3469)
			)
		)
	)
	(zone
		(layer "Cmts.User")
		(hatch none 0.5)
		(connect_pads
			(clearance 0)
		)
		(min_thickness 0.25)
		(keepout
			(tracks allowed)
			(vias allowed)
			(pads allowed)
			(copperpour allowed)
			(footprints allowed)
		)
		(placement
			(enabled no)
			(sheetname "")
		)
		(fill
			(thermal_gap 0.5)
			(thermal_bridge_width 0.5)
			(island_removal_mode 0)
		)
		(polygon
			(pts
				(xy 364.2741 -354.950268) (xy 364.2741 -353.565968) (xy 364.90656 -353.565968) (xy 364.90656 -354.950268)
			)
		)
	)
	(zone
		(layer "In9.Cu")
		(hatch none 0.5)
		(connect_pads
			(clearance 0)
		)
		(min_thickness 0.25)
		(keepout
			(tracks not_allowed)
			(vias allowed)
			(pads allowed)
			(copperpour not_allowed)
			(footprints allowed)
		)
		(placement
			(enabled no)
			(sheetname "")
		)
		(fill
			(thermal_gap 0.5)
			(thermal_bridge_width 0.5)
			(island_removal_mode 0)
		)
		(polygon
			(pts
				(xy 7.8994 -440.568588) (xy 7.8994 -437.708548) (xy 10.5029 -437.708548) (xy 10.5029 -440.568588)
			)
		)
	)
	(zone
		(layer "In9.Cu")
		(hatch none 0.5)
		(connect_pads
			(clearance 0)
		)
		(min_thickness 0.25)
		(keepout
			(tracks not_allowed)
			(vias allowed)
			(pads allowed)
			(copperpour not_allowed)
			(footprints allowed)
		)
		(placement
			(enabled no)
			(sheetname "")
		)
		(fill
			(thermal_gap 0.5)
			(thermal_bridge_width 0.5)
			(island_removal_mode 0)
		)
		(polygon
			(pts
				(xy 461.39862 -440.672728) (xy 461.39862 -437.713628) (xy 464.00212 -437.713628) (xy 464.00212 -440.672728)
			)
		)
	)
	(zone
		(layers "In10.Cu" "In12.Cu")
		(hatch none 0.5)
		(connect_pads
			(clearance 0)
		)
		(min_thickness 0.25)
		(keepout
			(tracks not_allowed)
			(vias allowed)
			(pads allowed)
			(copperpour not_allowed)
			(footprints allowed)
		)
		(placement
			(enabled no)
			(sheetname "")
		)
		(fill yes
			(thermal_gap 0.5)
			(thermal_bridge_width 0.5)
			(island_removal_mode 0)
		)
		(polygon
			(pts
				(arc
					(start 389.242046 -427.960536)
					(mid 389.264364 -428.014418)
					(end 389.318246 -428.036736)
				)
				(arc
					(start 390.258046 -428.036736)
					(mid 390.311928 -428.014418)
					(end 390.334246 -427.960536)
				)
				(arc
					(start 390.334246 -425.419012)
					(mid 390.311928 -425.36513)
					(end 390.258046 -425.342812)
				)
				(arc
					(start 389.318246 -425.342812)
					(mid 389.264364 -425.36513)
					(end 389.242046 -425.419012)
				)
				(arc
					(start 389.242046 -426.146468)
					(mid 389.244045 -426.163809)
					(end 389.24992 -426.18025)
				)
				(arc
					(start 389.483346 -426.6565)
					(mid 389.491129 -426.690028)
					(end 389.483346 -426.723556)
				)
				(arc
					(start 389.24992 -427.199806)
					(mid 389.244025 -427.216242)
					(end 389.242046 -427.233588)
				)
			)
		)
	)
	(zone
		(layers "In10.Cu" "In12.Cu")
		(hatch none 0.5)
		(connect_pads
			(clearance 0)
		)
		(min_thickness 0.25)
		(keepout
			(tracks not_allowed)
			(vias allowed)
			(pads allowed)
			(copperpour not_allowed)
			(footprints allowed)
		)
		(placement
			(enabled no)
			(sheetname "")
		)
		(fill yes
			(thermal_gap 0.5)
			(thermal_bridge_width 0.5)
			(island_removal_mode 0)
		)
		(polygon
			(pts
				(arc
					(start 383.242058 -428.960534)
					(mid 383.264376 -429.014416)
					(end 383.318258 -429.036734)
				)
				(arc
					(start 384.258058 -429.036734)
					(mid 384.31194 -429.014416)
					(end 384.334258 -428.960534)
				)
				(arc
					(start 384.334258 -426.41901)
					(mid 384.31194 -426.365128)
					(end 384.258058 -426.34281)
				)
				(arc
					(start 383.318258 -426.34281)
					(mid 383.264376 -426.365128)
					(end 383.242058 -426.41901)
				)
				(arc
					(start 383.242058 -427.146466)
					(mid 383.244057 -427.163807)
					(end 383.249932 -427.180248)
				)
				(arc
					(start 383.483358 -427.656498)
					(mid 383.491141 -427.690026)
					(end 383.483358 -427.723554)
				)
				(arc
					(start 383.249932 -428.199804)
					(mid 383.244037 -428.21624)
					(end 383.242058 -428.233586)
				)
			)
		)
	)
	(zone
		(layers "In10.Cu" "In12.Cu")
		(hatch none 0.5)
		(connect_pads
			(clearance 0)
		)
		(min_thickness 0.25)
		(keepout
			(tracks not_allowed)
			(vias allowed)
			(pads allowed)
			(copperpour not_allowed)
			(footprints allowed)
		)
		(placement
			(enabled no)
			(sheetname "")
		)
		(fill yes
			(thermal_gap 0.5)
			(thermal_bridge_width 0.5)
			(island_removal_mode 0)
		)
		(polygon
			(pts
				(arc
					(start 385.242054 -427.960536)
					(mid 385.264372 -428.014418)
					(end 385.318254 -428.036736)
				)
				(arc
					(start 386.258054 -428.036736)
					(mid 386.311936 -428.014418)
					(end 386.334254 -427.960536)
				)
				(arc
					(start 386.334254 -425.419012)
					(mid 386.311936 -425.36513)
					(end 386.258054 -425.342812)
				)
				(arc
					(start 385.318254 -425.342812)
					(mid 385.264372 -425.36513)
					(end 385.242054 -425.419012)
				)
				(arc
					(start 385.242054 -426.146468)
					(mid 385.244053 -426.163809)
					(end 385.249928 -426.18025)
				)
				(arc
					(start 385.483354 -426.6565)
					(mid 385.491137 -426.690028)
					(end 385.483354 -426.723556)
				)
				(arc
					(start 385.249928 -427.199806)
					(mid 385.244033 -427.216242)
					(end 385.242054 -427.233588)
				)
			)
		)
	)
	(zone
		(layers "In10.Cu" "In12.Cu")
		(hatch none 0.5)
		(connect_pads
			(clearance 0)
		)
		(min_thickness 0.25)
		(keepout
			(tracks not_allowed)
			(vias allowed)
			(pads allowed)
			(copperpour not_allowed)
			(footprints allowed)
		)
		(placement
			(enabled no)
			(sheetname "")
		)
		(fill yes
			(thermal_gap 0.5)
			(thermal_bridge_width 0.5)
			(island_removal_mode 0)
		)
		(polygon
			(pts
				(arc
					(start 400.242024 -428.960534)
					(mid 400.264342 -429.014416)
					(end 400.318224 -429.036734)
				)
				(arc
					(start 401.258024 -429.036734)
					(mid 401.311906 -429.014416)
					(end 401.334224 -428.960534)
				)
				(arc
					(start 401.334224 -426.41901)
					(mid 401.311906 -426.365128)
					(end 401.258024 -426.34281)
				)
				(arc
					(start 400.318224 -426.34281)
					(mid 400.264342 -426.365128)
					(end 400.242024 -426.41901)
				)
				(arc
					(start 400.242024 -427.146466)
					(mid 400.244023 -427.163807)
					(end 400.249898 -427.180248)
				)
				(arc
					(start 400.483324 -427.656498)
					(mid 400.491107 -427.690026)
					(end 400.483324 -427.723554)
				)
				(arc
					(start 400.249898 -428.199804)
					(mid 400.244003 -428.21624)
					(end 400.242024 -428.233586)
				)
			)
		)
	)
	(zone
		(layers "In10.Cu" "In12.Cu")
		(hatch none 0.5)
		(connect_pads
			(clearance 0)
		)
		(min_thickness 0.25)
		(keepout
			(tracks not_allowed)
			(vias allowed)
			(pads allowed)
			(copperpour not_allowed)
			(footprints allowed)
		)
		(placement
			(enabled no)
			(sheetname "")
		)
		(fill yes
			(thermal_gap 0.5)
			(thermal_bridge_width 0.5)
			(island_removal_mode 0)
		)
		(polygon
			(pts
				(arc
					(start 408.242008 -428.960534)
					(mid 408.264326 -429.014416)
					(end 408.318208 -429.036734)
				)
				(arc
					(start 409.258008 -429.036734)
					(mid 409.31189 -429.014416)
					(end 409.334208 -428.960534)
				)
				(arc
					(start 409.334208 -426.41901)
					(mid 409.31189 -426.365128)
					(end 409.258008 -426.34281)
				)
				(arc
					(start 408.318208 -426.34281)
					(mid 408.264326 -426.365128)
					(end 408.242008 -426.41901)
				)
				(arc
					(start 408.242008 -427.146466)
					(mid 408.244007 -427.163807)
					(end 408.249882 -427.180248)
				)
				(arc
					(start 408.483308 -427.656498)
					(mid 408.491091 -427.690026)
					(end 408.483308 -427.723554)
				)
				(arc
					(start 408.249882 -428.199804)
					(mid 408.243987 -428.21624)
					(end 408.242008 -428.233586)
				)
			)
		)
	)
	(zone
		(layers "In10.Cu" "In12.Cu")
		(hatch none 0.5)
		(connect_pads
			(clearance 0)
		)
		(min_thickness 0.25)
		(keepout
			(tracks not_allowed)
			(vias allowed)
			(pads allowed)
			(copperpour not_allowed)
			(footprints allowed)
		)
		(placement
			(enabled no)
			(sheetname "")
		)
		(fill yes
			(thermal_gap 0.5)
			(thermal_bridge_width 0.5)
			(island_removal_mode 0)
		)
		(polygon
			(pts
				(arc
					(start 62.142116 -431.560478)
					(mid 62.164434 -431.61436)
					(end 62.218316 -431.636678)
				)
				(arc
					(start 63.158116 -431.636678)
					(mid 63.211998 -431.61436)
					(end 63.234316 -431.560478)
				)
				(arc
					(start 63.234316 -429.018954)
					(mid 63.211998 -428.965072)
					(end 63.158116 -428.942754)
				)
				(arc
					(start 62.218316 -428.942754)
					(mid 62.164434 -428.965072)
					(end 62.142116 -429.018954)
				)
				(arc
					(start 62.142116 -429.74641)
					(mid 62.144115 -429.763751)
					(end 62.14999 -429.780192)
				)
				(arc
					(start 62.383416 -430.256442)
					(mid 62.391199 -430.28997)
					(end 62.383416 -430.323498)
				)
				(arc
					(start 62.14999 -430.799748)
					(mid 62.144095 -430.816184)
					(end 62.142116 -430.83353)
				)
			)
		)
	)
	(zone
		(layers "In10.Cu" "In12.Cu")
		(hatch none 0.5)
		(connect_pads
			(clearance 0)
		)
		(min_thickness 0.25)
		(keepout
			(tracks not_allowed)
			(vias allowed)
			(pads allowed)
			(copperpour not_allowed)
			(footprints allowed)
		)
		(placement
			(enabled no)
			(sheetname "")
		)
		(fill yes
			(thermal_gap 0.5)
			(thermal_bridge_width 0.5)
			(island_removal_mode 0)
		)
		(polygon
			(pts
				(arc
					(start 412.242 -428.960534)
					(mid 412.264318 -429.014416)
					(end 412.3182 -429.036734)
				)
				(arc
					(start 413.258 -429.036734)
					(mid 413.311882 -429.014416)
					(end 413.3342 -428.960534)
				)
				(arc
					(start 413.3342 -426.41901)
					(mid 413.311882 -426.365128)
					(end 413.258 -426.34281)
				)
				(arc
					(start 412.3182 -426.34281)
					(mid 412.264318 -426.365128)
					(end 412.242 -426.41901)
				)
				(arc
					(start 412.242 -427.146466)
					(mid 412.243999 -427.163807)
					(end 412.249874 -427.180248)
				)
				(arc
					(start 412.4833 -427.656498)
					(mid 412.491083 -427.690026)
					(end 412.4833 -427.723554)
				)
				(arc
					(start 412.249874 -428.199804)
					(mid 412.243979 -428.21624)
					(end 412.242 -428.233586)
				)
			)
		)
	)
	(zone
		(layers "In10.Cu" "In12.Cu")
		(hatch none 0.5)
		(connect_pads
			(clearance 0)
		)
		(min_thickness 0.25)
		(keepout
			(tracks not_allowed)
			(vias allowed)
			(pads allowed)
			(copperpour not_allowed)
			(footprints allowed)
		)
		(placement
			(enabled no)
			(sheetname "")
		)
		(fill yes
			(thermal_gap 0.5)
			(thermal_bridge_width 0.5)
			(island_removal_mode 0)
		)
		(polygon
			(pts
				(arc
					(start 139.242038 -428.960534)
					(mid 139.264356 -429.014416)
					(end 139.318238 -429.036734)
				)
				(arc
					(start 140.258038 -429.036734)
					(mid 140.31192 -429.014416)
					(end 140.334238 -428.960534)
				)
				(arc
					(start 140.334238 -426.41901)
					(mid 140.31192 -426.365128)
					(end 140.258038 -426.34281)
				)
				(arc
					(start 139.318238 -426.34281)
					(mid 139.264356 -426.365128)
					(end 139.242038 -426.41901)
				)
				(arc
					(start 139.242038 -427.146466)
					(mid 139.244037 -427.163807)
					(end 139.249912 -427.180248)
				)
				(arc
					(start 139.483338 -427.656498)
					(mid 139.491121 -427.690026)
					(end 139.483338 -427.723554)
				)
				(arc
					(start 139.249912 -428.199804)
					(mid 139.244017 -428.21624)
					(end 139.242038 -428.233586)
				)
			)
		)
	)
	(zone
		(layers "In10.Cu" "In12.Cu")
		(hatch none 0.5)
		(connect_pads
			(clearance 0)
		)
		(min_thickness 0.25)
		(keepout
			(tracks not_allowed)
			(vias allowed)
			(pads allowed)
			(copperpour not_allowed)
			(footprints allowed)
		)
		(placement
			(enabled no)
			(sheetname "")
		)
		(fill yes
			(thermal_gap 0.5)
			(thermal_bridge_width 0.5)
			(island_removal_mode 0)
		)
		(polygon
			(pts
				(arc
					(start 125.242066 -427.960536)
					(mid 125.264384 -428.014418)
					(end 125.318266 -428.036736)
				)
				(arc
					(start 126.258066 -428.036736)
					(mid 126.311948 -428.014418)
					(end 126.334266 -427.960536)
				)
				(arc
					(start 126.334266 -425.419012)
					(mid 126.311948 -425.36513)
					(end 126.258066 -425.342812)
				)
				(arc
					(start 125.318266 -425.342812)
					(mid 125.264384 -425.36513)
					(end 125.242066 -425.419012)
				)
				(arc
					(start 125.242066 -426.146468)
					(mid 125.244065 -426.163809)
					(end 125.24994 -426.18025)
				)
				(arc
					(start 125.483366 -426.6565)
					(mid 125.491149 -426.690028)
					(end 125.483366 -426.723556)
				)
				(arc
					(start 125.24994 -427.199806)
					(mid 125.244045 -427.216242)
					(end 125.242066 -427.233588)
				)
			)
		)
	)
	(zone
		(layers "In10.Cu" "In12.Cu")
		(hatch none 0.5)
		(connect_pads
			(clearance 0)
		)
		(min_thickness 0.25)
		(keepout
			(tracks not_allowed)
			(vias allowed)
			(pads allowed)
			(copperpour not_allowed)
			(footprints allowed)
		)
		(placement
			(enabled no)
			(sheetname "")
		)
		(fill yes
			(thermal_gap 0.5)
			(thermal_bridge_width 0.5)
			(island_removal_mode 0)
		)
		(polygon
			(pts
				(arc
					(start 393.242038 -427.960536)
					(mid 393.264356 -428.014418)
					(end 393.318238 -428.036736)
				)
				(arc
					(start 394.258038 -428.036736)
					(mid 394.31192 -428.014418)
					(end 394.334238 -427.960536)
				)
				(arc
					(start 394.334238 -425.419012)
					(mid 394.31192 -425.36513)
					(end 394.258038 -425.342812)
				)
				(arc
					(start 393.318238 -425.342812)
					(mid 393.264356 -425.36513)
					(end 393.242038 -425.419012)
				)
				(arc
					(start 393.242038 -426.146468)
					(mid 393.244037 -426.163809)
					(end 393.249912 -426.18025)
				)
				(arc
					(start 393.483338 -426.6565)
					(mid 393.491121 -426.690028)
					(end 393.483338 -426.723556)
				)
				(arc
					(start 393.249912 -427.199806)
					(mid 393.244017 -427.216242)
					(end 393.242038 -427.233588)
				)
			)
		)
	)
	(zone
		(layers "In10.Cu" "In12.Cu")
		(hatch none 0.5)
		(connect_pads
			(clearance 0)
		)
		(min_thickness 0.25)
		(keepout
			(tracks not_allowed)
			(vias allowed)
			(pads allowed)
			(copperpour not_allowed)
			(footprints allowed)
		)
		(placement
			(enabled no)
			(sheetname "")
		)
		(fill yes
			(thermal_gap 0.5)
			(thermal_bridge_width 0.5)
			(island_removal_mode 0)
		)
		(polygon
			(pts
				(arc
					(start 331.142086 -431.560478)
					(mid 331.164404 -431.61436)
					(end 331.218286 -431.636678)
				)
				(arc
					(start 332.158086 -431.636678)
					(mid 332.211968 -431.61436)
					(end 332.234286 -431.560478)
				)
				(arc
					(start 332.234286 -429.018954)
					(mid 332.211968 -428.965072)
					(end 332.158086 -428.942754)
				)
				(arc
					(start 331.218286 -428.942754)
					(mid 331.164404 -428.965072)
					(end 331.142086 -429.018954)
				)
				(arc
					(start 331.142086 -429.74641)
					(mid 331.144085 -429.763751)
					(end 331.14996 -429.780192)
				)
				(arc
					(start 331.383386 -430.256442)
					(mid 331.391169 -430.28997)
					(end 331.383386 -430.323498)
				)
				(arc
					(start 331.14996 -430.799748)
					(mid 331.144065 -430.816184)
					(end 331.142086 -430.83353)
				)
			)
		)
	)
	(zone
		(layers "In10.Cu" "In12.Cu")
		(hatch none 0.5)
		(connect_pads
			(clearance 0)
		)
		(min_thickness 0.25)
		(keepout
			(tracks not_allowed)
			(vias allowed)
			(pads allowed)
			(copperpour not_allowed)
			(footprints allowed)
		)
		(placement
			(enabled no)
			(sheetname "")
		)
		(fill yes
			(thermal_gap 0.5)
			(thermal_bridge_width 0.5)
			(island_removal_mode 0)
		)
		(polygon
			(pts
				(arc
					(start 137.242042 -427.960536)
					(mid 137.26436 -428.014418)
					(end 137.318242 -428.036736)
				)
				(arc
					(start 138.258042 -428.036736)
					(mid 138.311924 -428.014418)
					(end 138.334242 -427.960536)
				)
				(arc
					(start 138.334242 -425.419012)
					(mid 138.311924 -425.36513)
					(end 138.258042 -425.342812)
				)
				(arc
					(start 137.318242 -425.342812)
					(mid 137.26436 -425.36513)
					(end 137.242042 -425.419012)
				)
				(arc
					(start 137.242042 -426.146468)
					(mid 137.244041 -426.163809)
					(end 137.249916 -426.18025)
				)
				(arc
					(start 137.483342 -426.6565)
					(mid 137.491125 -426.690028)
					(end 137.483342 -426.723556)
				)
				(arc
					(start 137.249916 -427.199806)
					(mid 137.244021 -427.216242)
					(end 137.242042 -427.233588)
				)
			)
		)
	)
	(zone
		(layers "In10.Cu" "In12.Cu")
		(hatch none 0.5)
		(connect_pads
			(clearance 0)
		)
		(min_thickness 0.25)
		(keepout
			(tracks not_allowed)
			(vias allowed)
			(pads allowed)
			(copperpour not_allowed)
			(footprints allowed)
		)
		(placement
			(enabled no)
			(sheetname "")
		)
		(fill yes
			(thermal_gap 0.5)
			(thermal_bridge_width 0.5)
			(island_removal_mode 0)
		)
		(polygon
			(pts
				(arc
					(start 64.142112 -432.560476)
					(mid 64.16443 -432.614358)
					(end 64.218312 -432.636676)
				)
				(arc
					(start 65.158112 -432.636676)
					(mid 65.211994 -432.614358)
					(end 65.234312 -432.560476)
				)
				(arc
					(start 65.234312 -430.018952)
					(mid 65.211994 -429.96507)
					(end 65.158112 -429.942752)
				)
				(arc
					(start 64.218312 -429.942752)
					(mid 64.16443 -429.96507)
					(end 64.142112 -430.018952)
				)
				(arc
					(start 64.142112 -430.746408)
					(mid 64.144111 -430.763749)
					(end 64.149986 -430.78019)
				)
				(arc
					(start 64.383412 -431.25644)
					(mid 64.391195 -431.289968)
					(end 64.383412 -431.323496)
				)
				(arc
					(start 64.149986 -431.799746)
					(mid 64.144091 -431.816182)
					(end 64.142112 -431.833528)
				)
			)
		)
	)
	(zone
		(layers "In10.Cu" "In12.Cu")
		(hatch none 0.5)
		(connect_pads
			(clearance 0)
		)
		(min_thickness 0.25)
		(keepout
			(tracks not_allowed)
			(vias allowed)
			(pads allowed)
			(copperpour not_allowed)
			(footprints allowed)
		)
		(placement
			(enabled no)
			(sheetname "")
		)
		(fill yes
			(thermal_gap 0.5)
			(thermal_bridge_width 0.5)
			(island_removal_mode 0)
		)
		(polygon
			(pts
				(arc
					(start 387.24205 -428.960534)
					(mid 387.264368 -429.014416)
					(end 387.31825 -429.036734)
				)
				(arc
					(start 388.25805 -429.036734)
					(mid 388.311932 -429.014416)
					(end 388.33425 -428.960534)
				)
				(arc
					(start 388.33425 -426.41901)
					(mid 388.311932 -426.365128)
					(end 388.25805 -426.34281)
				)
				(arc
					(start 387.31825 -426.34281)
					(mid 387.264368 -426.365128)
					(end 387.24205 -426.41901)
				)
				(arc
					(start 387.24205 -427.146466)
					(mid 387.244049 -427.163807)
					(end 387.249924 -427.180248)
				)
				(arc
					(start 387.48335 -427.656498)
					(mid 387.491133 -427.690026)
					(end 387.48335 -427.723554)
				)
				(arc
					(start 387.249924 -428.199804)
					(mid 387.244029 -428.21624)
					(end 387.24205 -428.233586)
				)
			)
		)
	)
	(zone
		(layers "In10.Cu" "In12.Cu")
		(hatch none 0.5)
		(connect_pads
			(clearance 0)
		)
		(min_thickness 0.25)
		(keepout
			(tracks not_allowed)
			(vias allowed)
			(pads allowed)
			(copperpour not_allowed)
			(footprints allowed)
		)
		(placement
			(enabled no)
			(sheetname "")
		)
		(fill yes
			(thermal_gap 0.5)
			(thermal_bridge_width 0.5)
			(island_removal_mode 0)
		)
		(polygon
			(pts
				(arc
					(start 146.242024 -427.960536)
					(mid 146.264342 -428.014418)
					(end 146.318224 -428.036736)
				)
				(arc
					(start 147.258024 -428.036736)
					(mid 147.311906 -428.014418)
					(end 147.334224 -427.960536)
				)
				(arc
					(start 147.334224 -425.419012)
					(mid 147.311906 -425.36513)
					(end 147.258024 -425.342812)
				)
				(arc
					(start 146.318224 -425.342812)
					(mid 146.264342 -425.36513)
					(end 146.242024 -425.419012)
				)
				(arc
					(start 146.242024 -426.146468)
					(mid 146.244023 -426.163809)
					(end 146.249898 -426.18025)
				)
				(arc
					(start 146.483324 -426.6565)
					(mid 146.491107 -426.690028)
					(end 146.483324 -426.723556)
				)
				(arc
					(start 146.249898 -427.199806)
					(mid 146.244003 -427.216242)
					(end 146.242024 -427.233588)
				)
			)
		)
	)
	(zone
		(layers "In10.Cu" "In12.Cu")
		(hatch none 0.5)
		(connect_pads
			(clearance 0)
		)
		(min_thickness 0.25)
		(keepout
			(tracks not_allowed)
			(vias allowed)
			(pads allowed)
			(copperpour not_allowed)
			(footprints allowed)
		)
		(placement
			(enabled no)
			(sheetname "")
		)
		(fill yes
			(thermal_gap 0.5)
			(thermal_bridge_width 0.5)
			(island_removal_mode 0)
		)
		(polygon
			(pts
				(arc
					(start 333.142082 -432.560476)
					(mid 333.1644 -432.614358)
					(end 333.218282 -432.636676)
				)
				(arc
					(start 334.158082 -432.636676)
					(mid 334.211964 -432.614358)
					(end 334.234282 -432.560476)
				)
				(arc
					(start 334.234282 -430.018952)
					(mid 334.211964 -429.96507)
					(end 334.158082 -429.942752)
				)
				(arc
					(start 333.218282 -429.942752)
					(mid 333.1644 -429.96507)
					(end 333.142082 -430.018952)
				)
				(arc
					(start 333.142082 -430.746408)
					(mid 333.144081 -430.763749)
					(end 333.149956 -430.78019)
				)
				(arc
					(start 333.383382 -431.25644)
					(mid 333.391165 -431.289968)
					(end 333.383382 -431.323496)
				)
				(arc
					(start 333.149956 -431.799746)
					(mid 333.144061 -431.816182)
					(end 333.142082 -431.833528)
				)
			)
		)
	)
	(zone
		(layers "In10.Cu" "In12.Cu")
		(hatch none 0.5)
		(connect_pads
			(clearance 0)
		)
		(min_thickness 0.25)
		(keepout
			(tracks not_allowed)
			(vias allowed)
			(pads allowed)
			(copperpour not_allowed)
			(footprints allowed)
		)
		(placement
			(enabled no)
			(sheetname "")
		)
		(fill yes
			(thermal_gap 0.5)
			(thermal_bridge_width 0.5)
			(island_removal_mode 0)
		)
		(polygon
			(pts
				(arc
					(start 150.242016 -427.960536)
					(mid 150.264334 -428.014418)
					(end 150.318216 -428.036736)
				)
				(arc
					(start 151.258016 -428.036736)
					(mid 151.311898 -428.014418)
					(end 151.334216 -427.960536)
				)
				(arc
					(start 151.334216 -425.419012)
					(mid 151.311898 -425.36513)
					(end 151.258016 -425.342812)
				)
				(arc
					(start 150.318216 -425.342812)
					(mid 150.264334 -425.36513)
					(end 150.242016 -425.419012)
				)
				(arc
					(start 150.242016 -426.146468)
					(mid 150.244015 -426.163809)
					(end 150.24989 -426.18025)
				)
				(arc
					(start 150.483316 -426.6565)
					(mid 150.491099 -426.690028)
					(end 150.483316 -426.723556)
				)
				(arc
					(start 150.24989 -427.199806)
					(mid 150.243995 -427.216242)
					(end 150.242016 -427.233588)
				)
			)
		)
	)
	(zone
		(layers "In10.Cu" "In12.Cu")
		(hatch none 0.5)
		(connect_pads
			(clearance 0)
		)
		(min_thickness 0.25)
		(keepout
			(tracks not_allowed)
			(vias allowed)
			(pads allowed)
			(copperpour not_allowed)
			(footprints allowed)
		)
		(placement
			(enabled no)
			(sheetname "")
		)
		(fill yes
			(thermal_gap 0.5)
			(thermal_bridge_width 0.5)
			(island_removal_mode 0)
		)
		(polygon
			(pts
				(arc
					(start 381.242062 -427.960536)
					(mid 381.26438 -428.014418)
					(end 381.318262 -428.036736)
				)
				(arc
					(start 382.258062 -428.036736)
					(mid 382.311944 -428.014418)
					(end 382.334262 -427.960536)
				)
				(arc
					(start 382.334262 -425.419012)
					(mid 382.311944 -425.36513)
					(end 382.258062 -425.342812)
				)
				(arc
					(start 381.318262 -425.342812)
					(mid 381.26438 -425.36513)
					(end 381.242062 -425.419012)
				)
				(arc
					(start 381.242062 -426.146468)
					(mid 381.244061 -426.163809)
					(end 381.249936 -426.18025)
				)
				(arc
					(start 381.483362 -426.6565)
					(mid 381.491145 -426.690028)
					(end 381.483362 -426.723556)
				)
				(arc
					(start 381.249936 -427.199806)
					(mid 381.244041 -427.216242)
					(end 381.242062 -427.233588)
				)
			)
		)
	)
	(zone
		(layers "In10.Cu" "In12.Cu")
		(hatch none 0.5)
		(connect_pads
			(clearance 0)
		)
		(min_thickness 0.25)
		(keepout
			(tracks not_allowed)
			(vias allowed)
			(pads allowed)
			(copperpour not_allowed)
			(footprints allowed)
		)
		(placement
			(enabled no)
			(sheetname "")
		)
		(fill yes
			(thermal_gap 0.5)
			(thermal_bridge_width 0.5)
			(island_removal_mode 0)
		)
		(polygon
			(pts
				(arc
					(start 70.1421 -431.560478)
					(mid 70.164418 -431.61436)
					(end 70.2183 -431.636678)
				)
				(arc
					(start 71.1581 -431.636678)
					(mid 71.211982 -431.61436)
					(end 71.2343 -431.560478)
				)
				(arc
					(start 71.2343 -429.018954)
					(mid 71.211982 -428.965072)
					(end 71.1581 -428.942754)
				)
				(arc
					(start 70.2183 -428.942754)
					(mid 70.164418 -428.965072)
					(end 70.1421 -429.018954)
				)
				(arc
					(start 70.1421 -429.74641)
					(mid 70.144099 -429.763751)
					(end 70.149974 -429.780192)
				)
				(arc
					(start 70.3834 -430.256442)
					(mid 70.391183 -430.28997)
					(end 70.3834 -430.323498)
				)
				(arc
					(start 70.149974 -430.799748)
					(mid 70.144079 -430.816184)
					(end 70.1421 -430.83353)
				)
			)
		)
	)
	(zone
		(layers "In10.Cu" "In12.Cu")
		(hatch none 0.5)
		(connect_pads
			(clearance 0)
		)
		(min_thickness 0.25)
		(keepout
			(tracks not_allowed)
			(vias allowed)
			(pads allowed)
			(copperpour not_allowed)
			(footprints allowed)
		)
		(placement
			(enabled no)
			(sheetname "")
		)
		(fill yes
			(thermal_gap 0.5)
			(thermal_bridge_width 0.5)
			(island_removal_mode 0)
		)
		(polygon
			(pts
				(arc
					(start 345.142058 -432.560476)
					(mid 345.164376 -432.614358)
					(end 345.218258 -432.636676)
				)
				(arc
					(start 346.158058 -432.636676)
					(mid 346.21194 -432.614358)
					(end 346.234258 -432.560476)
				)
				(arc
					(start 346.234258 -430.018952)
					(mid 346.21194 -429.96507)
					(end 346.158058 -429.942752)
				)
				(arc
					(start 345.218258 -429.942752)
					(mid 345.164376 -429.96507)
					(end 345.142058 -430.018952)
				)
				(arc
					(start 345.142058 -430.746408)
					(mid 345.144057 -430.763749)
					(end 345.149932 -430.78019)
				)
				(arc
					(start 345.383358 -431.25644)
					(mid 345.391141 -431.289968)
					(end 345.383358 -431.323496)
				)
				(arc
					(start 345.149932 -431.799746)
					(mid 345.144037 -431.816182)
					(end 345.142058 -431.833528)
				)
			)
		)
	)
	(zone
		(layers "In10.Cu" "In12.Cu")
		(hatch none 0.5)
		(connect_pads
			(clearance 0)
		)
		(min_thickness 0.25)
		(keepout
			(tracks not_allowed)
			(vias allowed)
			(pads allowed)
			(copperpour not_allowed)
			(footprints allowed)
		)
		(placement
			(enabled no)
			(sheetname "")
		)
		(fill yes
			(thermal_gap 0.5)
			(thermal_bridge_width 0.5)
			(island_removal_mode 0)
		)
		(polygon
			(pts
				(arc
					(start 129.242058 -427.960536)
					(mid 129.264376 -428.014418)
					(end 129.318258 -428.036736)
				)
				(arc
					(start 130.258058 -428.036736)
					(mid 130.31194 -428.014418)
					(end 130.334258 -427.960536)
				)
				(arc
					(start 130.334258 -425.419012)
					(mid 130.31194 -425.36513)
					(end 130.258058 -425.342812)
				)
				(arc
					(start 129.318258 -425.342812)
					(mid 129.264376 -425.36513)
					(end 129.242058 -425.419012)
				)
				(arc
					(start 129.242058 -426.146468)
					(mid 129.244057 -426.163809)
					(end 129.249932 -426.18025)
				)
				(arc
					(start 129.483358 -426.6565)
					(mid 129.491141 -426.690028)
					(end 129.483358 -426.723556)
				)
				(arc
					(start 129.249932 -427.199806)
					(mid 129.244037 -427.216242)
					(end 129.242058 -427.233588)
				)
			)
		)
	)
	(zone
		(layers "In10.Cu" "In12.Cu")
		(hatch none 0.5)
		(connect_pads
			(clearance 0)
		)
		(min_thickness 0.25)
		(keepout
			(tracks not_allowed)
			(vias allowed)
			(pads allowed)
			(copperpour not_allowed)
			(footprints allowed)
		)
		(placement
			(enabled no)
			(sheetname "")
		)
		(fill yes
			(thermal_gap 0.5)
			(thermal_bridge_width 0.5)
			(island_removal_mode 0)
		)
		(polygon
			(pts
				(arc
					(start 395.242034 -428.960534)
					(mid 395.264352 -429.014416)
					(end 395.318234 -429.036734)
				)
				(arc
					(start 396.258034 -429.036734)
					(mid 396.311916 -429.014416)
					(end 396.334234 -428.960534)
				)
				(arc
					(start 396.334234 -426.41901)
					(mid 396.311916 -426.365128)
					(end 396.258034 -426.34281)
				)
				(arc
					(start 395.318234 -426.34281)
					(mid 395.264352 -426.365128)
					(end 395.242034 -426.41901)
				)
				(arc
					(start 395.242034 -427.146466)
					(mid 395.244033 -427.163807)
					(end 395.249908 -427.180248)
				)
				(arc
					(start 395.483334 -427.656498)
					(mid 395.491117 -427.690026)
					(end 395.483334 -427.723554)
				)
				(arc
					(start 395.249908 -428.199804)
					(mid 395.244013 -428.21624)
					(end 395.242034 -428.233586)
				)
			)
		)
	)
	(zone
		(layers "In10.Cu" "In12.Cu")
		(hatch none 0.5)
		(connect_pads
			(clearance 0)
		)
		(min_thickness 0.25)
		(keepout
			(tracks not_allowed)
			(vias allowed)
			(pads allowed)
			(copperpour not_allowed)
			(footprints allowed)
		)
		(placement
			(enabled no)
			(sheetname "")
		)
		(fill yes
			(thermal_gap 0.5)
			(thermal_bridge_width 0.5)
			(island_removal_mode 0)
		)
		(polygon
			(pts
				(arc
					(start 314.14212 -431.560478)
					(mid 314.164438 -431.61436)
					(end 314.21832 -431.636678)
				)
				(arc
					(start 315.15812 -431.636678)
					(mid 315.212002 -431.61436)
					(end 315.23432 -431.560478)
				)
				(arc
					(start 315.23432 -429.018954)
					(mid 315.212002 -428.965072)
					(end 315.15812 -428.942754)
				)
				(arc
					(start 314.21832 -428.942754)
					(mid 314.164438 -428.965072)
					(end 314.14212 -429.018954)
				)
				(arc
					(start 314.14212 -429.74641)
					(mid 314.144119 -429.763751)
					(end 314.149994 -429.780192)
				)
				(arc
					(start 314.38342 -430.256442)
					(mid 314.391203 -430.28997)
					(end 314.38342 -430.323498)
				)
				(arc
					(start 314.149994 -430.799748)
					(mid 314.144099 -430.816184)
					(end 314.14212 -430.83353)
				)
			)
		)
	)
	(zone
		(layers "In10.Cu" "In12.Cu")
		(hatch none 0.5)
		(connect_pads
			(clearance 0)
		)
		(min_thickness 0.25)
		(keepout
			(tracks not_allowed)
			(vias allowed)
			(pads allowed)
			(copperpour not_allowed)
			(footprints allowed)
		)
		(placement
			(enabled no)
			(sheetname "")
		)
		(fill yes
			(thermal_gap 0.5)
			(thermal_bridge_width 0.5)
			(island_removal_mode 0)
		)
		(polygon
			(pts
				(arc
					(start 142.242032 -427.960536)
					(mid 142.26435 -428.014418)
					(end 142.318232 -428.036736)
				)
				(arc
					(start 143.258032 -428.036736)
					(mid 143.311914 -428.014418)
					(end 143.334232 -427.960536)
				)
				(arc
					(start 143.334232 -425.419012)
					(mid 143.311914 -425.36513)
					(end 143.258032 -425.342812)
				)
				(arc
					(start 142.318232 -425.342812)
					(mid 142.26435 -425.36513)
					(end 142.242032 -425.419012)
				)
				(arc
					(start 142.242032 -426.146468)
					(mid 142.244031 -426.163809)
					(end 142.249906 -426.18025)
				)
				(arc
					(start 142.483332 -426.6565)
					(mid 142.491115 -426.690028)
					(end 142.483332 -426.723556)
				)
				(arc
					(start 142.249906 -427.199806)
					(mid 142.244011 -427.216242)
					(end 142.242032 -427.233588)
				)
			)
		)
	)
	(zone
		(layers "In10.Cu" "In12.Cu")
		(hatch none 0.5)
		(connect_pads
			(clearance 0)
		)
		(min_thickness 0.25)
		(keepout
			(tracks not_allowed)
			(vias allowed)
			(pads allowed)
			(copperpour not_allowed)
			(footprints allowed)
		)
		(placement
			(enabled no)
			(sheetname "")
		)
		(fill yes
			(thermal_gap 0.5)
			(thermal_bridge_width 0.5)
			(island_removal_mode 0)
		)
		(polygon
			(pts
				(arc
					(start 410.242004 -427.960536)
					(mid 410.264322 -428.014418)
					(end 410.318204 -428.036736)
				)
				(arc
					(start 411.258004 -428.036736)
					(mid 411.311886 -428.014418)
					(end 411.334204 -427.960536)
				)
				(arc
					(start 411.334204 -425.419012)
					(mid 411.311886 -425.36513)
					(end 411.258004 -425.342812)
				)
				(arc
					(start 410.318204 -425.342812)
					(mid 410.264322 -425.36513)
					(end 410.242004 -425.419012)
				)
				(arc
					(start 410.242004 -426.146468)
					(mid 410.244003 -426.163809)
					(end 410.249878 -426.18025)
				)
				(arc
					(start 410.483304 -426.6565)
					(mid 410.491087 -426.690028)
					(end 410.483304 -426.723556)
				)
				(arc
					(start 410.249878 -427.199806)
					(mid 410.243983 -427.216242)
					(end 410.242004 -427.233588)
				)
			)
		)
	)
	(zone
		(layers "In10.Cu" "In12.Cu")
		(hatch none 0.5)
		(connect_pads
			(clearance 0)
		)
		(min_thickness 0.25)
		(keepout
			(tracks not_allowed)
			(vias allowed)
			(pads allowed)
			(copperpour not_allowed)
			(footprints allowed)
		)
		(placement
			(enabled no)
			(sheetname "")
		)
		(fill yes
			(thermal_gap 0.5)
			(thermal_bridge_width 0.5)
			(island_removal_mode 0)
		)
		(polygon
			(pts
				(arc
					(start 79.142082 -431.560478)
					(mid 79.1644 -431.61436)
					(end 79.218282 -431.636678)
				)
				(arc
					(start 80.158082 -431.636678)
					(mid 80.211964 -431.61436)
					(end 80.234282 -431.560478)
				)
				(arc
					(start 80.234282 -429.018954)
					(mid 80.211964 -428.965072)
					(end 80.158082 -428.942754)
				)
				(arc
					(start 79.218282 -428.942754)
					(mid 79.1644 -428.965072)
					(end 79.142082 -429.018954)
				)
				(arc
					(start 79.142082 -429.74641)
					(mid 79.144081 -429.763751)
					(end 79.149956 -429.780192)
				)
				(arc
					(start 79.383382 -430.256442)
					(mid 79.391165 -430.28997)
					(end 79.383382 -430.323498)
				)
				(arc
					(start 79.149956 -430.799748)
					(mid 79.144061 -430.816184)
					(end 79.142082 -430.83353)
				)
			)
		)
	)
	(zone
		(layers "In10.Cu" "In12.Cu")
		(hatch none 0.5)
		(connect_pads
			(clearance 0)
		)
		(min_thickness 0.25)
		(keepout
			(tracks not_allowed)
			(vias allowed)
			(pads allowed)
			(copperpour not_allowed)
			(footprints allowed)
		)
		(placement
			(enabled no)
			(sheetname "")
		)
		(fill yes
			(thermal_gap 0.5)
			(thermal_bridge_width 0.5)
			(island_removal_mode 0)
		)
		(polygon
			(pts
				(arc
					(start 326.142096 -431.560478)
					(mid 326.164414 -431.61436)
					(end 326.218296 -431.636678)
				)
				(arc
					(start 327.158096 -431.636678)
					(mid 327.211978 -431.61436)
					(end 327.234296 -431.560478)
				)
				(arc
					(start 327.234296 -429.018954)
					(mid 327.211978 -428.965072)
					(end 327.158096 -428.942754)
				)
				(arc
					(start 326.218296 -428.942754)
					(mid 326.164414 -428.965072)
					(end 326.142096 -429.018954)
				)
				(arc
					(start 326.142096 -429.74641)
					(mid 326.144095 -429.763751)
					(end 326.14997 -429.780192)
				)
				(arc
					(start 326.383396 -430.256442)
					(mid 326.391179 -430.28997)
					(end 326.383396 -430.323498)
				)
				(arc
					(start 326.14997 -430.799748)
					(mid 326.144075 -430.816184)
					(end 326.142096 -430.83353)
				)
			)
		)
	)
	(zone
		(layers "In10.Cu" "In12.Cu")
		(hatch none 0.5)
		(connect_pads
			(clearance 0)
		)
		(min_thickness 0.25)
		(keepout
			(tracks not_allowed)
			(vias allowed)
			(pads allowed)
			(copperpour not_allowed)
			(footprints allowed)
		)
		(placement
			(enabled no)
			(sheetname "")
		)
		(fill yes
			(thermal_gap 0.5)
			(thermal_bridge_width 0.5)
			(island_removal_mode 0)
		)
		(polygon
			(pts
				(arc
					(start 60.14212 -432.560476)
					(mid 60.164438 -432.614358)
					(end 60.21832 -432.636676)
				)
				(arc
					(start 61.15812 -432.636676)
					(mid 61.212002 -432.614358)
					(end 61.23432 -432.560476)
				)
				(arc
					(start 61.23432 -430.018952)
					(mid 61.212002 -429.96507)
					(end 61.15812 -429.942752)
				)
				(arc
					(start 60.21832 -429.942752)
					(mid 60.164438 -429.96507)
					(end 60.14212 -430.018952)
				)
				(arc
					(start 60.14212 -430.746408)
					(mid 60.144119 -430.763749)
					(end 60.149994 -430.78019)
				)
				(arc
					(start 60.38342 -431.25644)
					(mid 60.391203 -431.289968)
					(end 60.38342 -431.323496)
				)
				(arc
					(start 60.149994 -431.799746)
					(mid 60.144099 -431.816182)
					(end 60.14212 -431.833528)
				)
			)
		)
	)
	(zone
		(layers "In10.Cu" "In12.Cu")
		(hatch none 0.5)
		(connect_pads
			(clearance 0)
		)
		(min_thickness 0.25)
		(keepout
			(tracks not_allowed)
			(vias allowed)
			(pads allowed)
			(copperpour not_allowed)
			(footprints allowed)
		)
		(placement
			(enabled no)
			(sheetname "")
		)
		(fill yes
			(thermal_gap 0.5)
			(thermal_bridge_width 0.5)
			(island_removal_mode 0)
		)
		(polygon
			(pts
				(arc
					(start 144.242028 -428.960534)
					(mid 144.264346 -429.014416)
					(end 144.318228 -429.036734)
				)
				(arc
					(start 145.258028 -429.036734)
					(mid 145.31191 -429.014416)
					(end 145.334228 -428.960534)
				)
				(arc
					(start 145.334228 -426.41901)
					(mid 145.31191 -426.365128)
					(end 145.258028 -426.34281)
				)
				(arc
					(start 144.318228 -426.34281)
					(mid 144.264346 -426.365128)
					(end 144.242028 -426.41901)
				)
				(arc
					(start 144.242028 -427.146466)
					(mid 144.244027 -427.163807)
					(end 144.249902 -427.180248)
				)
				(arc
					(start 144.483328 -427.656498)
					(mid 144.491111 -427.690026)
					(end 144.483328 -427.723554)
				)
				(arc
					(start 144.249902 -428.199804)
					(mid 144.244007 -428.21624)
					(end 144.242028 -428.233586)
				)
			)
		)
	)
	(zone
		(layers "In10.Cu" "In12.Cu")
		(hatch none 0.5)
		(connect_pads
			(clearance 0)
		)
		(min_thickness 0.25)
		(keepout
			(tracks not_allowed)
			(vias allowed)
			(pads allowed)
			(copperpour not_allowed)
			(footprints allowed)
		)
		(placement
			(enabled no)
			(sheetname "")
		)
		(fill yes
			(thermal_gap 0.5)
			(thermal_bridge_width 0.5)
			(island_removal_mode 0)
		)
		(polygon
			(pts
				(arc
					(start 341.142066 -432.560476)
					(mid 341.164384 -432.614358)
					(end 341.218266 -432.636676)
				)
				(arc
					(start 342.158066 -432.636676)
					(mid 342.211948 -432.614358)
					(end 342.234266 -432.560476)
				)
				(arc
					(start 342.234266 -430.018952)
					(mid 342.211948 -429.96507)
					(end 342.158066 -429.942752)
				)
				(arc
					(start 341.218266 -429.942752)
					(mid 341.164384 -429.96507)
					(end 341.142066 -430.018952)
				)
				(arc
					(start 341.142066 -430.746408)
					(mid 341.144065 -430.763749)
					(end 341.14994 -430.78019)
				)
				(arc
					(start 341.383366 -431.25644)
					(mid 341.391149 -431.289968)
					(end 341.383366 -431.323496)
				)
				(arc
					(start 341.14994 -431.799746)
					(mid 341.144045 -431.816182)
					(end 341.142066 -431.833528)
				)
			)
		)
	)
	(zone
		(layers "In10.Cu" "In12.Cu")
		(hatch none 0.5)
		(connect_pads
			(clearance 0)
		)
		(min_thickness 0.25)
		(keepout
			(tracks not_allowed)
			(vias allowed)
			(pads allowed)
			(copperpour not_allowed)
			(footprints allowed)
		)
		(placement
			(enabled no)
			(sheetname "")
		)
		(fill yes
			(thermal_gap 0.5)
			(thermal_bridge_width 0.5)
			(island_removal_mode 0)
		)
		(polygon
			(pts
				(arc
					(start 343.142062 -431.560478)
					(mid 343.16438 -431.61436)
					(end 343.218262 -431.636678)
				)
				(arc
					(start 344.158062 -431.636678)
					(mid 344.211944 -431.61436)
					(end 344.234262 -431.560478)
				)
				(arc
					(start 344.234262 -429.018954)
					(mid 344.211944 -428.965072)
					(end 344.158062 -428.942754)
				)
				(arc
					(start 343.218262 -428.942754)
					(mid 343.16438 -428.965072)
					(end 343.142062 -429.018954)
				)
				(arc
					(start 343.142062 -429.74641)
					(mid 343.144061 -429.763751)
					(end 343.149936 -429.780192)
				)
				(arc
					(start 343.383362 -430.256442)
					(mid 343.391145 -430.28997)
					(end 343.383362 -430.323498)
				)
				(arc
					(start 343.149936 -430.799748)
					(mid 343.144041 -430.816184)
					(end 343.142062 -430.83353)
				)
			)
		)
	)
	(zone
		(layers "In10.Cu" "In12.Cu")
		(hatch none 0.5)
		(connect_pads
			(clearance 0)
		)
		(min_thickness 0.25)
		(keepout
			(tracks not_allowed)
			(vias allowed)
			(pads allowed)
			(copperpour not_allowed)
			(footprints allowed)
		)
		(placement
			(enabled no)
			(sheetname "")
		)
		(fill yes
			(thermal_gap 0.5)
			(thermal_bridge_width 0.5)
			(island_removal_mode 0)
		)
		(polygon
			(pts
				(arc
					(start 85.14207 -432.560476)
					(mid 85.164388 -432.614358)
					(end 85.21827 -432.636676)
				)
				(arc
					(start 86.15807 -432.636676)
					(mid 86.211952 -432.614358)
					(end 86.23427 -432.560476)
				)
				(arc
					(start 86.23427 -430.018952)
					(mid 86.211952 -429.96507)
					(end 86.15807 -429.942752)
				)
				(arc
					(start 85.21827 -429.942752)
					(mid 85.164388 -429.96507)
					(end 85.14207 -430.018952)
				)
				(arc
					(start 85.14207 -430.746408)
					(mid 85.144069 -430.763749)
					(end 85.149944 -430.78019)
				)
				(arc
					(start 85.38337 -431.25644)
					(mid 85.391153 -431.289968)
					(end 85.38337 -431.323496)
				)
				(arc
					(start 85.149944 -431.799746)
					(mid 85.144049 -431.816182)
					(end 85.14207 -431.833528)
				)
			)
		)
	)
	(zone
		(layers "In10.Cu" "In12.Cu")
		(hatch none 0.5)
		(connect_pads
			(clearance 0)
		)
		(min_thickness 0.25)
		(keepout
			(tracks not_allowed)
			(vias allowed)
			(pads allowed)
			(copperpour not_allowed)
			(footprints allowed)
		)
		(placement
			(enabled no)
			(sheetname "")
		)
		(fill yes
			(thermal_gap 0.5)
			(thermal_bridge_width 0.5)
			(island_removal_mode 0)
		)
		(polygon
			(pts
				(arc
					(start 316.142116 -432.560476)
					(mid 316.164434 -432.614358)
					(end 316.218316 -432.636676)
				)
				(arc
					(start 317.158116 -432.636676)
					(mid 317.211998 -432.614358)
					(end 317.234316 -432.560476)
				)
				(arc
					(start 317.234316 -430.018952)
					(mid 317.211998 -429.96507)
					(end 317.158116 -429.942752)
				)
				(arc
					(start 316.218316 -429.942752)
					(mid 316.164434 -429.96507)
					(end 316.142116 -430.018952)
				)
				(arc
					(start 316.142116 -430.746408)
					(mid 316.144115 -430.763749)
					(end 316.14999 -430.78019)
				)
				(arc
					(start 316.383416 -431.25644)
					(mid 316.391199 -431.289968)
					(end 316.383416 -431.323496)
				)
				(arc
					(start 316.14999 -431.799746)
					(mid 316.144095 -431.816182)
					(end 316.142116 -431.833528)
				)
			)
		)
	)
	(zone
		(layers "In10.Cu" "In12.Cu")
		(hatch none 0.5)
		(connect_pads
			(clearance 0)
		)
		(min_thickness 0.25)
		(keepout
			(tracks not_allowed)
			(vias allowed)
			(pads allowed)
			(copperpour not_allowed)
			(footprints allowed)
		)
		(placement
			(enabled no)
			(sheetname "")
		)
		(fill yes
			(thermal_gap 0.5)
			(thermal_bridge_width 0.5)
			(island_removal_mode 0)
		)
		(polygon
			(pts
				(arc
					(start 328.142092 -432.560476)
					(mid 328.16441 -432.614358)
					(end 328.218292 -432.636676)
				)
				(arc
					(start 329.158092 -432.636676)
					(mid 329.211974 -432.614358)
					(end 329.234292 -432.560476)
				)
				(arc
					(start 329.234292 -430.018952)
					(mid 329.211974 -429.96507)
					(end 329.158092 -429.942752)
				)
				(arc
					(start 328.218292 -429.942752)
					(mid 328.16441 -429.96507)
					(end 328.142092 -430.018952)
				)
				(arc
					(start 328.142092 -430.746408)
					(mid 328.144091 -430.763749)
					(end 328.149966 -430.78019)
				)
				(arc
					(start 328.383392 -431.25644)
					(mid 328.391175 -431.289968)
					(end 328.383392 -431.323496)
				)
				(arc
					(start 328.149966 -431.799746)
					(mid 328.144071 -431.816182)
					(end 328.142092 -431.833528)
				)
			)
		)
	)
	(zone
		(layers "In10.Cu" "In12.Cu")
		(hatch none 0.5)
		(connect_pads
			(clearance 0)
		)
		(min_thickness 0.25)
		(keepout
			(tracks not_allowed)
			(vias allowed)
			(pads allowed)
			(copperpour not_allowed)
			(footprints allowed)
		)
		(placement
			(enabled no)
			(sheetname "")
		)
		(fill yes
			(thermal_gap 0.5)
			(thermal_bridge_width 0.5)
			(island_removal_mode 0)
		)
		(polygon
			(pts
				(arc
					(start 322.142104 -431.560478)
					(mid 322.164422 -431.61436)
					(end 322.218304 -431.636678)
				)
				(arc
					(start 323.158104 -431.636678)
					(mid 323.211986 -431.61436)
					(end 323.234304 -431.560478)
				)
				(arc
					(start 323.234304 -429.018954)
					(mid 323.211986 -428.965072)
					(end 323.158104 -428.942754)
				)
				(arc
					(start 322.218304 -428.942754)
					(mid 322.164422 -428.965072)
					(end 322.142104 -429.018954)
				)
				(arc
					(start 322.142104 -429.74641)
					(mid 322.144103 -429.763751)
					(end 322.149978 -429.780192)
				)
				(arc
					(start 322.383404 -430.256442)
					(mid 322.391187 -430.28997)
					(end 322.383404 -430.323498)
				)
				(arc
					(start 322.149978 -430.799748)
					(mid 322.144083 -430.816184)
					(end 322.142104 -430.83353)
				)
			)
		)
	)
	(zone
		(layers "In10.Cu" "In12.Cu")
		(hatch none 0.5)
		(connect_pads
			(clearance 0)
		)
		(min_thickness 0.25)
		(keepout
			(tracks not_allowed)
			(vias allowed)
			(pads allowed)
			(copperpour not_allowed)
			(footprints allowed)
		)
		(placement
			(enabled no)
			(sheetname "")
		)
		(fill yes
			(thermal_gap 0.5)
			(thermal_bridge_width 0.5)
			(island_removal_mode 0)
		)
		(polygon
			(pts
				(arc
					(start 398.242028 -427.960536)
					(mid 398.264346 -428.014418)
					(end 398.318228 -428.036736)
				)
				(arc
					(start 399.258028 -428.036736)
					(mid 399.31191 -428.014418)
					(end 399.334228 -427.960536)
				)
				(arc
					(start 399.334228 -425.419012)
					(mid 399.31191 -425.36513)
					(end 399.258028 -425.342812)
				)
				(arc
					(start 398.318228 -425.342812)
					(mid 398.264346 -425.36513)
					(end 398.242028 -425.419012)
				)
				(arc
					(start 398.242028 -426.146468)
					(mid 398.244027 -426.163809)
					(end 398.249902 -426.18025)
				)
				(arc
					(start 398.483328 -426.6565)
					(mid 398.491111 -426.690028)
					(end 398.483328 -426.723556)
				)
				(arc
					(start 398.249902 -427.199806)
					(mid 398.244007 -427.216242)
					(end 398.242028 -427.233588)
				)
			)
		)
	)
	(zone
		(layers "In10.Cu" "In12.Cu")
		(hatch none 0.5)
		(connect_pads
			(clearance 0)
		)
		(min_thickness 0.25)
		(keepout
			(tracks not_allowed)
			(vias allowed)
			(pads allowed)
			(copperpour not_allowed)
			(footprints allowed)
		)
		(placement
			(enabled no)
			(sheetname "")
		)
		(fill yes
			(thermal_gap 0.5)
			(thermal_bridge_width 0.5)
			(island_removal_mode 0)
		)
		(polygon
			(pts
				(arc
					(start 89.142062 -432.560476)
					(mid 89.16438 -432.614358)
					(end 89.218262 -432.636676)
				)
				(arc
					(start 90.158062 -432.636676)
					(mid 90.211944 -432.614358)
					(end 90.234262 -432.560476)
				)
				(arc
					(start 90.234262 -430.018952)
					(mid 90.211944 -429.96507)
					(end 90.158062 -429.942752)
				)
				(arc
					(start 89.218262 -429.942752)
					(mid 89.16438 -429.96507)
					(end 89.142062 -430.018952)
				)
				(arc
					(start 89.142062 -430.746408)
					(mid 89.144061 -430.763749)
					(end 89.149936 -430.78019)
				)
				(arc
					(start 89.383362 -431.25644)
					(mid 89.391145 -431.289968)
					(end 89.383362 -431.323496)
				)
				(arc
					(start 89.149936 -431.799746)
					(mid 89.144041 -431.816182)
					(end 89.142062 -431.833528)
				)
			)
		)
	)
	(zone
		(layers "In10.Cu" "In12.Cu")
		(hatch none 0.5)
		(connect_pads
			(clearance 0)
		)
		(min_thickness 0.25)
		(keepout
			(tracks not_allowed)
			(vias allowed)
			(pads allowed)
			(copperpour not_allowed)
			(footprints allowed)
		)
		(placement
			(enabled no)
			(sheetname "")
		)
		(fill yes
			(thermal_gap 0.5)
			(thermal_bridge_width 0.5)
			(island_removal_mode 0)
		)
		(polygon
			(pts
				(arc
					(start 406.242012 -427.960536)
					(mid 406.26433 -428.014418)
					(end 406.318212 -428.036736)
				)
				(arc
					(start 407.258012 -428.036736)
					(mid 407.311894 -428.014418)
					(end 407.334212 -427.960536)
				)
				(arc
					(start 407.334212 -425.419012)
					(mid 407.311894 -425.36513)
					(end 407.258012 -425.342812)
				)
				(arc
					(start 406.318212 -425.342812)
					(mid 406.26433 -425.36513)
					(end 406.242012 -425.419012)
				)
				(arc
					(start 406.242012 -426.146468)
					(mid 406.244011 -426.163809)
					(end 406.249886 -426.18025)
				)
				(arc
					(start 406.483312 -426.6565)
					(mid 406.491095 -426.690028)
					(end 406.483312 -426.723556)
				)
				(arc
					(start 406.249886 -427.199806)
					(mid 406.243991 -427.216242)
					(end 406.242012 -427.233588)
				)
			)
		)
	)
	(zone
		(layers "In10.Cu" "In12.Cu")
		(hatch none 0.5)
		(connect_pads
			(clearance 0)
		)
		(min_thickness 0.25)
		(keepout
			(tracks not_allowed)
			(vias allowed)
			(pads allowed)
			(copperpour not_allowed)
			(footprints allowed)
		)
		(placement
			(enabled no)
			(sheetname "")
		)
		(fill yes
			(thermal_gap 0.5)
			(thermal_bridge_width 0.5)
			(island_removal_mode 0)
		)
		(polygon
			(pts
				(arc
					(start 133.24205 -427.960536)
					(mid 133.264368 -428.014418)
					(end 133.31825 -428.036736)
				)
				(arc
					(start 134.25805 -428.036736)
					(mid 134.311932 -428.014418)
					(end 134.33425 -427.960536)
				)
				(arc
					(start 134.33425 -425.419012)
					(mid 134.311932 -425.36513)
					(end 134.25805 -425.342812)
				)
				(arc
					(start 133.31825 -425.342812)
					(mid 133.264368 -425.36513)
					(end 133.24205 -425.419012)
				)
				(arc
					(start 133.24205 -426.146468)
					(mid 133.244049 -426.163809)
					(end 133.249924 -426.18025)
				)
				(arc
					(start 133.48335 -426.6565)
					(mid 133.491133 -426.690028)
					(end 133.48335 -426.723556)
				)
				(arc
					(start 133.249924 -427.199806)
					(mid 133.244029 -427.216242)
					(end 133.24205 -427.233588)
				)
			)
		)
	)
	(zone
		(layers "In10.Cu" "In12.Cu")
		(hatch none 0.5)
		(connect_pads
			(clearance 0)
		)
		(min_thickness 0.25)
		(keepout
			(tracks not_allowed)
			(vias allowed)
			(pads allowed)
			(copperpour not_allowed)
			(footprints allowed)
		)
		(placement
			(enabled no)
			(sheetname "")
		)
		(fill yes
			(thermal_gap 0.5)
			(thermal_bridge_width 0.5)
			(island_removal_mode 0)
		)
		(polygon
			(pts
				(arc
					(start 318.142112 -431.560478)
					(mid 318.16443 -431.61436)
					(end 318.218312 -431.636678)
				)
				(arc
					(start 319.158112 -431.636678)
					(mid 319.211994 -431.61436)
					(end 319.234312 -431.560478)
				)
				(arc
					(start 319.234312 -429.018954)
					(mid 319.211994 -428.965072)
					(end 319.158112 -428.942754)
				)
				(arc
					(start 318.218312 -428.942754)
					(mid 318.16443 -428.965072)
					(end 318.142112 -429.018954)
				)
				(arc
					(start 318.142112 -429.74641)
					(mid 318.144111 -429.763751)
					(end 318.149986 -429.780192)
				)
				(arc
					(start 318.383412 -430.256442)
					(mid 318.391195 -430.28997)
					(end 318.383412 -430.323498)
				)
				(arc
					(start 318.149986 -430.799748)
					(mid 318.144091 -430.816184)
					(end 318.142112 -430.83353)
				)
			)
		)
	)
	(zone
		(layers "In10.Cu" "In12.Cu")
		(hatch none 0.5)
		(connect_pads
			(clearance 0)
		)
		(min_thickness 0.25)
		(keepout
			(tracks not_allowed)
			(vias allowed)
			(pads allowed)
			(copperpour not_allowed)
			(footprints allowed)
		)
		(placement
			(enabled no)
			(sheetname "")
		)
		(fill yes
			(thermal_gap 0.5)
			(thermal_bridge_width 0.5)
			(island_removal_mode 0)
		)
		(polygon
			(pts
				(arc
					(start 337.142074 -432.560476)
					(mid 337.164392 -432.614358)
					(end 337.218274 -432.636676)
				)
				(arc
					(start 338.158074 -432.636676)
					(mid 338.211956 -432.614358)
					(end 338.234274 -432.560476)
				)
				(arc
					(start 338.234274 -430.018952)
					(mid 338.211956 -429.96507)
					(end 338.158074 -429.942752)
				)
				(arc
					(start 337.218274 -429.942752)
					(mid 337.164392 -429.96507)
					(end 337.142074 -430.018952)
				)
				(arc
					(start 337.142074 -430.746408)
					(mid 337.144073 -430.763749)
					(end 337.149948 -430.78019)
				)
				(arc
					(start 337.383374 -431.25644)
					(mid 337.391157 -431.289968)
					(end 337.383374 -431.323496)
				)
				(arc
					(start 337.149948 -431.799746)
					(mid 337.144053 -431.816182)
					(end 337.142074 -431.833528)
				)
			)
		)
	)
	(zone
		(layers "In10.Cu" "In12.Cu")
		(hatch none 0.5)
		(connect_pads
			(clearance 0)
		)
		(min_thickness 0.25)
		(keepout
			(tracks not_allowed)
			(vias allowed)
			(pads allowed)
			(copperpour not_allowed)
			(footprints allowed)
		)
		(placement
			(enabled no)
			(sheetname "")
		)
		(fill yes
			(thermal_gap 0.5)
			(thermal_bridge_width 0.5)
			(island_removal_mode 0)
		)
		(polygon
			(pts
				(arc
					(start 391.242042 -428.960534)
					(mid 391.26436 -429.014416)
					(end 391.318242 -429.036734)
				)
				(arc
					(start 392.258042 -429.036734)
					(mid 392.311924 -429.014416)
					(end 392.334242 -428.960534)
				)
				(arc
					(start 392.334242 -426.41901)
					(mid 392.311924 -426.365128)
					(end 392.258042 -426.34281)
				)
				(arc
					(start 391.318242 -426.34281)
					(mid 391.26436 -426.365128)
					(end 391.242042 -426.41901)
				)
				(arc
					(start 391.242042 -427.146466)
					(mid 391.244041 -427.163807)
					(end 391.249916 -427.180248)
				)
				(arc
					(start 391.483342 -427.656498)
					(mid 391.491125 -427.690026)
					(end 391.483342 -427.723554)
				)
				(arc
					(start 391.249916 -428.199804)
					(mid 391.244021 -428.21624)
					(end 391.242042 -428.233586)
				)
			)
		)
	)
	(zone
		(layers "In10.Cu" "In12.Cu")
		(hatch none 0.5)
		(connect_pads
			(clearance 0)
		)
		(min_thickness 0.25)
		(keepout
			(tracks not_allowed)
			(vias allowed)
			(pads allowed)
			(copperpour not_allowed)
			(footprints allowed)
		)
		(placement
			(enabled no)
			(sheetname "")
		)
		(fill yes
			(thermal_gap 0.5)
			(thermal_bridge_width 0.5)
			(island_removal_mode 0)
		)
		(polygon
			(pts
				(arc
					(start 154.242008 -427.960536)
					(mid 154.264326 -428.014418)
					(end 154.318208 -428.036736)
				)
				(arc
					(start 155.258008 -428.036736)
					(mid 155.31189 -428.014418)
					(end 155.334208 -427.960536)
				)
				(arc
					(start 155.334208 -425.419012)
					(mid 155.31189 -425.36513)
					(end 155.258008 -425.342812)
				)
				(arc
					(start 154.318208 -425.342812)
					(mid 154.264326 -425.36513)
					(end 154.242008 -425.419012)
				)
				(arc
					(start 154.242008 -426.146468)
					(mid 154.244007 -426.163809)
					(end 154.249882 -426.18025)
				)
				(arc
					(start 154.483308 -426.6565)
					(mid 154.491091 -426.690028)
					(end 154.483308 -426.723556)
				)
				(arc
					(start 154.249882 -427.199806)
					(mid 154.243987 -427.216242)
					(end 154.242008 -427.233588)
				)
			)
		)
	)
	(zone
		(layers "In10.Cu" "In12.Cu")
		(hatch none 0.5)
		(connect_pads
			(clearance 0)
		)
		(min_thickness 0.25)
		(keepout
			(tracks not_allowed)
			(vias allowed)
			(pads allowed)
			(copperpour not_allowed)
			(footprints allowed)
		)
		(placement
			(enabled no)
			(sheetname "")
		)
		(fill yes
			(thermal_gap 0.5)
			(thermal_bridge_width 0.5)
			(island_removal_mode 0)
		)
		(polygon
			(pts
				(arc
					(start 324.1421 -432.560476)
					(mid 324.164418 -432.614358)
					(end 324.2183 -432.636676)
				)
				(arc
					(start 325.1581 -432.636676)
					(mid 325.211982 -432.614358)
					(end 325.2343 -432.560476)
				)
				(arc
					(start 325.2343 -430.018952)
					(mid 325.211982 -429.96507)
					(end 325.1581 -429.942752)
				)
				(arc
					(start 324.2183 -429.942752)
					(mid 324.164418 -429.96507)
					(end 324.1421 -430.018952)
				)
				(arc
					(start 324.1421 -430.746408)
					(mid 324.144099 -430.763749)
					(end 324.149974 -430.78019)
				)
				(arc
					(start 324.3834 -431.25644)
					(mid 324.391183 -431.289968)
					(end 324.3834 -431.323496)
				)
				(arc
					(start 324.149974 -431.799746)
					(mid 324.144079 -431.816182)
					(end 324.1421 -431.833528)
				)
			)
		)
	)
	(zone
		(layers "In10.Cu" "In12.Cu")
		(hatch none 0.5)
		(connect_pads
			(clearance 0)
		)
		(min_thickness 0.25)
		(keepout
			(tracks not_allowed)
			(vias allowed)
			(pads allowed)
			(copperpour not_allowed)
			(footprints allowed)
		)
		(placement
			(enabled no)
			(sheetname "")
		)
		(fill yes
			(thermal_gap 0.5)
			(thermal_bridge_width 0.5)
			(island_removal_mode 0)
		)
		(polygon
			(pts
				(arc
					(start 131.242054 -428.960534)
					(mid 131.264372 -429.014416)
					(end 131.318254 -429.036734)
				)
				(arc
					(start 132.258054 -429.036734)
					(mid 132.311936 -429.014416)
					(end 132.334254 -428.960534)
				)
				(arc
					(start 132.334254 -426.41901)
					(mid 132.311936 -426.365128)
					(end 132.258054 -426.34281)
				)
				(arc
					(start 131.318254 -426.34281)
					(mid 131.264372 -426.365128)
					(end 131.242054 -426.41901)
				)
				(arc
					(start 131.242054 -427.146466)
					(mid 131.244053 -427.163807)
					(end 131.249928 -427.180248)
				)
				(arc
					(start 131.483354 -427.656498)
					(mid 131.491137 -427.690026)
					(end 131.483354 -427.723554)
				)
				(arc
					(start 131.249928 -428.199804)
					(mid 131.244033 -428.21624)
					(end 131.242054 -428.233586)
				)
			)
		)
	)
	(zone
		(layers "In10.Cu" "In12.Cu")
		(hatch none 0.5)
		(connect_pads
			(clearance 0)
		)
		(min_thickness 0.25)
		(keepout
			(tracks not_allowed)
			(vias allowed)
			(pads allowed)
			(copperpour not_allowed)
			(footprints allowed)
		)
		(placement
			(enabled no)
			(sheetname "")
		)
		(fill yes
			(thermal_gap 0.5)
			(thermal_bridge_width 0.5)
			(island_removal_mode 0)
		)
		(polygon
			(pts
				(arc
					(start 320.142108 -432.560476)
					(mid 320.164426 -432.614358)
					(end 320.218308 -432.636676)
				)
				(arc
					(start 321.158108 -432.636676)
					(mid 321.21199 -432.614358)
					(end 321.234308 -432.560476)
				)
				(arc
					(start 321.234308 -430.018952)
					(mid 321.21199 -429.96507)
					(end 321.158108 -429.942752)
				)
				(arc
					(start 320.218308 -429.942752)
					(mid 320.164426 -429.96507)
					(end 320.142108 -430.018952)
				)
				(arc
					(start 320.142108 -430.746408)
					(mid 320.144107 -430.763749)
					(end 320.149982 -430.78019)
				)
				(arc
					(start 320.383408 -431.25644)
					(mid 320.391191 -431.289968)
					(end 320.383408 -431.323496)
				)
				(arc
					(start 320.149982 -431.799746)
					(mid 320.144087 -431.816182)
					(end 320.142108 -431.833528)
				)
			)
		)
	)
	(zone
		(layers "In10.Cu" "In12.Cu")
		(hatch none 0.5)
		(connect_pads
			(clearance 0)
		)
		(min_thickness 0.25)
		(keepout
			(tracks not_allowed)
			(vias allowed)
			(pads allowed)
			(copperpour not_allowed)
			(footprints allowed)
		)
		(placement
			(enabled no)
			(sheetname "")
		)
		(fill yes
			(thermal_gap 0.5)
			(thermal_bridge_width 0.5)
			(island_removal_mode 0)
		)
		(polygon
			(pts
				(arc
					(start 75.14209 -431.560478)
					(mid 75.164408 -431.61436)
					(end 75.21829 -431.636678)
				)
				(arc
					(start 76.15809 -431.636678)
					(mid 76.211972 -431.61436)
					(end 76.23429 -431.560478)
				)
				(arc
					(start 76.23429 -429.018954)
					(mid 76.211972 -428.965072)
					(end 76.15809 -428.942754)
				)
				(arc
					(start 75.21829 -428.942754)
					(mid 75.164408 -428.965072)
					(end 75.14209 -429.018954)
				)
				(arc
					(start 75.14209 -429.74641)
					(mid 75.144089 -429.763751)
					(end 75.149964 -429.780192)
				)
				(arc
					(start 75.38339 -430.256442)
					(mid 75.391173 -430.28997)
					(end 75.38339 -430.323498)
				)
				(arc
					(start 75.149964 -430.799748)
					(mid 75.144069 -430.816184)
					(end 75.14209 -430.83353)
				)
			)
		)
	)
	(zone
		(layers "In10.Cu" "In12.Cu")
		(hatch none 0.5)
		(connect_pads
			(clearance 0)
		)
		(min_thickness 0.25)
		(keepout
			(tracks not_allowed)
			(vias allowed)
			(pads allowed)
			(copperpour not_allowed)
			(footprints allowed)
		)
		(placement
			(enabled no)
			(sheetname "")
		)
		(fill yes
			(thermal_gap 0.5)
			(thermal_bridge_width 0.5)
			(island_removal_mode 0)
		)
		(polygon
			(pts
				(arc
					(start 156.242004 -428.960534)
					(mid 156.264322 -429.014416)
					(end 156.318204 -429.036734)
				)
				(arc
					(start 157.258004 -429.036734)
					(mid 157.311886 -429.014416)
					(end 157.334204 -428.960534)
				)
				(arc
					(start 157.334204 -426.41901)
					(mid 157.311886 -426.365128)
					(end 157.258004 -426.34281)
				)
				(arc
					(start 156.318204 -426.34281)
					(mid 156.264322 -426.365128)
					(end 156.242004 -426.41901)
				)
				(arc
					(start 156.242004 -427.146466)
					(mid 156.244003 -427.163807)
					(end 156.249878 -427.180248)
				)
				(arc
					(start 156.483304 -427.656498)
					(mid 156.491087 -427.690026)
					(end 156.483304 -427.723554)
				)
				(arc
					(start 156.249878 -428.199804)
					(mid 156.243983 -428.21624)
					(end 156.242004 -428.233586)
				)
			)
		)
	)
	(zone
		(layers "In10.Cu" "In12.Cu")
		(hatch none 0.5)
		(connect_pads
			(clearance 0)
		)
		(min_thickness 0.25)
		(keepout
			(tracks not_allowed)
			(vias allowed)
			(pads allowed)
			(copperpour not_allowed)
			(footprints allowed)
		)
		(placement
			(enabled no)
			(sheetname "")
		)
		(fill yes
			(thermal_gap 0.5)
			(thermal_bridge_width 0.5)
			(island_removal_mode 0)
		)
		(polygon
			(pts
				(arc
					(start 135.242046 -428.960534)
					(mid 135.264364 -429.014416)
					(end 135.318246 -429.036734)
				)
				(arc
					(start 136.258046 -429.036734)
					(mid 136.311928 -429.014416)
					(end 136.334246 -428.960534)
				)
				(arc
					(start 136.334246 -426.41901)
					(mid 136.311928 -426.365128)
					(end 136.258046 -426.34281)
				)
				(arc
					(start 135.318246 -426.34281)
					(mid 135.264364 -426.365128)
					(end 135.242046 -426.41901)
				)
				(arc
					(start 135.242046 -427.146466)
					(mid 135.244045 -427.163807)
					(end 135.24992 -427.180248)
				)
				(arc
					(start 135.483346 -427.656498)
					(mid 135.491129 -427.690026)
					(end 135.483346 -427.723554)
				)
				(arc
					(start 135.24992 -428.199804)
					(mid 135.244025 -428.21624)
					(end 135.242046 -428.233586)
				)
			)
		)
	)
	(zone
		(layers "In10.Cu" "In12.Cu")
		(hatch none 0.5)
		(connect_pads
			(clearance 0)
		)
		(min_thickness 0.25)
		(keepout
			(tracks not_allowed)
			(vias allowed)
			(pads allowed)
			(copperpour not_allowed)
			(footprints allowed)
		)
		(placement
			(enabled no)
			(sheetname "")
		)
		(fill yes
			(thermal_gap 0.5)
			(thermal_bridge_width 0.5)
			(island_removal_mode 0)
		)
		(polygon
			(pts
				(arc
					(start 127.242062 -428.960534)
					(mid 127.26438 -429.014416)
					(end 127.318262 -429.036734)
				)
				(arc
					(start 128.258062 -429.036734)
					(mid 128.311944 -429.014416)
					(end 128.334262 -428.960534)
				)
				(arc
					(start 128.334262 -426.41901)
					(mid 128.311944 -426.365128)
					(end 128.258062 -426.34281)
				)
				(arc
					(start 127.318262 -426.34281)
					(mid 127.26438 -426.365128)
					(end 127.242062 -426.41901)
				)
				(arc
					(start 127.242062 -427.146466)
					(mid 127.244061 -427.163807)
					(end 127.249936 -427.180248)
				)
				(arc
					(start 127.483362 -427.656498)
					(mid 127.491145 -427.690026)
					(end 127.483362 -427.723554)
				)
				(arc
					(start 127.249936 -428.199804)
					(mid 127.244041 -428.21624)
					(end 127.242062 -428.233586)
				)
			)
		)
	)
	(zone
		(layers "In10.Cu" "In12.Cu")
		(hatch none 0.5)
		(connect_pads
			(clearance 0)
		)
		(min_thickness 0.25)
		(keepout
			(tracks not_allowed)
			(vias allowed)
			(pads allowed)
			(copperpour not_allowed)
			(footprints allowed)
		)
		(placement
			(enabled no)
			(sheetname "")
		)
		(fill yes
			(thermal_gap 0.5)
			(thermal_bridge_width 0.5)
			(island_removal_mode 0)
		)
		(polygon
			(pts
				(arc
					(start 83.142074 -431.560478)
					(mid 83.164392 -431.61436)
					(end 83.218274 -431.636678)
				)
				(arc
					(start 84.158074 -431.636678)
					(mid 84.211956 -431.61436)
					(end 84.234274 -431.560478)
				)
				(arc
					(start 84.234274 -429.018954)
					(mid 84.211956 -428.965072)
					(end 84.158074 -428.942754)
				)
				(arc
					(start 83.218274 -428.942754)
					(mid 83.164392 -428.965072)
					(end 83.142074 -429.018954)
				)
				(arc
					(start 83.142074 -429.74641)
					(mid 83.144073 -429.763751)
					(end 83.149948 -429.780192)
				)
				(arc
					(start 83.383374 -430.256442)
					(mid 83.391157 -430.28997)
					(end 83.383374 -430.323498)
				)
				(arc
					(start 83.149948 -430.799748)
					(mid 83.144053 -430.816184)
					(end 83.142074 -430.83353)
				)
			)
		)
	)
	(zone
		(layers "In10.Cu" "In12.Cu")
		(hatch none 0.5)
		(connect_pads
			(clearance 0)
		)
		(min_thickness 0.25)
		(keepout
			(tracks not_allowed)
			(vias allowed)
			(pads allowed)
			(copperpour not_allowed)
			(footprints allowed)
		)
		(placement
			(enabled no)
			(sheetname "")
		)
		(fill yes
			(thermal_gap 0.5)
			(thermal_bridge_width 0.5)
			(island_removal_mode 0)
		)
		(polygon
			(pts
				(arc
					(start 339.14207 -431.560478)
					(mid 339.164388 -431.61436)
					(end 339.21827 -431.636678)
				)
				(arc
					(start 340.15807 -431.636678)
					(mid 340.211952 -431.61436)
					(end 340.23427 -431.560478)
				)
				(arc
					(start 340.23427 -429.018954)
					(mid 340.211952 -428.965072)
					(end 340.15807 -428.942754)
				)
				(arc
					(start 339.21827 -428.942754)
					(mid 339.164388 -428.965072)
					(end 339.14207 -429.018954)
				)
				(arc
					(start 339.14207 -429.74641)
					(mid 339.144069 -429.763751)
					(end 339.149944 -429.780192)
				)
				(arc
					(start 339.38337 -430.256442)
					(mid 339.391153 -430.28997)
					(end 339.38337 -430.323498)
				)
				(arc
					(start 339.149944 -430.799748)
					(mid 339.144049 -430.816184)
					(end 339.14207 -430.83353)
				)
			)
		)
	)
	(zone
		(layers "In10.Cu" "In12.Cu")
		(hatch none 0.5)
		(connect_pads
			(clearance 0)
		)
		(min_thickness 0.25)
		(keepout
			(tracks not_allowed)
			(vias allowed)
			(pads allowed)
			(copperpour not_allowed)
			(footprints allowed)
		)
		(placement
			(enabled no)
			(sheetname "")
		)
		(fill yes
			(thermal_gap 0.5)
			(thermal_bridge_width 0.5)
			(island_removal_mode 0)
		)
		(polygon
			(pts
				(arc
					(start 152.242012 -428.960534)
					(mid 152.26433 -429.014416)
					(end 152.318212 -429.036734)
				)
				(arc
					(start 153.258012 -429.036734)
					(mid 153.311894 -429.014416)
					(end 153.334212 -428.960534)
				)
				(arc
					(start 153.334212 -426.41901)
					(mid 153.311894 -426.365128)
					(end 153.258012 -426.34281)
				)
				(arc
					(start 152.318212 -426.34281)
					(mid 152.26433 -426.365128)
					(end 152.242012 -426.41901)
				)
				(arc
					(start 152.242012 -427.146466)
					(mid 152.244011 -427.163807)
					(end 152.249886 -427.180248)
				)
				(arc
					(start 152.483312 -427.656498)
					(mid 152.491095 -427.690026)
					(end 152.483312 -427.723554)
				)
				(arc
					(start 152.249886 -428.199804)
					(mid 152.243991 -428.21624)
					(end 152.242012 -428.233586)
				)
			)
		)
	)
	(zone
		(layers "In10.Cu" "In12.Cu")
		(hatch none 0.5)
		(connect_pads
			(clearance 0)
		)
		(min_thickness 0.25)
		(keepout
			(tracks not_allowed)
			(vias allowed)
			(pads allowed)
			(copperpour not_allowed)
			(footprints allowed)
		)
		(placement
			(enabled no)
			(sheetname "")
		)
		(fill yes
			(thermal_gap 0.5)
			(thermal_bridge_width 0.5)
			(island_removal_mode 0)
		)
		(polygon
			(pts
				(arc
					(start 58.142124 -431.560478)
					(mid 58.164442 -431.61436)
					(end 58.218324 -431.636678)
				)
				(arc
					(start 59.158124 -431.636678)
					(mid 59.212006 -431.61436)
					(end 59.234324 -431.560478)
				)
				(arc
					(start 59.234324 -429.018954)
					(mid 59.212006 -428.965072)
					(end 59.158124 -428.942754)
				)
				(arc
					(start 58.218324 -428.942754)
					(mid 58.164442 -428.965072)
					(end 58.142124 -429.018954)
				)
				(arc
					(start 58.142124 -429.74641)
					(mid 58.144123 -429.763751)
					(end 58.149998 -429.780192)
				)
				(arc
					(start 58.383424 -430.256442)
					(mid 58.391207 -430.28997)
					(end 58.383424 -430.323498)
				)
				(arc
					(start 58.149998 -430.799748)
					(mid 58.144103 -430.816184)
					(end 58.142124 -430.83353)
				)
			)
		)
	)
	(zone
		(layers "In10.Cu" "In12.Cu")
		(hatch none 0.5)
		(connect_pads
			(clearance 0)
		)
		(min_thickness 0.25)
		(keepout
			(tracks not_allowed)
			(vias allowed)
			(pads allowed)
			(copperpour not_allowed)
			(footprints allowed)
		)
		(placement
			(enabled no)
			(sheetname "")
		)
		(fill yes
			(thermal_gap 0.5)
			(thermal_bridge_width 0.5)
			(island_removal_mode 0)
		)
		(polygon
			(pts
				(arc
					(start 81.142078 -432.560476)
					(mid 81.164396 -432.614358)
					(end 81.218278 -432.636676)
				)
				(arc
					(start 82.158078 -432.636676)
					(mid 82.21196 -432.614358)
					(end 82.234278 -432.560476)
				)
				(arc
					(start 82.234278 -430.018952)
					(mid 82.21196 -429.96507)
					(end 82.158078 -429.942752)
				)
				(arc
					(start 81.218278 -429.942752)
					(mid 81.164396 -429.96507)
					(end 81.142078 -430.018952)
				)
				(arc
					(start 81.142078 -430.746408)
					(mid 81.144077 -430.763749)
					(end 81.149952 -430.78019)
				)
				(arc
					(start 81.383378 -431.25644)
					(mid 81.391161 -431.289968)
					(end 81.383378 -431.323496)
				)
				(arc
					(start 81.149952 -431.799746)
					(mid 81.144057 -431.816182)
					(end 81.142078 -431.833528)
				)
			)
		)
	)
	(zone
		(layers "In10.Cu" "In12.Cu")
		(hatch none 0.5)
		(connect_pads
			(clearance 0)
		)
		(min_thickness 0.25)
		(keepout
			(tracks not_allowed)
			(vias allowed)
			(pads allowed)
			(copperpour not_allowed)
			(footprints allowed)
		)
		(placement
			(enabled no)
			(sheetname "")
		)
		(fill yes
			(thermal_gap 0.5)
			(thermal_bridge_width 0.5)
			(island_removal_mode 0)
		)
		(polygon
			(pts
				(arc
					(start 404.242016 -428.960534)
					(mid 404.264334 -429.014416)
					(end 404.318216 -429.036734)
				)
				(arc
					(start 405.258016 -429.036734)
					(mid 405.311898 -429.014416)
					(end 405.334216 -428.960534)
				)
				(arc
					(start 405.334216 -426.41901)
					(mid 405.311898 -426.365128)
					(end 405.258016 -426.34281)
				)
				(arc
					(start 404.318216 -426.34281)
					(mid 404.264334 -426.365128)
					(end 404.242016 -426.41901)
				)
				(arc
					(start 404.242016 -427.146466)
					(mid 404.244015 -427.163807)
					(end 404.24989 -427.180248)
				)
				(arc
					(start 404.483316 -427.656498)
					(mid 404.491099 -427.690026)
					(end 404.483316 -427.723554)
				)
				(arc
					(start 404.24989 -428.199804)
					(mid 404.243995 -428.21624)
					(end 404.242016 -428.233586)
				)
			)
		)
	)
	(zone
		(layers "In10.Cu" "In12.Cu")
		(hatch none 0.5)
		(connect_pads
			(clearance 0)
		)
		(min_thickness 0.25)
		(keepout
			(tracks not_allowed)
			(vias allowed)
			(pads allowed)
			(copperpour not_allowed)
			(footprints allowed)
		)
		(placement
			(enabled no)
			(sheetname "")
		)
		(fill yes
			(thermal_gap 0.5)
			(thermal_bridge_width 0.5)
			(island_removal_mode 0)
		)
		(polygon
			(pts
				(arc
					(start 335.142078 -431.560478)
					(mid 335.164396 -431.61436)
					(end 335.218278 -431.636678)
				)
				(arc
					(start 336.158078 -431.636678)
					(mid 336.21196 -431.61436)
					(end 336.234278 -431.560478)
				)
				(arc
					(start 336.234278 -429.018954)
					(mid 336.21196 -428.965072)
					(end 336.158078 -428.942754)
				)
				(arc
					(start 335.218278 -428.942754)
					(mid 335.164396 -428.965072)
					(end 335.142078 -429.018954)
				)
				(arc
					(start 335.142078 -429.74641)
					(mid 335.144077 -429.763751)
					(end 335.149952 -429.780192)
				)
				(arc
					(start 335.383378 -430.256442)
					(mid 335.391161 -430.28997)
					(end 335.383378 -430.323498)
				)
				(arc
					(start 335.149952 -430.799748)
					(mid 335.144057 -430.816184)
					(end 335.142078 -430.83353)
				)
			)
		)
	)
	(zone
		(layers "In10.Cu" "In12.Cu")
		(hatch none 0.5)
		(connect_pads
			(clearance 0)
		)
		(min_thickness 0.25)
		(keepout
			(tracks not_allowed)
			(vias allowed)
			(pads allowed)
			(copperpour not_allowed)
			(footprints allowed)
		)
		(placement
			(enabled no)
			(sheetname "")
		)
		(fill yes
			(thermal_gap 0.5)
			(thermal_bridge_width 0.5)
			(island_removal_mode 0)
		)
		(polygon
			(pts
				(arc
					(start 68.142104 -432.560476)
					(mid 68.164422 -432.614358)
					(end 68.218304 -432.636676)
				)
				(arc
					(start 69.158104 -432.636676)
					(mid 69.211986 -432.614358)
					(end 69.234304 -432.560476)
				)
				(arc
					(start 69.234304 -430.018952)
					(mid 69.211986 -429.96507)
					(end 69.158104 -429.942752)
				)
				(arc
					(start 68.218304 -429.942752)
					(mid 68.164422 -429.96507)
					(end 68.142104 -430.018952)
				)
				(arc
					(start 68.142104 -430.746408)
					(mid 68.144103 -430.763749)
					(end 68.149978 -430.78019)
				)
				(arc
					(start 68.383404 -431.25644)
					(mid 68.391187 -431.289968)
					(end 68.383404 -431.323496)
				)
				(arc
					(start 68.149978 -431.799746)
					(mid 68.144083 -431.816182)
					(end 68.142104 -431.833528)
				)
			)
		)
	)
	(zone
		(layers "In10.Cu" "In12.Cu")
		(hatch none 0.5)
		(connect_pads
			(clearance 0)
		)
		(min_thickness 0.25)
		(keepout
			(tracks not_allowed)
			(vias allowed)
			(pads allowed)
			(copperpour not_allowed)
			(footprints allowed)
		)
		(placement
			(enabled no)
			(sheetname "")
		)
		(fill yes
			(thermal_gap 0.5)
			(thermal_bridge_width 0.5)
			(island_removal_mode 0)
		)
		(polygon
			(pts
				(arc
					(start 402.24202 -427.960536)
					(mid 402.264338 -428.014418)
					(end 402.31822 -428.036736)
				)
				(arc
					(start 403.25802 -428.036736)
					(mid 403.311902 -428.014418)
					(end 403.33422 -427.960536)
				)
				(arc
					(start 403.33422 -425.419012)
					(mid 403.311902 -425.36513)
					(end 403.25802 -425.342812)
				)
				(arc
					(start 402.31822 -425.342812)
					(mid 402.264338 -425.36513)
					(end 402.24202 -425.419012)
				)
				(arc
					(start 402.24202 -426.146468)
					(mid 402.244019 -426.163809)
					(end 402.249894 -426.18025)
				)
				(arc
					(start 402.48332 -426.6565)
					(mid 402.491103 -426.690028)
					(end 402.48332 -426.723556)
				)
				(arc
					(start 402.249894 -427.199806)
					(mid 402.243999 -427.216242)
					(end 402.24202 -427.233588)
				)
			)
		)
	)
	(zone
		(layers "In10.Cu" "In12.Cu")
		(hatch none 0.5)
		(connect_pads
			(clearance 0)
		)
		(min_thickness 0.25)
		(keepout
			(tracks not_allowed)
			(vias allowed)
			(pads allowed)
			(copperpour not_allowed)
			(footprints allowed)
		)
		(placement
			(enabled no)
			(sheetname "")
		)
		(fill yes
			(thermal_gap 0.5)
			(thermal_bridge_width 0.5)
			(island_removal_mode 0)
		)
		(polygon
			(pts
				(arc
					(start 72.142096 -432.560476)
					(mid 72.164414 -432.614358)
					(end 72.218296 -432.636676)
				)
				(arc
					(start 73.158096 -432.636676)
					(mid 73.211978 -432.614358)
					(end 73.234296 -432.560476)
				)
				(arc
					(start 73.234296 -430.018952)
					(mid 73.211978 -429.96507)
					(end 73.158096 -429.942752)
				)
				(arc
					(start 72.218296 -429.942752)
					(mid 72.164414 -429.96507)
					(end 72.142096 -430.018952)
				)
				(arc
					(start 72.142096 -430.746408)
					(mid 72.144095 -430.763749)
					(end 72.14997 -430.78019)
				)
				(arc
					(start 72.383396 -431.25644)
					(mid 72.391179 -431.289968)
					(end 72.383396 -431.323496)
				)
				(arc
					(start 72.14997 -431.799746)
					(mid 72.144075 -431.816182)
					(end 72.142096 -431.833528)
				)
			)
		)
	)
	(zone
		(layers "In10.Cu" "In12.Cu")
		(hatch none 0.5)
		(connect_pads
			(clearance 0)
		)
		(min_thickness 0.25)
		(keepout
			(tracks not_allowed)
			(vias allowed)
			(pads allowed)
			(copperpour not_allowed)
			(footprints allowed)
		)
		(placement
			(enabled no)
			(sheetname "")
		)
		(fill yes
			(thermal_gap 0.5)
			(thermal_bridge_width 0.5)
			(island_removal_mode 0)
		)
		(polygon
			(pts
				(arc
					(start 87.142066 -431.560478)
					(mid 87.164384 -431.61436)
					(end 87.218266 -431.636678)
				)
				(arc
					(start 88.158066 -431.636678)
					(mid 88.211948 -431.61436)
					(end 88.234266 -431.560478)
				)
				(arc
					(start 88.234266 -429.018954)
					(mid 88.211948 -428.965072)
					(end 88.158066 -428.942754)
				)
				(arc
					(start 87.218266 -428.942754)
					(mid 87.164384 -428.965072)
					(end 87.142066 -429.018954)
				)
				(arc
					(start 87.142066 -429.74641)
					(mid 87.144065 -429.763751)
					(end 87.14994 -429.780192)
				)
				(arc
					(start 87.383366 -430.256442)
					(mid 87.391149 -430.28997)
					(end 87.383366 -430.323498)
				)
				(arc
					(start 87.14994 -430.799748)
					(mid 87.144045 -430.816184)
					(end 87.142066 -430.83353)
				)
			)
		)
	)
	(zone
		(layers "In10.Cu" "In12.Cu")
		(hatch none 0.5)
		(connect_pads
			(clearance 0)
		)
		(min_thickness 0.25)
		(keepout
			(tracks not_allowed)
			(vias allowed)
			(pads allowed)
			(copperpour not_allowed)
			(footprints allowed)
		)
		(placement
			(enabled no)
			(sheetname "")
		)
		(fill yes
			(thermal_gap 0.5)
			(thermal_bridge_width 0.5)
			(island_removal_mode 0)
		)
		(polygon
			(pts
				(arc
					(start 66.142108 -431.560478)
					(mid 66.164426 -431.61436)
					(end 66.218308 -431.636678)
				)
				(arc
					(start 67.158108 -431.636678)
					(mid 67.21199 -431.61436)
					(end 67.234308 -431.560478)
				)
				(arc
					(start 67.234308 -429.018954)
					(mid 67.21199 -428.965072)
					(end 67.158108 -428.942754)
				)
				(arc
					(start 66.218308 -428.942754)
					(mid 66.164426 -428.965072)
					(end 66.142108 -429.018954)
				)
				(arc
					(start 66.142108 -429.74641)
					(mid 66.144107 -429.763751)
					(end 66.149982 -429.780192)
				)
				(arc
					(start 66.383408 -430.256442)
					(mid 66.391191 -430.28997)
					(end 66.383408 -430.323498)
				)
				(arc
					(start 66.149982 -430.799748)
					(mid 66.144087 -430.816184)
					(end 66.142108 -430.83353)
				)
			)
		)
	)
	(zone
		(layers "In10.Cu" "In12.Cu")
		(hatch none 0.5)
		(connect_pads
			(clearance 0)
		)
		(min_thickness 0.25)
		(keepout
			(tracks not_allowed)
			(vias allowed)
			(pads allowed)
			(copperpour not_allowed)
			(footprints allowed)
		)
		(placement
			(enabled no)
			(sheetname "")
		)
		(fill yes
			(thermal_gap 0.5)
			(thermal_bridge_width 0.5)
			(island_removal_mode 0)
		)
		(polygon
			(pts
				(arc
					(start 148.24202 -428.960534)
					(mid 148.264338 -429.014416)
					(end 148.31822 -429.036734)
				)
				(arc
					(start 149.25802 -429.036734)
					(mid 149.311902 -429.014416)
					(end 149.33422 -428.960534)
				)
				(arc
					(start 149.33422 -426.41901)
					(mid 149.311902 -426.365128)
					(end 149.25802 -426.34281)
				)
				(arc
					(start 148.31822 -426.34281)
					(mid 148.264338 -426.365128)
					(end 148.24202 -426.41901)
				)
				(arc
					(start 148.24202 -427.146466)
					(mid 148.244019 -427.163807)
					(end 148.249894 -427.180248)
				)
				(arc
					(start 148.48332 -427.656498)
					(mid 148.491103 -427.690026)
					(end 148.48332 -427.723554)
				)
				(arc
					(start 148.249894 -428.199804)
					(mid 148.243999 -428.21624)
					(end 148.24202 -428.233586)
				)
			)
		)
	)
	(zone
		(layers "In10.Cu" "In12.Cu")
		(hatch none 0.5)
		(connect_pads
			(clearance 0)
		)
		(min_thickness 0.25)
		(keepout
			(tracks not_allowed)
			(vias allowed)
			(pads allowed)
			(copperpour not_allowed)
			(footprints allowed)
		)
		(placement
			(enabled no)
			(sheetname "")
		)
		(fill yes
			(thermal_gap 0.5)
			(thermal_bridge_width 0.5)
			(island_removal_mode 0)
		)
		(polygon
			(pts
				(arc
					(start 77.142086 -432.560476)
					(mid 77.164404 -432.614358)
					(end 77.218286 -432.636676)
				)
				(arc
					(start 78.158086 -432.636676)
					(mid 78.211968 -432.614358)
					(end 78.234286 -432.560476)
				)
				(arc
					(start 78.234286 -430.018952)
					(mid 78.211968 -429.96507)
					(end 78.158086 -429.942752)
				)
				(arc
					(start 77.218286 -429.942752)
					(mid 77.164404 -429.96507)
					(end 77.142086 -430.018952)
				)
				(arc
					(start 77.142086 -430.746408)
					(mid 77.144085 -430.763749)
					(end 77.14996 -430.78019)
				)
				(arc
					(start 77.383386 -431.25644)
					(mid 77.391169 -431.289968)
					(end 77.383386 -431.323496)
				)
				(arc
					(start 77.14996 -431.799746)
					(mid 77.144065 -431.816182)
					(end 77.142086 -431.833528)
				)
			)
		)
	)
	(zone
		(layer "In11.Cu")
		(hatch none 0.5)
		(connect_pads
			(clearance 0)
		)
		(min_thickness 0.25)
		(keepout
			(tracks allowed)
			(vias allowed)
			(pads allowed)
			(copperpour allowed)
			(footprints allowed)
		)
		(placement
			(enabled no)
			(sheetname "")
		)
		(fill
			(thermal_gap 0.5)
			(thermal_bridge_width 0.5)
			(island_removal_mode 0)
		)
		(polygon
			(pts
				(xy 176.621186 -223.718374) (xy 176.621186 -223.442784) (xy 177.179986 -223.442784) (xy 177.179986 -223.718374)
			)
		)
	)
	(zone
		(layer "In11.Cu")
		(hatch none 0.5)
		(connect_pads
			(clearance 0)
		)
		(min_thickness 0.25)
		(keepout
			(tracks allowed)
			(vias allowed)
			(pads allowed)
			(copperpour allowed)
			(footprints allowed)
		)
		(placement
			(enabled no)
			(sheetname "")
		)
		(fill
			(thermal_gap 0.5)
			(thermal_bridge_width 0.5)
			(island_removal_mode 0)
		)
		(polygon
			(pts
				(xy 294.586152 -235.846874) (xy 294.586152 -235.297218) (xy 295.216072 -235.297218) (xy 295.216072 -235.846874)
			)
		)
	)
	(zone
		(layer "In11.Cu")
		(hatch none 0.5)
		(connect_pads
			(clearance 0)
		)
		(min_thickness 0.25)
		(keepout
			(tracks allowed)
			(vias allowed)
			(pads allowed)
			(copperpour allowed)
			(footprints allowed)
		)
		(placement
			(enabled no)
			(sheetname "")
		)
		(fill
			(thermal_gap 0.5)
			(thermal_bridge_width 0.5)
			(island_removal_mode 0)
		)
		(polygon
			(pts
				(xy 172.521118 -230.518462) (xy 172.521118 -230.242872) (xy 173.079918 -230.242872) (xy 173.079918 -230.518462)
			)
		)
	)
	(zone
		(layer "In11.Cu")
		(hatch none 0.5)
		(connect_pads
			(clearance 0)
		)
		(min_thickness 0.25)
		(keepout
			(tracks allowed)
			(vias allowed)
			(pads allowed)
			(copperpour allowed)
			(footprints allowed)
		)
		(placement
			(enabled no)
			(sheetname "")
		)
		(fill
			(thermal_gap 0.5)
			(thermal_bridge_width 0.5)
			(island_removal_mode 0)
		)
		(polygon
			(pts
				(xy 283.24302 -267.795248) (xy 283.24302 -266.375388) (xy 284.59176 -266.375388) (xy 284.59176 -267.795248)
			)
		)
	)
	(zone
		(layer "In11.Cu")
		(hatch none 0.5)
		(connect_pads
			(clearance 0)
		)
		(min_thickness 0.25)
		(keepout
			(tracks allowed)
			(vias allowed)
			(pads allowed)
			(copperpour allowed)
			(footprints allowed)
		)
		(placement
			(enabled no)
			(sheetname "")
		)
		(fill
			(thermal_gap 0.5)
			(thermal_bridge_width 0.5)
			(island_removal_mode 0)
		)
		(polygon
			(pts
				(xy 424.561254 -204.168502) (xy 424.561254 -203.892912) (xy 425.120054 -203.892912) (xy 425.120054 -204.168502)
			)
		)
	)
	(zone
		(layer "In11.Cu")
		(hatch none 0.5)
		(connect_pads
			(clearance 0)
		)
		(min_thickness 0.25)
		(keepout
			(tracks allowed)
			(vias allowed)
			(pads allowed)
			(copperpour allowed)
			(footprints allowed)
		)
		(placement
			(enabled no)
			(sheetname "")
		)
		(fill
			(thermal_gap 0.5)
			(thermal_bridge_width 0.5)
			(island_removal_mode 0)
		)
		(polygon
			(pts
				(xy 451.186042 -301.814738) (xy 451.186042 -302.090328) (xy 450.627242 -302.090328) (xy 450.627242 -301.814738)
			)
		)
	)
	(zone
		(layer "In11.Cu")
		(hatch none 0.5)
		(connect_pads
			(clearance 0)
		)
		(min_thickness 0.25)
		(keepout
			(tracks allowed)
			(vias allowed)
			(pads allowed)
			(copperpour allowed)
			(footprints allowed)
		)
		(placement
			(enabled no)
			(sheetname "")
		)
		(fill
			(thermal_gap 0.5)
			(thermal_bridge_width 0.5)
			(island_removal_mode 0)
		)
		(polygon
			(pts
				(xy 46.646084 -238.39678) (xy 46.646084 -237.847124) (xy 47.276004 -237.847124) (xy 47.276004 -238.39678)
			)
		)
	)
	(zone
		(layer "In11.Cu")
		(hatch none 0.5)
		(connect_pads
			(clearance 0)
		)
		(min_thickness 0.25)
		(keepout
			(tracks allowed)
			(vias allowed)
			(pads allowed)
			(copperpour allowed)
			(footprints allowed)
		)
		(placement
			(enabled no)
			(sheetname "")
		)
		(fill
			(thermal_gap 0.5)
			(thermal_bridge_width 0.5)
			(island_removal_mode 0)
		)
		(polygon
			(pts
				(xy 172.521118 -213.518496) (xy 172.521118 -213.242906) (xy 173.079918 -213.242906) (xy 173.079918 -213.518496)
			)
		)
	)
	(zone
		(layer "In11.Cu")
		(hatch none 0.5)
		(connect_pads
			(clearance 0)
		)
		(min_thickness 0.25)
		(keepout
			(tracks allowed)
			(vias allowed)
			(pads allowed)
			(copperpour allowed)
			(footprints allowed)
		)
		(placement
			(enabled no)
			(sheetname "")
		)
		(fill
			(thermal_gap 0.5)
			(thermal_bridge_width 0.5)
			(island_removal_mode 0)
		)
		(polygon
			(pts
				(xy 173.070774 -231.264714) (xy 173.070774 -231.540304) (xy 172.511974 -231.540304) (xy 172.511974 -231.264714)
			)
		)
	)
	(zone
		(layer "In11.Cu")
		(hatch none 0.5)
		(connect_pads
			(clearance 0)
		)
		(min_thickness 0.25)
		(keepout
			(tracks allowed)
			(vias allowed)
			(pads allowed)
			(copperpour allowed)
			(footprints allowed)
		)
		(placement
			(enabled no)
			(sheetname "")
		)
		(fill
			(thermal_gap 0.5)
			(thermal_bridge_width 0.5)
			(island_removal_mode 0)
		)
		(polygon
			(pts
				(xy 450.636386 -205.868524) (xy 450.636386 -205.592934) (xy 451.195186 -205.592934) (xy 451.195186 -205.868524)
			)
		)
	)
	(zone
		(layer "In11.Cu")
		(hatch none 0.5)
		(connect_pads
			(clearance 0)
		)
		(min_thickness 0.25)
		(keepout
			(tracks allowed)
			(vias allowed)
			(pads allowed)
			(copperpour allowed)
			(footprints allowed)
		)
		(placement
			(enabled no)
			(sheetname "")
		)
		(fill
			(thermal_gap 0.5)
			(thermal_bridge_width 0.5)
			(island_removal_mode 0)
		)
		(polygon
			(pts
				(xy 425.11091 -266.964668) (xy 425.11091 -267.240258) (xy 424.55211 -267.240258) (xy 424.55211 -266.964668)
			)
		)
	)
	(zone
		(layer "In11.Cu")
		(hatch none 0.5)
		(connect_pads
			(clearance 0)
		)
		(min_thickness 0.25)
		(keepout
			(tracks allowed)
			(vias allowed)
			(pads allowed)
			(copperpour allowed)
			(footprints allowed)
		)
		(placement
			(enabled no)
			(sheetname "")
		)
		(fill
			(thermal_gap 0.5)
			(thermal_bridge_width 0.5)
			(island_removal_mode 0)
		)
		(polygon
			(pts
				(xy 177.170842 -276.314662) (xy 177.170842 -276.590252) (xy 176.612042 -276.590252) (xy 176.612042 -276.314662)
			)
		)
	)
	(zone
		(layer "In11.Cu")
		(hatch none 0.5)
		(connect_pads
			(clearance 0)
		)
		(min_thickness 0.25)
		(keepout
			(tracks allowed)
			(vias allowed)
			(pads allowed)
			(copperpour allowed)
			(footprints allowed)
		)
		(placement
			(enabled no)
			(sheetname "")
		)
		(fill
			(thermal_gap 0.5)
			(thermal_bridge_width 0.5)
			(island_removal_mode 0)
		)
		(polygon
			(pts
				(xy 188.158374 -282.264612) (xy 188.158374 -282.540202) (xy 187.599574 -282.540202) (xy 187.599574 -282.264612)
			)
		)
	)
	(zone
		(layer "In11.Cu")
		(hatch none 0.5)
		(connect_pads
			(clearance 0)
		)
		(min_thickness 0.25)
		(keepout
			(tracks allowed)
			(vias allowed)
			(pads allowed)
			(copperpour allowed)
			(footprints allowed)
		)
		(placement
			(enabled no)
			(sheetname "")
		)
		(fill
			(thermal_gap 0.5)
			(thermal_bridge_width 0.5)
			(island_removal_mode 0)
		)
		(polygon
			(pts
				(xy 20.570952 -197.59676) (xy 20.570952 -197.047104) (xy 21.200872 -197.047104) (xy 21.200872 -197.59676)
			)
		)
	)
	(zone
		(layer "In11.Cu")
		(hatch none 0.5)
		(connect_pads
			(clearance 0)
		)
		(min_thickness 0.25)
		(keepout
			(tracks allowed)
			(vias allowed)
			(pads allowed)
			(copperpour allowed)
			(footprints allowed)
		)
		(placement
			(enabled no)
			(sheetname "")
		)
		(fill
			(thermal_gap 0.5)
			(thermal_bridge_width 0.5)
			(island_removal_mode 0)
		)
		(polygon
			(pts
				(xy 173.070774 -300.114716) (xy 173.070774 -300.390306) (xy 172.511974 -300.390306) (xy 172.511974 -300.114716)
			)
		)
	)
	(zone
		(layer "In11.Cu")
		(hatch none 0.5)
		(connect_pads
			(clearance 0)
		)
		(min_thickness 0.25)
		(keepout
			(tracks allowed)
			(vias allowed)
			(pads allowed)
			(copperpour allowed)
			(footprints allowed)
		)
		(placement
			(enabled no)
			(sheetname "")
		)
		(fill
			(thermal_gap 0.5)
			(thermal_bridge_width 0.5)
			(island_removal_mode 0)
		)
		(polygon
			(pts
				(xy 450.636386 -305.318414) (xy 450.636386 -305.042824) (xy 451.195186 -305.042824) (xy 451.195186 -305.318414)
			)
		)
	)
	(zone
		(layer "In11.Cu")
		(hatch none 0.5)
		(connect_pads
			(clearance 0)
		)
		(min_thickness 0.25)
		(keepout
			(tracks allowed)
			(vias allowed)
			(pads allowed)
			(copperpour allowed)
			(footprints allowed)
		)
		(placement
			(enabled no)
			(sheetname "")
		)
		(fill
			(thermal_gap 0.5)
			(thermal_bridge_width 0.5)
			(island_removal_mode 0)
		)
		(polygon
			(pts
				(xy 424.561254 -315.518546) (xy 424.561254 -315.242956) (xy 425.120054 -315.242956) (xy 425.120054 -315.518546)
			)
		)
	)
	(zone
		(layer "In11.Cu")
		(hatch none 0.5)
		(connect_pads
			(clearance 0)
		)
		(min_thickness 0.25)
		(keepout
			(tracks allowed)
			(vias allowed)
			(pads allowed)
			(copperpour allowed)
			(footprints allowed)
		)
		(placement
			(enabled no)
			(sheetname "")
		)
		(fill
			(thermal_gap 0.5)
			(thermal_bridge_width 0.5)
			(island_removal_mode 0)
		)
		(polygon
			(pts
				(xy 176.621186 -240.718594) (xy 176.621186 -240.443004) (xy 177.179986 -240.443004) (xy 177.179986 -240.718594)
			)
		)
	)
	(zone
		(layer "In11.Cu")
		(hatch none 0.5)
		(connect_pads
			(clearance 0)
		)
		(min_thickness 0.25)
		(keepout
			(tracks allowed)
			(vias allowed)
			(pads allowed)
			(copperpour allowed)
			(footprints allowed)
		)
		(placement
			(enabled no)
			(sheetname "")
		)
		(fill
			(thermal_gap 0.5)
			(thermal_bridge_width 0.5)
			(island_removal_mode 0)
		)
		(polygon
			(pts
				(xy 425.11091 -222.764604) (xy 425.11091 -223.040194) (xy 424.55211 -223.040194) (xy 424.55211 -222.764604)
			)
		)
	)
	(zone
		(layer "In11.Cu")
		(hatch none 0.5)
		(connect_pads
			(clearance 0)
		)
		(min_thickness 0.25)
		(keepout
			(tracks allowed)
			(vias allowed)
			(pads allowed)
			(copperpour allowed)
			(footprints allowed)
		)
		(placement
			(enabled no)
			(sheetname "")
		)
		(fill
			(thermal_gap 0.5)
			(thermal_bridge_width 0.5)
			(island_removal_mode 0)
		)
		(polygon
			(pts
				(xy 46.646084 -294.496744) (xy 46.646084 -293.947088) (xy 47.276004 -293.947088) (xy 47.276004 -294.496744)
			)
		)
	)
	(zone
		(layer "In11.Cu")
		(hatch none 0.5)
		(connect_pads
			(clearance 0)
		)
		(min_thickness 0.25)
		(keepout
			(tracks allowed)
			(vias allowed)
			(pads allowed)
			(copperpour allowed)
			(footprints allowed)
		)
		(placement
			(enabled no)
			(sheetname "")
		)
		(fill
			(thermal_gap 0.5)
			(thermal_bridge_width 0.5)
			(island_removal_mode 0)
		)
		(polygon
			(pts
				(xy 294.586152 -291.946838) (xy 294.586152 -291.397182) (xy 295.216072 -291.397182) (xy 295.216072 -291.946838)
			)
		)
	)
	(zone
		(layer "In11.Cu")
		(hatch none 0.5)
		(connect_pads
			(clearance 0)
		)
		(min_thickness 0.25)
		(keepout
			(tracks allowed)
			(vias allowed)
			(pads allowed)
			(copperpour allowed)
			(footprints allowed)
		)
		(placement
			(enabled no)
			(sheetname "")
		)
		(fill
			(thermal_gap 0.5)
			(thermal_bridge_width 0.5)
			(island_removal_mode 0)
		)
		(polygon
			(pts
				(xy 294.586152 -314.896754) (xy 294.586152 -314.347098) (xy 295.216072 -314.347098) (xy 295.216072 -314.896754)
			)
		)
	)
	(zone
		(layer "In11.Cu")
		(hatch none 0.5)
		(connect_pads
			(clearance 0)
		)
		(min_thickness 0.25)
		(keepout
			(tracks allowed)
			(vias allowed)
			(pads allowed)
			(copperpour allowed)
			(footprints allowed)
		)
		(placement
			(enabled no)
			(sheetname "")
		)
		(fill
			(thermal_gap 0.5)
			(thermal_bridge_width 0.5)
			(island_removal_mode 0)
		)
		(polygon
			(pts
				(xy 421.010842 -279.714706) (xy 421.010842 -279.990296) (xy 420.452042 -279.990296) (xy 420.452042 -279.714706)
			)
		)
	)
	(zone
		(layer "In11.Cu")
		(hatch none 0.5)
		(connect_pads
			(clearance 0)
		)
		(min_thickness 0.25)
		(keepout
			(tracks allowed)
			(vias allowed)
			(pads allowed)
			(copperpour allowed)
			(footprints allowed)
		)
		(placement
			(enabled no)
			(sheetname "")
		)
		(fill
			(thermal_gap 0.5)
			(thermal_bridge_width 0.5)
			(island_removal_mode 0)
		)
		(polygon
			(pts
				(xy 451.186042 -234.664758) (xy 451.186042 -234.940348) (xy 450.627242 -234.940348) (xy 450.627242 -234.664758)
			)
		)
	)
	(zone
		(layer "In11.Cu")
		(hatch none 0.5)
		(connect_pads
			(clearance 0)
		)
		(min_thickness 0.25)
		(keepout
			(tracks allowed)
			(vias allowed)
			(pads allowed)
			(copperpour allowed)
			(footprints allowed)
		)
		(placement
			(enabled no)
			(sheetname "")
		)
		(fill
			(thermal_gap 0.5)
			(thermal_bridge_width 0.5)
			(island_removal_mode 0)
		)
		(polygon
			(pts
				(xy 298.71162 -314.04687) (xy 298.71162 -313.497214) (xy 299.34154 -313.497214) (xy 299.34154 -314.04687)
			)
		)
	)
	(zone
		(layer "In11.Cu")
		(hatch none 0.5)
		(connect_pads
			(clearance 0)
		)
		(min_thickness 0.25)
		(keepout
			(tracks allowed)
			(vias allowed)
			(pads allowed)
			(copperpour allowed)
			(footprints allowed)
		)
		(placement
			(enabled no)
			(sheetname "")
		)
		(fill
			(thermal_gap 0.5)
			(thermal_bridge_width 0.5)
			(island_removal_mode 0)
		)
		(polygon
			(pts
				(xy 294.586152 -212.04682) (xy 294.586152 -211.497164) (xy 295.216072 -211.497164) (xy 295.216072 -212.04682)
			)
		)
	)
	(zone
		(layer "In11.Cu")
		(hatch none 0.5)
		(connect_pads
			(clearance 0)
		)
		(min_thickness 0.25)
		(keepout
			(tracks allowed)
			(vias allowed)
			(pads allowed)
			(copperpour allowed)
			(footprints allowed)
		)
		(placement
			(enabled no)
			(sheetname "")
		)
		(fill
			(thermal_gap 0.5)
			(thermal_bridge_width 0.5)
			(island_removal_mode 0)
		)
		(polygon
			(pts
				(xy 50.771552 -295.346882) (xy 50.771552 -294.797226) (xy 51.401472 -294.797226) (xy 51.401472 -295.346882)
			)
		)
	)
	(zone
		(layer "In11.Cu")
		(hatch none 0.5)
		(connect_pads
			(clearance 0)
		)
		(min_thickness 0.25)
		(keepout
			(tracks allowed)
			(vias allowed)
			(pads allowed)
			(copperpour allowed)
			(footprints allowed)
		)
		(placement
			(enabled no)
			(sheetname "")
		)
		(fill
			(thermal_gap 0.5)
			(thermal_bridge_width 0.5)
			(island_removal_mode 0)
		)
		(polygon
			(pts
				(xy 176.621186 -264.518394) (xy 176.621186 -264.242804) (xy 177.179986 -264.242804) (xy 177.179986 -264.518394)
			)
		)
	)
	(zone
		(layer "In11.Cu")
		(hatch none 0.5)
		(connect_pads
			(clearance 0)
		)
		(min_thickness 0.25)
		(keepout
			(tracks allowed)
			(vias allowed)
			(pads allowed)
			(copperpour allowed)
			(footprints allowed)
		)
		(placement
			(enabled no)
			(sheetname "")
		)
		(fill
			(thermal_gap 0.5)
			(thermal_bridge_width 0.5)
			(island_removal_mode 0)
		)
		(polygon
			(pts
				(xy 420.461186 -248.368566) (xy 420.461186 -248.092976) (xy 421.019986 -248.092976) (xy 421.019986 -248.368566)
			)
		)
	)
	(zone
		(layer "In11.Cu")
		(hatch none 0.5)
		(connect_pads
			(clearance 0)
		)
		(min_thickness 0.25)
		(keepout
			(tracks allowed)
			(vias allowed)
			(pads allowed)
			(copperpour allowed)
			(footprints allowed)
		)
		(placement
			(enabled no)
			(sheetname "")
		)
		(fill
			(thermal_gap 0.5)
			(thermal_bridge_width 0.5)
			(island_removal_mode 0)
		)
		(polygon
			(pts
				(xy 202.696318 -217.768424) (xy 202.696318 -217.492834) (xy 203.255118 -217.492834) (xy 203.255118 -217.768424)
			)
		)
	)
	(zone
		(layer "In11.Cu")
		(hatch none 0.5)
		(connect_pads
			(clearance 0)
		)
		(min_thickness 0.25)
		(keepout
			(tracks allowed)
			(vias allowed)
			(pads allowed)
			(copperpour allowed)
			(footprints allowed)
		)
		(placement
			(enabled no)
			(sheetname "")
		)
		(fill
			(thermal_gap 0.5)
			(thermal_bridge_width 0.5)
			(island_removal_mode 0)
		)
		(polygon
			(pts
				(xy 450.636386 -217.768424) (xy 450.636386 -217.492834) (xy 451.195186 -217.492834) (xy 451.195186 -217.768424)
			)
		)
	)
	(zone
		(layer "In11.Cu")
		(hatch none 0.5)
		(connect_pads
			(clearance 0)
		)
		(min_thickness 0.25)
		(keepout
			(tracks allowed)
			(vias allowed)
			(pads allowed)
			(copperpour allowed)
			(footprints allowed)
		)
		(placement
			(enabled no)
			(sheetname "")
		)
		(fill
			(thermal_gap 0.5)
			(thermal_bridge_width 0.5)
			(island_removal_mode 0)
		)
		(polygon
			(pts
				(xy 450.636386 -198.218552) (xy 450.636386 -197.942962) (xy 451.195186 -197.942962) (xy 451.195186 -198.218552)
			)
		)
	)
	(zone
		(layer "In11.Cu")
		(hatch none 0.5)
		(connect_pads
			(clearance 0)
		)
		(min_thickness 0.25)
		(keepout
			(tracks allowed)
			(vias allowed)
			(pads allowed)
			(copperpour allowed)
			(footprints allowed)
		)
		(placement
			(enabled no)
			(sheetname "")
		)
		(fill
			(thermal_gap 0.5)
			(thermal_bridge_width 0.5)
			(island_removal_mode 0)
		)
		(polygon
			(pts
				(xy 298.71162 -281.74696) (xy 298.71162 -281.197304) (xy 299.34154 -281.197304) (xy 299.34154 -281.74696)
			)
		)
	)
	(zone
		(layer "In11.Cu")
		(hatch none 0.5)
		(connect_pads
			(clearance 0)
		)
		(min_thickness 0.25)
		(keepout
			(tracks allowed)
			(vias allowed)
			(pads allowed)
			(copperpour allowed)
			(footprints allowed)
		)
		(placement
			(enabled no)
			(sheetname "")
		)
		(fill
			(thermal_gap 0.5)
			(thermal_bridge_width 0.5)
			(island_removal_mode 0)
		)
		(polygon
			(pts
				(xy 192.258442 -278.864822) (xy 192.258442 -279.140412) (xy 191.699642 -279.140412) (xy 191.699642 -278.864822)
			)
		)
	)
	(zone
		(layer "In11.Cu")
		(hatch none 0.5)
		(connect_pads
			(clearance 0)
		)
		(min_thickness 0.25)
		(keepout
			(tracks allowed)
			(vias allowed)
			(pads allowed)
			(copperpour allowed)
			(footprints allowed)
		)
		(placement
			(enabled no)
			(sheetname "")
		)
		(fill
			(thermal_gap 0.5)
			(thermal_bridge_width 0.5)
			(island_removal_mode 0)
		)
		(polygon
			(pts
				(xy 173.070774 -282.264612) (xy 173.070774 -282.540202) (xy 172.511974 -282.540202) (xy 172.511974 -282.264612)
			)
		)
	)
	(zone
		(layer "In11.Cu")
		(hatch none 0.5)
		(connect_pads
			(clearance 0)
		)
		(min_thickness 0.25)
		(keepout
			(tracks allowed)
			(vias allowed)
			(pads allowed)
			(copperpour allowed)
			(footprints allowed)
		)
		(placement
			(enabled no)
			(sheetname "")
		)
		(fill
			(thermal_gap 0.5)
			(thermal_bridge_width 0.5)
			(island_removal_mode 0)
		)
		(polygon
			(pts
				(xy 176.621186 -298.51858) (xy 176.621186 -298.24299) (xy 177.179986 -298.24299) (xy 177.179986 -298.51858)
			)
		)
	)
	(zone
		(layer "In11.Cu")
		(hatch none 0.5)
		(connect_pads
			(clearance 0)
		)
		(min_thickness 0.25)
		(keepout
			(tracks allowed)
			(vias allowed)
			(pads allowed)
			(copperpour allowed)
			(footprints allowed)
		)
		(placement
			(enabled no)
			(sheetname "")
		)
		(fill
			(thermal_gap 0.5)
			(thermal_bridge_width 0.5)
			(island_removal_mode 0)
		)
		(polygon
			(pts
				(xy 451.186042 -295.01465) (xy 451.186042 -295.29024) (xy 450.627242 -295.29024) (xy 450.627242 -295.01465)
			)
		)
	)
	(zone
		(layer "In11.Cu")
		(hatch none 0.5)
		(connect_pads
			(clearance 0)
		)
		(min_thickness 0.25)
		(keepout
			(tracks allowed)
			(vias allowed)
			(pads allowed)
			(copperpour allowed)
			(footprints allowed)
		)
		(placement
			(enabled no)
			(sheetname "")
		)
		(fill
			(thermal_gap 0.5)
			(thermal_bridge_width 0.5)
			(island_removal_mode 0)
		)
		(polygon
			(pts
				(xy 172.521118 -311.268618) (xy 172.521118 -310.993028) (xy 173.079918 -310.993028) (xy 173.079918 -311.268618)
			)
		)
	)
	(zone
		(layer "In11.Cu")
		(hatch none 0.5)
		(connect_pads
			(clearance 0)
		)
		(min_thickness 0.25)
		(keepout
			(tracks allowed)
			(vias allowed)
			(pads allowed)
			(copperpour allowed)
			(footprints allowed)
		)
		(placement
			(enabled no)
			(sheetname "")
		)
		(fill
			(thermal_gap 0.5)
			(thermal_bridge_width 0.5)
			(island_removal_mode 0)
		)
		(polygon
			(pts
				(xy 298.71162 -265.596878) (xy 298.71162 -265.047222) (xy 299.34154 -265.047222) (xy 299.34154 -265.596878)
			)
		)
	)
	(zone
		(layer "In11.Cu")
		(hatch none 0.5)
		(connect_pads
			(clearance 0)
		)
		(min_thickness 0.25)
		(keepout
			(tracks allowed)
			(vias allowed)
			(pads allowed)
			(copperpour allowed)
			(footprints allowed)
		)
		(placement
			(enabled no)
			(sheetname "")
		)
		(fill
			(thermal_gap 0.5)
			(thermal_bridge_width 0.5)
			(island_removal_mode 0)
		)
		(polygon
			(pts
				(xy 425.11091 -211.714842) (xy 425.11091 -211.990432) (xy 424.55211 -211.990432) (xy 424.55211 -211.714842)
			)
		)
	)
	(zone
		(layer "In11.Cu")
		(hatch none 0.5)
		(connect_pads
			(clearance 0)
		)
		(min_thickness 0.25)
		(keepout
			(tracks allowed)
			(vias allowed)
			(pads allowed)
			(copperpour allowed)
			(footprints allowed)
		)
		(placement
			(enabled no)
			(sheetname "")
		)
		(fill
			(thermal_gap 0.5)
			(thermal_bridge_width 0.5)
			(island_removal_mode 0)
		)
		(polygon
			(pts
				(xy 187.608718 -278.11857) (xy 187.608718 -277.84298) (xy 188.167518 -277.84298) (xy 188.167518 -278.11857)
			)
		)
	)
	(zone
		(layer "In11.Cu")
		(hatch none 0.5)
		(connect_pads
			(clearance 0)
		)
		(min_thickness 0.25)
		(keepout
			(tracks not_allowed)
			(vias allowed)
			(pads allowed)
			(copperpour not_allowed)
			(footprints allowed)
		)
		(placement
			(enabled no)
			(sheetname "")
		)
		(fill
			(thermal_gap 0.5)
			(thermal_bridge_width 0.5)
			(island_removal_mode 0)
		)
		(polygon
			(pts
				(arc
					(start 383.242058 -428.960788)
					(mid 383.264376 -429.01467)
					(end 383.318258 -429.036988)
				)
				(arc
					(start 384.258058 -429.036988)
					(mid 384.31194 -429.01467)
					(end 384.334258 -428.960788)
				)
				(arc
					(start 384.334258 -426.419264)
					(mid 384.31194 -426.365382)
					(end 384.258058 -426.343064)
				)
				(arc
					(start 383.318258 -426.343064)
					(mid 383.264376 -426.365382)
					(end 383.242058 -426.419264)
				)
			)
		)
	)
	(zone
		(layer "In11.Cu")
		(hatch none 0.5)
		(connect_pads
			(clearance 0)
		)
		(min_thickness 0.25)
		(keepout
			(tracks allowed)
			(vias allowed)
			(pads allowed)
			(copperpour allowed)
			(footprints allowed)
		)
		(placement
			(enabled no)
			(sheetname "")
		)
		(fill
			(thermal_gap 0.5)
			(thermal_bridge_width 0.5)
			(island_removal_mode 0)
		)
		(polygon
			(pts
				(xy 172.994574 -263.564624) (xy 172.994574 -263.840214) (xy 172.435774 -263.840214) (xy 172.435774 -263.564624)
			)
		)
	)
	(zone
		(layer "In11.Cu")
		(hatch none 0.5)
		(connect_pads
			(clearance 0)
		)
		(min_thickness 0.25)
		(keepout
			(tracks allowed)
			(vias allowed)
			(pads allowed)
			(copperpour allowed)
			(footprints allowed)
		)
		(placement
			(enabled no)
			(sheetname "")
		)
		(fill
			(thermal_gap 0.5)
			(thermal_bridge_width 0.5)
			(island_removal_mode 0)
		)
		(polygon
			(pts
				(xy 172.521118 -215.218518) (xy 172.521118 -214.942928) (xy 173.079918 -214.942928) (xy 173.079918 -215.218518)
			)
		)
	)
	(zone
		(layer "In11.Cu")
		(hatch none 0.5)
		(connect_pads
			(clearance 0)
		)
		(min_thickness 0.25)
		(keepout
			(tracks allowed)
			(vias allowed)
			(pads allowed)
			(copperpour allowed)
			(footprints allowed)
		)
		(placement
			(enabled no)
			(sheetname "")
		)
		(fill
			(thermal_gap 0.5)
			(thermal_bridge_width 0.5)
			(island_removal_mode 0)
		)
		(polygon
			(pts
				(xy 435.548786 -310.41848) (xy 435.548786 -310.14289) (xy 436.107586 -310.14289) (xy 436.107586 -310.41848)
			)
		)
	)
	(zone
		(layer "In11.Cu")
		(hatch none 0.5)
		(connect_pads
			(clearance 0)
		)
		(min_thickness 0.25)
		(keepout
			(tracks allowed)
			(vias allowed)
			(pads allowed)
			(copperpour allowed)
			(footprints allowed)
		)
		(placement
			(enabled no)
			(sheetname "")
		)
		(fill
			(thermal_gap 0.5)
			(thermal_bridge_width 0.5)
			(island_removal_mode 0)
		)
		(polygon
			(pts
				(xy 451.186042 -289.0647) (xy 451.186042 -289.34029) (xy 450.627242 -289.34029) (xy 450.627242 -289.0647)
			)
		)
	)
	(zone
		(layer "In11.Cu")
		(hatch none 0.5)
		(connect_pads
			(clearance 0)
		)
		(min_thickness 0.25)
		(keepout
			(tracks allowed)
			(vias allowed)
			(pads allowed)
			(copperpour allowed)
			(footprints allowed)
		)
		(placement
			(enabled no)
			(sheetname "")
		)
		(fill
			(thermal_gap 0.5)
			(thermal_bridge_width 0.5)
			(island_removal_mode 0)
		)
		(polygon
			(pts
				(xy 176.621186 -209.268568) (xy 176.621186 -208.992978) (xy 177.179986 -208.992978) (xy 177.179986 -209.268568)
			)
		)
	)
	(zone
		(layer "In11.Cu")
		(hatch none 0.5)
		(connect_pads
			(clearance 0)
		)
		(min_thickness 0.25)
		(keepout
			(tracks allowed)
			(vias allowed)
			(pads allowed)
			(copperpour allowed)
			(footprints allowed)
		)
		(placement
			(enabled no)
			(sheetname "")
		)
		(fill
			(thermal_gap 0.5)
			(thermal_bridge_width 0.5)
			(island_removal_mode 0)
		)
		(polygon
			(pts
				(xy 436.098442 -227.014786) (xy 436.098442 -227.290376) (xy 435.539642 -227.290376) (xy 435.539642 -227.014786)
			)
		)
	)
	(zone
		(layer "In11.Cu")
		(hatch none 0.5)
		(connect_pads
			(clearance 0)
		)
		(min_thickness 0.25)
		(keepout
			(tracks allowed)
			(vias allowed)
			(pads allowed)
			(copperpour allowed)
			(footprints allowed)
		)
		(placement
			(enabled no)
			(sheetname "")
		)
		(fill
			(thermal_gap 0.5)
			(thermal_bridge_width 0.5)
			(island_removal_mode 0)
		)
		(polygon
			(pts
				(xy 298.71162 -262.196834) (xy 298.71162 -261.647178) (xy 299.34154 -261.647178) (xy 299.34154 -262.196834)
			)
		)
	)
	(zone
		(layer "In11.Cu")
		(hatch none 0.5)
		(connect_pads
			(clearance 0)
		)
		(min_thickness 0.25)
		(keepout
			(tracks allowed)
			(vias allowed)
			(pads allowed)
			(copperpour allowed)
			(footprints allowed)
		)
		(placement
			(enabled no)
			(sheetname "")
		)
		(fill
			(thermal_gap 0.5)
			(thermal_bridge_width 0.5)
			(island_removal_mode 0)
		)
		(polygon
			(pts
				(xy 436.098442 -309.46471) (xy 436.098442 -309.7403) (xy 435.539642 -309.7403) (xy 435.539642 -309.46471)
			)
		)
	)
	(zone
		(layer "In11.Cu")
		(hatch none 0.5)
		(connect_pads
			(clearance 0)
		)
		(min_thickness 0.25)
		(keepout
			(tracks not_allowed)
			(vias allowed)
			(pads allowed)
			(copperpour not_allowed)
			(footprints allowed)
		)
		(placement
			(enabled no)
			(sheetname "")
		)
		(fill
			(thermal_gap 0.5)
			(thermal_bridge_width 0.5)
			(island_removal_mode 0)
		)
		(polygon
			(pts
				(arc
					(start 408.242008 -428.960788)
					(mid 408.264326 -429.01467)
					(end 408.318208 -429.036988)
				)
				(arc
					(start 409.258008 -429.036988)
					(mid 409.31189 -429.01467)
					(end 409.334208 -428.960788)
				)
				(arc
					(start 409.334208 -426.419264)
					(mid 409.31189 -426.365382)
					(end 409.258008 -426.343064)
				)
				(arc
					(start 408.318208 -426.343064)
					(mid 408.264326 -426.365382)
					(end 408.242008 -426.419264)
				)
			)
		)
	)
	(zone
		(layer "In11.Cu")
		(hatch none 0.5)
		(connect_pads
			(clearance 0)
		)
		(min_thickness 0.25)
		(keepout
			(tracks allowed)
			(vias allowed)
			(pads allowed)
			(copperpour allowed)
			(footprints allowed)
		)
		(placement
			(enabled no)
			(sheetname "")
		)
		(fill
			(thermal_gap 0.5)
			(thermal_bridge_width 0.5)
			(island_removal_mode 0)
		)
		(polygon
			(pts
				(xy 172.521118 -289.168586) (xy 172.521118 -288.892996) (xy 173.079918 -288.892996) (xy 173.079918 -289.168586)
			)
		)
	)
	(zone
		(layer "In11.Cu")
		(hatch none 0.5)
		(connect_pads
			(clearance 0)
		)
		(min_thickness 0.25)
		(keepout
			(tracks allowed)
			(vias allowed)
			(pads allowed)
			(copperpour allowed)
			(footprints allowed)
		)
		(placement
			(enabled no)
			(sheetname "")
		)
		(fill
			(thermal_gap 0.5)
			(thermal_bridge_width 0.5)
			(island_removal_mode 0)
		)
		(polygon
			(pts
				(xy 141.670278 -281.33421) (xy 142.419578 -281.33421) (xy 143.153638 -280.60015) (xy 143.153638 -279.90927)
				(xy 139.523978 -276.27961) (xy 139.39266 -276.27961) (xy 139.39266 -276.792182) (xy 139.768834 -277.168356)
				(xy 139.768834 -277.29942) (xy 139.675616 -277.392638) (xy 139.675616 -277.673816) (xy 139.80668 -277.80488)
				(xy 139.80668 -278.004524) (xy 139.662154 -278.14905) (xy 139.662154 -278.34082) (xy 139.807442 -278.486108)
				(xy 139.807442 -278.6634) (xy 139.63269 -278.838152) (xy 139.630658 -278.838152) (xy 139.630658 -279.29459)
				(xy 139.630658 -279.681432) (xy 140.021818 -280.072592) (xy 140.148818 -280.199592) (xy 140.148818 -280.47061)
				(xy 139.696698 -280.92273) (xy 139.696698 -281.01163) (xy 139.795758 -281.11069) (xy 139.800838 -281.11069)
				(xy 139.856718 -281.16657) (xy 139.856718 -281.32151) (xy 139.6746 -281.503628) (xy 139.6746 -281.716988)
				(xy 139.39774 -281.993848) (xy 139.39774 -282.379928) (xy 140.859002 -283.84119) (xy 141.045438 -283.84119)
				(xy 141.136878 -283.74975) (xy 141.136878 -282.98267) (xy 140.969238 -282.81503) (xy 140.969238 -281.83713)
				(xy 141.472158 -281.33421)
			)
		)
	)
	(zone
		(layer "In11.Cu")
		(hatch none 0.5)
		(connect_pads
			(clearance 0)
		)
		(min_thickness 0.25)
		(keepout
			(tracks allowed)
			(vias allowed)
			(pads allowed)
			(copperpour allowed)
			(footprints allowed)
		)
		(placement
			(enabled no)
			(sheetname "")
		)
		(fill
			(thermal_gap 0.5)
			(thermal_bridge_width 0.5)
			(island_removal_mode 0)
		)
		(polygon
			(pts
				(xy 425.11091 -216.814654) (xy 425.11091 -217.090244) (xy 424.55211 -217.090244) (xy 424.55211 -216.814654)
			)
		)
	)
	(zone
		(layer "In11.Cu")
		(hatch none 0.5)
		(connect_pads
			(clearance 0)
		)
		(min_thickness 0.25)
		(keepout
			(tracks allowed)
			(vias allowed)
			(pads allowed)
			(copperpour allowed)
			(footprints allowed)
		)
		(placement
			(enabled no)
			(sheetname "")
		)
		(fill
			(thermal_gap 0.5)
			(thermal_bridge_width 0.5)
			(island_removal_mode 0)
		)
		(polygon
			(pts
				(xy 187.608718 -310.41848) (xy 187.608718 -310.14289) (xy 188.167518 -310.14289) (xy 188.167518 -310.41848)
			)
		)
	)
	(zone
		(layer "In11.Cu")
		(hatch none 0.5)
		(connect_pads
			(clearance 0)
		)
		(min_thickness 0.25)
		(keepout
			(tracks allowed)
			(vias allowed)
			(pads allowed)
			(copperpour allowed)
			(footprints allowed)
		)
		(placement
			(enabled no)
			(sheetname "")
		)
		(fill
			(thermal_gap 0.5)
			(thermal_bridge_width 0.5)
			(island_removal_mode 0)
		)
		(polygon
			(pts
				(xy 184.714642 -267.814806) (xy 184.714642 -268.090396) (xy 184.155842 -268.090396) (xy 184.155842 -267.814806)
			)
		)
	)
	(zone
		(layer "In11.Cu")
		(hatch none 0.5)
		(connect_pads
			(clearance 0)
		)
		(min_thickness 0.25)
		(keepout
			(tracks allowed)
			(vias allowed)
			(pads allowed)
			(copperpour allowed)
			(footprints allowed)
		)
		(placement
			(enabled no)
			(sheetname "")
		)
		(fill
			(thermal_gap 0.5)
			(thermal_bridge_width 0.5)
			(island_removal_mode 0)
		)
		(polygon
			(pts
				(xy 313.77382 -268.996922) (xy 313.77382 -268.447266) (xy 314.40374 -268.447266) (xy 314.40374 -268.996922)
			)
		)
	)
	(zone
		(layer "In11.Cu")
		(hatch none 0.5)
		(connect_pads
			(clearance 0)
		)
		(min_thickness 0.25)
		(keepout
			(tracks allowed)
			(vias allowed)
			(pads allowed)
			(copperpour allowed)
			(footprints allowed)
		)
		(placement
			(enabled no)
			(sheetname "")
		)
		(fill
			(thermal_gap 0.5)
			(thermal_bridge_width 0.5)
			(island_removal_mode 0)
		)
		(polygon
			(pts
				(xy 176.621186 -252.618494) (xy 176.621186 -252.342904) (xy 177.179986 -252.342904) (xy 177.179986 -252.618494)
			)
		)
	)
	(zone
		(layer "In11.Cu")
		(hatch none 0.5)
		(connect_pads
			(clearance 0)
		)
		(min_thickness 0.25)
		(keepout
			(tracks allowed)
			(vias allowed)
			(pads allowed)
			(copperpour allowed)
			(footprints allowed)
		)
		(placement
			(enabled no)
			(sheetname "")
		)
		(fill
			(thermal_gap 0.5)
			(thermal_bridge_width 0.5)
			(island_removal_mode 0)
		)
		(polygon
			(pts
				(xy 298.71162 -270.696944) (xy 298.71162 -270.147288) (xy 299.34154 -270.147288) (xy 299.34154 -270.696944)
			)
		)
	)
	(zone
		(layer "In11.Cu")
		(hatch none 0.5)
		(connect_pads
			(clearance 0)
		)
		(min_thickness 0.25)
		(keepout
			(tracks allowed)
			(vias allowed)
			(pads allowed)
			(copperpour allowed)
			(footprints allowed)
		)
		(placement
			(enabled no)
			(sheetname "")
		)
		(fill
			(thermal_gap 0.5)
			(thermal_bridge_width 0.5)
			(island_removal_mode 0)
		)
		(polygon
			(pts
				(xy 268.51102 -240.94694) (xy 268.51102 -240.397284) (xy 269.14094 -240.397284) (xy 269.14094 -240.94694)
			)
		)
	)
	(zone
		(layer "In11.Cu")
		(hatch none 0.5)
		(connect_pads
			(clearance 0)
		)
		(min_thickness 0.25)
		(keepout
			(tracks allowed)
			(vias allowed)
			(pads allowed)
			(copperpour allowed)
			(footprints allowed)
		)
		(placement
			(enabled no)
			(sheetname "")
		)
		(fill
			(thermal_gap 0.5)
			(thermal_bridge_width 0.5)
			(island_removal_mode 0)
		)
		(polygon
			(pts
				(xy 350.905826 -210.893152) (xy 355.51745 -210.893152) (xy 358.250744 -210.893152) (xy 386.515356 -210.892644)
				(xy 386.713984 -211.091272) (xy 386.713984 -216.51468) (xy 387.391656 -217.192352) (xy 387.39191 -219.271342)
				(xy 388.222236 -220.101668) (xy 388.222236 -220.349826) (xy 388.372096 -220.499686) (xy 388.372096 -220.739208)
				(xy 388.248652 -220.862652) (xy 388.248652 -221.189804) (xy 389.12546 -222.066612) (xy 389.12546 -222.179642)
				(xy 388.88416 -222.420942) (xy 388.88416 -223.422464) (xy 388.005828 -224.300796) (xy 388.005828 -224.373948)
				(xy 388.906258 -225.274378) (xy 388.906258 -225.32213) (xy 388.34568 -225.882708) (xy 388.34568 -225.957892)
				(xy 388.617968 -226.23018) (xy 388.617968 -226.393756) (xy 388.173468 -226.838256) (xy 388.173468 -231.473248)
				(xy 388.458202 -231.757982) (xy 388.458202 -232.134156) (xy 388.27964 -232.312718) (xy 388.27964 -234.26674)
				(xy 388.519162 -234.506262) (xy 389.112252 -234.506262) (xy 389.118348 -234.512358) (xy 389.118348 -245.882668)
				(xy 388.735824 -246.265192) (xy 386.426964 -246.265446) (xy 386.41909 -246.265446) (xy 386.316728 -246.367808)
				(xy 386.316728 -246.796052) (xy 386.249672 -246.863108) (xy 386.249672 -249.408188) (xy 386.098288 -249.559572)
				(xy 386.098288 -249.806206) (xy 386.009388 -249.895106) (xy 385.835398 -249.895106) (xy 385.322064 -250.40844)
				(xy 384.86207 -250.40844) (xy 384.725164 -250.271534) (xy 375.285762 -250.271534) (xy 374.749568 -250.807728)
				(xy 372.473728 -250.807728) (xy 372.462806 -250.81865) (xy 372.462806 -251.660406) (xy 372.661434 -251.859034)
				(xy 372.661434 -252.919738) (xy 372.462806 -253.118366) (xy 372.462806 -253.966726) (xy 372.528846 -254.032766)
				(xy 372.937786 -254.032766) (xy 373.076978 -253.893574) (xy 373.19331 -253.893574) (xy 373.19331 -253.83363)
				(xy 373.19331 -253.708154) (xy 373.204486 -253.696978) (xy 373.476012 -253.696978) (xy 373.672608 -253.893574)
				(xy 388.129018 -253.89332) (xy 388.28853 -254.052832) (xy 388.28853 -258.149598) (xy 388.234682 -258.203446)
				(xy 388.129018 -258.203446) (xy 387.335014 -258.203446) (xy 387.234176 -258.304284) (xy 387.234176 -258.760722)
				(xy 387.378702 -258.905248) (xy 387.949186 -258.905248) (xy 388.00913 -258.965192) (xy 388.00913 -260.059932)
				(xy 388.079488 -260.13029) (xy 388.079488 -260.60527) (xy 387.965442 -260.719316) (xy 387.965442 -260.945376)
				(xy 388.155434 -261.135368) (xy 388.155434 -261.335266) (xy 388.144004 -261.346696) (xy 388.116064 -261.346696)
				(xy 387.926072 -261.536688) (xy 387.926072 -261.604252) (xy 388.611618 -262.289798) (xy 388.875778 -262.289798)
				(xy 388.927848 -262.341868) (xy 388.927848 -263.809988) (xy 388.895844 -263.841992) (xy 387.629146 -263.842246)
				(xy 387.629146 -265.798046) (xy 387.629146 -265.910314) (xy 387.876542 -266.15771) (xy 388.028688 -266.15771)
				(xy 388.129018 -266.25804) (xy 388.129018 -268.238732) (xy 388.206996 -268.31671) (xy 388.61111 -268.31671)
				(xy 388.689088 -268.394688) (xy 388.689088 -271.023588) (xy 388.509256 -271.20342) (xy 388.077456 -271.20342)
				(xy 387.332728 -271.948148) (xy 387.332728 -276.792182) (xy 387.708902 -277.168356) (xy 387.708902 -277.29942)
				(xy 387.615684 -277.392638) (xy 387.615684 -277.673816) (xy 387.746748 -277.80488) (xy 387.746748 -278.004524)
				(xy 387.602222 -278.14905) (xy 387.602222 -278.34082) (xy 387.74751 -278.486108) (xy 387.74751 -278.6634)
				(xy 387.572758 -278.838152) (xy 387.570726 -278.838152) (xy 387.570726 -279.681432) (xy 387.961886 -280.072592)
				(xy 388.088886 -280.199592) (xy 388.088886 -280.47061) (xy 387.636766 -280.92273) (xy 387.636766 -281.01163)
				(xy 387.735826 -281.11069) (xy 387.740906 -281.11069) (xy 387.796786 -281.16657) (xy 387.796786 -281.32151)
				(xy 387.614668 -281.503628) (xy 387.614668 -281.716988) (xy 387.337808 -281.993848) (xy 387.337808 -282.379928)
				(xy 387.862826 -282.904946) (xy 388.523226 -283.565346) (xy 388.523226 -283.87167) (xy 387.922262 -283.87167)
				(xy 387.922262 -283.64688) (xy 387.252464 -282.977082) (xy 387.033262 -282.977082) (xy 386.31368 -283.696664)
				(xy 386.31368 -283.86024) (xy 386.71246 -284.259274) (xy 386.71246 -284.789626) (xy 387.399784 -285.47695)
				(xy 387.846824 -285.92399) (xy 387.846824 -285.934912) (xy 386.885942 -286.895794) (xy 386.823712 -286.958024)
				(xy 386.226304 -286.958024) (xy 386.206746 -286.977582) (xy 386.206746 -288.07283) (xy 386.715254 -288.581338)
				(xy 386.715508 -291.495988) (xy 358.252268 -291.496496) (xy 355.518974 -291.496496) (xy 350.90735 -291.496496)
			)
		)
	)
	(zone
		(layer "In11.Cu")
		(hatch none 0.5)
		(connect_pads
			(clearance 0)
		)
		(min_thickness 0.25)
		(keepout
			(tracks allowed)
			(vias allowed)
			(pads allowed)
			(copperpour allowed)
			(footprints allowed)
		)
		(placement
			(enabled no)
			(sheetname "")
		)
		(fill
			(thermal_gap 0.5)
			(thermal_bridge_width 0.5)
			(island_removal_mode 0)
		)
		(polygon
			(pts
				(xy 425.11091 -265.264646) (xy 425.11091 -265.540236) (xy 424.55211 -265.540236) (xy 424.55211 -265.264646)
			)
		)
	)
	(zone
		(layer "In11.Cu")
		(hatch none 0.5)
		(connect_pads
			(clearance 0)
		)
		(min_thickness 0.25)
		(keepout
			(tracks allowed)
			(vias allowed)
			(pads allowed)
			(copperpour allowed)
			(footprints allowed)
		)
		(placement
			(enabled no)
			(sheetname "")
		)
		(fill
			(thermal_gap 0.5)
			(thermal_bridge_width 0.5)
			(island_removal_mode 0)
		)
		(polygon
			(pts
				(xy 421.010842 -274.61464) (xy 421.010842 -274.89023) (xy 420.452042 -274.89023) (xy 420.452042 -274.61464)
			)
		)
	)
	(zone
		(layer "In11.Cu")
		(hatch none 0.5)
		(connect_pads
			(clearance 0)
		)
		(min_thickness 0.25)
		(keepout
			(tracks allowed)
			(vias allowed)
			(pads allowed)
			(copperpour allowed)
			(footprints allowed)
		)
		(placement
			(enabled no)
			(sheetname "")
		)
		(fill
			(thermal_gap 0.5)
			(thermal_bridge_width 0.5)
			(island_removal_mode 0)
		)
		(polygon
			(pts
				(xy 177.170842 -219.364814) (xy 177.170842 -219.640404) (xy 176.612042 -219.640404) (xy 176.612042 -219.364814)
			)
		)
	)
	(zone
		(layer "In11.Cu")
		(hatch none 0.5)
		(connect_pads
			(clearance 0)
		)
		(min_thickness 0.25)
		(keepout
			(tracks allowed)
			(vias allowed)
			(pads allowed)
			(copperpour allowed)
			(footprints allowed)
		)
		(placement
			(enabled no)
			(sheetname "")
		)
		(fill
			(thermal_gap 0.5)
			(thermal_bridge_width 0.5)
			(island_removal_mode 0)
		)
		(polygon
			(pts
				(xy 50.771552 -262.196834) (xy 50.771552 -261.647178) (xy 51.401472 -261.647178) (xy 51.401472 -262.196834)
			)
		)
	)
	(zone
		(layer "In11.Cu")
		(hatch none 0.5)
		(connect_pads
			(clearance 0)
		)
		(min_thickness 0.25)
		(keepout
			(tracks allowed)
			(vias allowed)
			(pads allowed)
			(copperpour allowed)
			(footprints allowed)
		)
		(placement
			(enabled no)
			(sheetname "")
		)
		(fill
			(thermal_gap 0.5)
			(thermal_bridge_width 0.5)
			(island_removal_mode 0)
		)
		(polygon
			(pts
				(xy 424.561254 -296.818558) (xy 424.561254 -296.542968) (xy 425.120054 -296.542968) (xy 425.120054 -296.818558)
			)
		)
	)
	(zone
		(layer "In11.Cu")
		(hatch none 0.5)
		(connect_pads
			(clearance 0)
		)
		(min_thickness 0.25)
		(keepout
			(tracks allowed)
			(vias allowed)
			(pads allowed)
			(copperpour allowed)
			(footprints allowed)
		)
		(placement
			(enabled no)
			(sheetname "")
		)
		(fill
			(thermal_gap 0.5)
			(thermal_bridge_width 0.5)
			(island_removal_mode 0)
		)
		(polygon
			(pts
				(xy 203.245974 -222.764604) (xy 203.245974 -223.040194) (xy 202.687174 -223.040194) (xy 202.687174 -222.764604)
				(xy 202.687174 -222.323406) (xy 203.245974 -222.323406)
			)
		)
	)
	(zone
		(layer "In11.Cu")
		(hatch none 0.5)
		(connect_pads
			(clearance 0)
		)
		(min_thickness 0.25)
		(keepout
			(tracks allowed)
			(vias allowed)
			(pads allowed)
			(copperpour allowed)
			(footprints allowed)
		)
		(placement
			(enabled no)
			(sheetname "")
		)
		(fill
			(thermal_gap 0.5)
			(thermal_bridge_width 0.5)
			(island_removal_mode 0)
		)
		(polygon
			(pts
				(xy 435.548786 -236.468412) (xy 435.548786 -236.192822) (xy 436.107586 -236.192822) (xy 436.107586 -236.468412)
			)
		)
	)
	(zone
		(layer "In11.Cu")
		(hatch none 0.5)
		(connect_pads
			(clearance 0)
		)
		(min_thickness 0.25)
		(keepout
			(tracks allowed)
			(vias allowed)
			(pads allowed)
			(copperpour allowed)
			(footprints allowed)
		)
		(placement
			(enabled no)
			(sheetname "")
		)
		(fill
			(thermal_gap 0.5)
			(thermal_bridge_width 0.5)
			(island_removal_mode 0)
		)
		(polygon
			(pts
				(xy 298.68622 -211.196936) (xy 298.68622 -210.64728) (xy 299.31614 -210.64728) (xy 299.31614 -211.196936)
			)
		)
	)
	(zone
		(layer "In11.Cu")
		(hatch none 0.5)
		(connect_pads
			(clearance 0)
		)
		(min_thickness 0.25)
		(keepout
			(tracks allowed)
			(vias allowed)
			(pads allowed)
			(copperpour allowed)
			(footprints allowed)
		)
		(placement
			(enabled no)
			(sheetname "")
		)
		(fill
			(thermal_gap 0.5)
			(thermal_bridge_width 0.5)
			(island_removal_mode 0)
		)
		(polygon
			(pts
				(xy 202.696318 -271.318482) (xy 202.696318 -271.042892) (xy 203.255118 -271.042892) (xy 203.255118 -271.318482)
				(xy 203.255118 -271.65935) (xy 202.696318 -271.65935)
			)
		)
	)
	(zone
		(layer "In11.Cu")
		(hatch none 0.5)
		(connect_pads
			(clearance 0)
		)
		(min_thickness 0.25)
		(keepout
			(tracks allowed)
			(vias allowed)
			(pads allowed)
			(copperpour allowed)
			(footprints allowed)
		)
		(placement
			(enabled no)
			(sheetname "")
		)
		(fill
			(thermal_gap 0.5)
			(thermal_bridge_width 0.5)
			(island_removal_mode 0)
		)
		(polygon
			(pts
				(xy 203.245974 -261.014718) (xy 203.245974 -261.290308) (xy 202.687174 -261.290308) (xy 202.687174 -261.014718)
			)
		)
	)
	(zone
		(layer "In11.Cu")
		(hatch none 0.5)
		(connect_pads
			(clearance 0)
		)
		(min_thickness 0.25)
		(keepout
			(tracks allowed)
			(vias allowed)
			(pads allowed)
			(copperpour allowed)
			(footprints allowed)
		)
		(placement
			(enabled no)
			(sheetname "")
		)
		(fill
			(thermal_gap 0.5)
			(thermal_bridge_width 0.5)
			(island_removal_mode 0)
		)
		(polygon
			(pts
				(xy 157.433518 -268.66596) (xy 157.992318 -268.66596) (xy 157.992318 -269.61846) (xy 157.433518 -269.61846)
				(xy 156.922978 -269.61846) (xy 156.922978 -268.66596)
			)
		)
	)
	(zone
		(layer "In11.Cu")
		(hatch none 0.5)
		(connect_pads
			(clearance 0)
		)
		(min_thickness 0.25)
		(keepout
			(tracks allowed)
			(vias allowed)
			(pads allowed)
			(copperpour allowed)
			(footprints allowed)
		)
		(placement
			(enabled no)
			(sheetname "")
		)
		(fill
			(thermal_gap 0.5)
			(thermal_bridge_width 0.5)
			(island_removal_mode 0)
		)
		(polygon
			(pts
				(xy 46.646084 -249.446796) (xy 46.646084 -248.89714) (xy 47.276004 -248.89714) (xy 47.276004 -249.446796)
			)
		)
	)
	(zone
		(layer "In11.Cu")
		(hatch none 0.5)
		(connect_pads
			(clearance 0)
		)
		(min_thickness 0.25)
		(keepout
			(tracks allowed)
			(vias allowed)
			(pads allowed)
			(copperpour allowed)
			(footprints allowed)
		)
		(placement
			(enabled no)
			(sheetname "")
		)
		(fill
			(thermal_gap 0.5)
			(thermal_bridge_width 0.5)
			(island_removal_mode 0)
		)
		(polygon
			(pts
				(xy 203.245974 -226.164648) (xy 203.245974 -226.440238) (xy 202.687174 -226.440238) (xy 202.687174 -226.164648)
			)
		)
	)
	(zone
		(layer "In11.Cu")
		(hatch none 0.5)
		(connect_pads
			(clearance 0)
		)
		(min_thickness 0.25)
		(keepout
			(tracks allowed)
			(vias allowed)
			(pads allowed)
			(copperpour allowed)
			(footprints allowed)
		)
		(placement
			(enabled no)
			(sheetname "")
		)
		(fill
			(thermal_gap 0.5)
			(thermal_bridge_width 0.5)
			(island_removal_mode 0)
		)
		(polygon
			(pts
				(xy 177.170842 -249.964702) (xy 177.170842 -250.240292) (xy 176.612042 -250.240292) (xy 176.612042 -249.964702)
			)
		)
	)
	(zone
		(layer "In11.Cu")
		(hatch none 0.5)
		(connect_pads
			(clearance 0)
		)
		(min_thickness 0.25)
		(keepout
			(tracks allowed)
			(vias allowed)
			(pads allowed)
			(copperpour allowed)
			(footprints allowed)
		)
		(placement
			(enabled no)
			(sheetname "")
		)
		(fill
			(thermal_gap 0.5)
			(thermal_bridge_width 0.5)
			(island_removal_mode 0)
		)
		(polygon
			(pts
				(xy 425.11091 -289.0647) (xy 425.11091 -289.34029) (xy 424.55211 -289.34029) (xy 424.55211 -289.0647)
			)
		)
	)
	(zone
		(layer "In11.Cu")
		(hatch none 0.5)
		(connect_pads
			(clearance 0)
		)
		(min_thickness 0.25)
		(keepout
			(tracks allowed)
			(vias allowed)
			(pads allowed)
			(copperpour allowed)
			(footprints allowed)
		)
		(placement
			(enabled no)
			(sheetname "")
		)
		(fill
			(thermal_gap 0.5)
			(thermal_bridge_width 0.5)
			(island_removal_mode 0)
		)
		(polygon
			(pts
				(xy 421.010842 -249.114818) (xy 421.010842 -249.390408) (xy 420.452042 -249.390408) (xy 420.452042 -249.114818)
			)
		)
	)
	(zone
		(layer "In11.Cu")
		(hatch none 0.5)
		(connect_pads
			(clearance 0)
		)
		(min_thickness 0.25)
		(keepout
			(tracks allowed)
			(vias allowed)
			(pads allowed)
			(copperpour allowed)
			(footprints allowed)
		)
		(placement
			(enabled no)
			(sheetname "")
		)
		(fill
			(thermal_gap 0.5)
			(thermal_bridge_width 0.5)
			(island_removal_mode 0)
		)
		(polygon
			(pts
				(xy 50.746152 -225.646742) (xy 50.746152 -225.097086) (xy 51.376072 -225.097086) (xy 51.376072 -225.646742)
			)
		)
	)
	(zone
		(layer "In11.Cu")
		(hatch none 0.5)
		(connect_pads
			(clearance 0)
		)
		(min_thickness 0.25)
		(keepout
			(tracks allowed)
			(vias allowed)
			(pads allowed)
			(copperpour allowed)
			(footprints allowed)
		)
		(placement
			(enabled no)
			(sheetname "")
		)
		(fill
			(thermal_gap 0.5)
			(thermal_bridge_width 0.5)
			(island_removal_mode 0)
		)
		(polygon
			(pts
				(xy 46.646084 -312.346848) (xy 46.646084 -311.797192) (xy 47.276004 -311.797192) (xy 47.276004 -312.346848)
			)
		)
	)
	(zone
		(layer "In11.Cu")
		(hatch none 0.5)
		(connect_pads
			(clearance 0)
		)
		(min_thickness 0.25)
		(keepout
			(tracks allowed)
			(vias allowed)
			(pads allowed)
			(copperpour allowed)
			(footprints allowed)
		)
		(placement
			(enabled no)
			(sheetname "")
		)
		(fill
			(thermal_gap 0.5)
			(thermal_bridge_width 0.5)
			(island_removal_mode 0)
		)
		(polygon
			(pts
				(xy 425.11091 -300.9646) (xy 425.11091 -301.24019) (xy 424.55211 -301.24019) (xy 424.55211 -300.9646)
			)
		)
	)
	(zone
		(layer "In11.Cu")
		(hatch none 0.5)
		(connect_pads
			(clearance 0)
		)
		(min_thickness 0.25)
		(keepout
			(tracks allowed)
			(vias allowed)
			(pads allowed)
			(copperpour allowed)
			(footprints allowed)
		)
		(placement
			(enabled no)
			(sheetname "")
		)
		(fill
			(thermal_gap 0.5)
			(thermal_bridge_width 0.5)
			(island_removal_mode 0)
		)
		(polygon
			(pts
				(xy 176.621186 -216.068402) (xy 176.621186 -215.792812) (xy 177.179986 -215.792812) (xy 177.179986 -216.068402)
			)
		)
	)
	(zone
		(layer "In11.Cu")
		(hatch none 0.5)
		(connect_pads
			(clearance 0)
		)
		(min_thickness 0.25)
		(keepout
			(tracks allowed)
			(vias allowed)
			(pads allowed)
			(copperpour allowed)
			(footprints allowed)
		)
		(placement
			(enabled no)
			(sheetname "")
		)
		(fill
			(thermal_gap 0.5)
			(thermal_bridge_width 0.5)
			(island_removal_mode 0)
		)
		(polygon
			(pts
				(xy 294.586152 -224.796858) (xy 294.586152 -224.247202) (xy 295.216072 -224.247202) (xy 295.216072 -224.796858)
			)
		)
	)
	(zone
		(layer "In11.Cu")
		(hatch none 0.5)
		(connect_pads
			(clearance 0)
		)
		(min_thickness 0.25)
		(keepout
			(tracks allowed)
			(vias allowed)
			(pads allowed)
			(copperpour allowed)
			(footprints allowed)
		)
		(placement
			(enabled no)
			(sheetname "")
		)
		(fill
			(thermal_gap 0.5)
			(thermal_bridge_width 0.5)
			(island_removal_mode 0)
		)
		(polygon
			(pts
				(xy 425.11091 -249.964702) (xy 425.11091 -250.240292) (xy 424.55211 -250.240292) (xy 424.55211 -249.964702)
			)
		)
	)
	(zone
		(layer "In11.Cu")
		(hatch none 0.5)
		(connect_pads
			(clearance 0)
		)
		(min_thickness 0.25)
		(keepout
			(tracks allowed)
			(vias allowed)
			(pads allowed)
			(copperpour allowed)
			(footprints allowed)
		)
		(placement
			(enabled no)
			(sheetname "")
		)
		(fill
			(thermal_gap 0.5)
			(thermal_bridge_width 0.5)
			(island_removal_mode 0)
		)
		(polygon
			(pts
				(xy 450.636386 -271.318482) (xy 450.636386 -271.042892) (xy 451.195186 -271.042892) (xy 451.195186 -271.318482)
				(xy 451.195186 -271.65935) (xy 450.636386 -271.65935)
			)
		)
	)
	(zone
		(layer "In11.Cu")
		(hatch none 0.5)
		(connect_pads
			(clearance 0)
		)
		(min_thickness 0.25)
		(keepout
			(tracks allowed)
			(vias allowed)
			(pads allowed)
			(copperpour allowed)
			(footprints allowed)
		)
		(placement
			(enabled no)
			(sheetname "")
		)
		(fill
			(thermal_gap 0.5)
			(thermal_bridge_width 0.5)
			(island_removal_mode 0)
		)
		(polygon
			(pts
				(xy 451.186042 -290.764722) (xy 451.186042 -291.040312) (xy 450.627242 -291.040312) (xy 450.627242 -290.764722)
			)
		)
	)
	(zone
		(layer "In11.Cu")
		(hatch none 0.5)
		(connect_pads
			(clearance 0)
		)
		(min_thickness 0.25)
		(keepout
			(tracks allowed)
			(vias allowed)
			(pads allowed)
			(copperpour allowed)
			(footprints allowed)
		)
		(placement
			(enabled no)
			(sheetname "")
		)
		(fill
			(thermal_gap 0.5)
			(thermal_bridge_width 0.5)
			(island_removal_mode 0)
		)
		(polygon
			(pts
				(xy 283.636212 -267.319506) (xy 283.636212 -266.737846) (xy 284.195012 -266.737846) (xy 284.195012 -267.319506)
			)
		)
	)
	(zone
		(layer "In11.Cu")
		(hatch none 0.5)
		(connect_pads
			(clearance 0)
		)
		(min_thickness 0.25)
		(keepout
			(tracks allowed)
			(vias allowed)
			(pads allowed)
			(copperpour allowed)
			(footprints allowed)
		)
		(placement
			(enabled no)
			(sheetname "")
		)
		(fill
			(thermal_gap 0.5)
			(thermal_bridge_width 0.5)
			(island_removal_mode 0)
		)
		(polygon
			(pts
				(xy 425.11091 -307.764688) (xy 425.11091 -308.040278) (xy 424.55211 -308.040278) (xy 424.55211 -307.764688)
			)
		)
	)
	(zone
		(layer "In11.Cu")
		(hatch none 0.5)
		(connect_pads
			(clearance 0)
		)
		(min_thickness 0.25)
		(keepout
			(tracks allowed)
			(vias allowed)
			(pads allowed)
			(copperpour allowed)
			(footprints allowed)
		)
		(placement
			(enabled no)
			(sheetname "")
		)
		(fill
			(thermal_gap 0.5)
			(thermal_bridge_width 0.5)
			(island_removal_mode 0)
		)
		(polygon
			(pts
				(xy 424.561254 -229.668578) (xy 424.561254 -229.392988) (xy 425.120054 -229.392988) (xy 425.120054 -229.668578)
			)
		)
	)
	(zone
		(layer "In11.Cu")
		(hatch none 0.5)
		(connect_pads
			(clearance 0)
		)
		(min_thickness 0.25)
		(keepout
			(tracks allowed)
			(vias allowed)
			(pads allowed)
			(copperpour allowed)
			(footprints allowed)
		)
		(placement
			(enabled no)
			(sheetname "")
		)
		(fill
			(thermal_gap 0.5)
			(thermal_bridge_width 0.5)
			(island_removal_mode 0)
		)
		(polygon
			(pts
				(xy 46.646084 -200.14692) (xy 46.646084 -199.597264) (xy 47.276004 -199.597264) (xy 47.276004 -200.14692)
			)
		)
	)
	(zone
		(layer "In11.Cu")
		(hatch none 0.5)
		(connect_pads
			(clearance 0)
		)
		(min_thickness 0.25)
		(keepout
			(tracks allowed)
			(vias allowed)
			(pads allowed)
			(copperpour allowed)
			(footprints allowed)
		)
		(placement
			(enabled no)
			(sheetname "")
		)
		(fill
			(thermal_gap 0.5)
			(thermal_bridge_width 0.5)
			(island_removal_mode 0)
		)
		(polygon
			(pts
				(xy 420.461186 -293.418514) (xy 420.461186 -293.142924) (xy 421.019986 -293.142924) (xy 421.019986 -293.418514)
			)
		)
	)
	(zone
		(layer "In11.Cu")
		(hatch none 0.5)
		(connect_pads
			(clearance 0)
		)
		(min_thickness 0.25)
		(keepout
			(tracks allowed)
			(vias allowed)
			(pads allowed)
			(copperpour allowed)
			(footprints allowed)
		)
		(placement
			(enabled no)
			(sheetname "")
		)
		(fill
			(thermal_gap 0.5)
			(thermal_bridge_width 0.5)
			(island_removal_mode 0)
		)
		(polygon
			(pts
				(xy 268.558518 -297.042332) (xy 268.558518 -296.502074) (xy 269.126462 -296.502074) (xy 269.426944 -296.502074)
				(xy 269.531084 -296.606214) (xy 269.531084 -296.871644) (xy 269.360396 -297.042332) (xy 269.117318 -297.042332)
			)
		)
	)
	(zone
		(layer "In11.Cu")
		(hatch none 0.5)
		(connect_pads
			(clearance 0)
		)
		(min_thickness 0.25)
		(keepout
			(tracks allowed)
			(vias allowed)
			(pads allowed)
			(copperpour allowed)
			(footprints allowed)
		)
		(placement
			(enabled no)
			(sheetname "")
		)
		(fill
			(thermal_gap 0.5)
			(thermal_bridge_width 0.5)
			(island_removal_mode 0)
		)
		(polygon
			(pts
				(xy 298.71162 -292.796976) (xy 298.71162 -292.24732) (xy 299.34154 -292.24732) (xy 299.34154 -292.796976)
			)
		)
	)
	(zone
		(layer "In11.Cu")
		(hatch none 0.5)
		(connect_pads
			(clearance 0)
		)
		(min_thickness 0.25)
		(keepout
			(tracks allowed)
			(vias allowed)
			(pads allowed)
			(copperpour allowed)
			(footprints allowed)
		)
		(placement
			(enabled no)
			(sheetname "")
		)
		(fill
			(thermal_gap 0.5)
			(thermal_bridge_width 0.5)
			(island_removal_mode 0)
		)
		(polygon
			(pts
				(xy 420.461186 -272.16862) (xy 420.461186 -271.89303) (xy 421.019986 -271.89303) (xy 421.019986 -272.16862)
			)
		)
	)
	(zone
		(layer "In11.Cu")
		(hatch none 0.5)
		(connect_pads
			(clearance 0)
		)
		(min_thickness 0.25)
		(keepout
			(tracks allowed)
			(vias allowed)
			(pads allowed)
			(copperpour allowed)
			(footprints allowed)
		)
		(placement
			(enabled no)
			(sheetname "")
		)
		(fill
			(thermal_gap 0.5)
			(thermal_bridge_width 0.5)
			(island_removal_mode 0)
		)
		(polygon
			(pts
				(xy 421.010842 -289.914838) (xy 421.010842 -290.190428) (xy 420.452042 -290.190428) (xy 420.452042 -289.914838)
			)
		)
	)
	(zone
		(layer "In11.Cu")
		(hatch none 0.5)
		(connect_pads
			(clearance 0)
		)
		(min_thickness 0.25)
		(keepout
			(tracks allowed)
			(vias allowed)
			(pads allowed)
			(copperpour allowed)
			(footprints allowed)
		)
		(placement
			(enabled no)
			(sheetname "")
		)
		(fill
			(thermal_gap 0.5)
			(thermal_bridge_width 0.5)
			(island_removal_mode 0)
		)
		(polygon
			(pts
				(xy 294.586152 -204.396848) (xy 294.586152 -203.847192) (xy 295.216072 -203.847192) (xy 295.216072 -204.396848)
			)
		)
	)
	(zone
		(layer "In11.Cu")
		(hatch none 0.5)
		(connect_pads
			(clearance 0)
		)
		(min_thickness 0.25)
		(keepout
			(tracks allowed)
			(vias allowed)
			(pads allowed)
			(copperpour allowed)
			(footprints allowed)
		)
		(placement
			(enabled no)
			(sheetname "")
		)
		(fill
			(thermal_gap 0.5)
			(thermal_bridge_width 0.5)
			(island_removal_mode 0)
		)
		(polygon
			(pts
				(xy 268.569186 -250.297696) (xy 268.569186 -249.749056) (xy 269.094966 -249.749056) (xy 269.094966 -250.297696)
			)
		)
	)
	(zone
		(layer "In11.Cu")
		(hatch none 0.5)
		(connect_pads
			(clearance 0)
		)
		(min_thickness 0.25)
		(keepout
			(tracks allowed)
			(vias allowed)
			(pads allowed)
			(copperpour allowed)
			(footprints allowed)
		)
		(placement
			(enabled no)
			(sheetname "")
		)
		(fill
			(thermal_gap 0.5)
			(thermal_bridge_width 0.5)
			(island_removal_mode 0)
		)
		(polygon
			(pts
				(xy 188.158374 -261.014718) (xy 188.158374 -261.290308) (xy 187.599574 -261.290308) (xy 187.599574 -261.014718)
			)
		)
	)
	(zone
		(layer "In11.Cu")
		(hatch none 0.5)
		(connect_pads
			(clearance 0)
		)
		(min_thickness 0.25)
		(keepout
			(tracks allowed)
			(vias allowed)
			(pads allowed)
			(copperpour allowed)
			(footprints allowed)
		)
		(placement
			(enabled no)
			(sheetname "")
		)
		(fill
			(thermal_gap 0.5)
			(thermal_bridge_width 0.5)
			(island_removal_mode 0)
		)
		(polygon
			(pts
				(xy 425.11091 -224.464626) (xy 425.11091 -224.740216) (xy 424.55211 -224.740216) (xy 424.55211 -224.464626)
			)
		)
	)
	(zone
		(layer "In11.Cu")
		(hatch none 0.5)
		(connect_pads
			(clearance 0)
		)
		(min_thickness 0.25)
		(keepout
			(tracks allowed)
			(vias allowed)
			(pads allowed)
			(copperpour allowed)
			(footprints allowed)
		)
		(placement
			(enabled no)
			(sheetname "")
		)
		(fill
			(thermal_gap 0.5)
			(thermal_bridge_width 0.5)
			(island_removal_mode 0)
		)
		(polygon
			(pts
				(xy 177.170842 -238.064802) (xy 177.170842 -238.340392) (xy 176.612042 -238.340392) (xy 176.612042 -238.064802)
			)
		)
	)
	(zone
		(layer "In11.Cu")
		(hatch none 0.5)
		(connect_pads
			(clearance 0)
		)
		(min_thickness 0.25)
		(keepout
			(tracks allowed)
			(vias allowed)
			(pads allowed)
			(copperpour allowed)
			(footprints allowed)
		)
		(placement
			(enabled no)
			(sheetname "")
		)
		(fill
			(thermal_gap 0.5)
			(thermal_bridge_width 0.5)
			(island_removal_mode 0)
		)
		(polygon
			(pts
				(xy 202.696318 -277.268432) (xy 202.696318 -276.992842) (xy 203.255118 -276.992842) (xy 203.255118 -277.268432)
			)
		)
	)
	(zone
		(layer "In11.Cu")
		(hatch none 0.5)
		(connect_pads
			(clearance 0)
		)
		(min_thickness 0.25)
		(keepout
			(tracks allowed)
			(vias allowed)
			(pads allowed)
			(copperpour allowed)
			(footprints allowed)
		)
		(placement
			(enabled no)
			(sheetname "")
		)
		(fill
			(thermal_gap 0.5)
			(thermal_bridge_width 0.5)
			(island_removal_mode 0)
		)
		(polygon
			(pts
				(xy 173.070774 -305.214782) (xy 173.070774 -305.490372) (xy 172.511974 -305.490372) (xy 172.511974 -305.214782)
			)
		)
	)
	(zone
		(layer "In11.Cu")
		(hatch none 0.5)
		(connect_pads
			(clearance 0)
		)
		(min_thickness 0.25)
		(keepout
			(tracks allowed)
			(vias allowed)
			(pads allowed)
			(copperpour allowed)
			(footprints allowed)
		)
		(placement
			(enabled no)
			(sheetname "")
		)
		(fill
			(thermal_gap 0.5)
			(thermal_bridge_width 0.5)
			(island_removal_mode 0)
		)
		(polygon
			(pts
				(xy 449.961254 -271.318482) (xy 449.402454 -271.318482) (xy 448.99961 -271.318482) (xy 448.99961 -270.536162)
				(xy 450.302884 -270.536162) (xy 450.302884 -271.318482)
			)
		)
	)
	(zone
		(layer "In11.Cu")
		(hatch none 0.5)
		(connect_pads
			(clearance 0)
		)
		(min_thickness 0.25)
		(keepout
			(tracks allowed)
			(vias allowed)
			(pads allowed)
			(copperpour allowed)
			(footprints allowed)
		)
		(placement
			(enabled no)
			(sheetname "")
		)
		(fill
			(thermal_gap 0.5)
			(thermal_bridge_width 0.5)
			(island_removal_mode 0)
		)
		(polygon
			(pts
				(xy 177.170842 -232.114852) (xy 177.170842 -232.390442) (xy 176.612042 -232.390442) (xy 176.612042 -232.114852)
			)
		)
	)
	(zone
		(layer "In11.Cu")
		(hatch none 0.5)
		(connect_pads
			(clearance 0)
		)
		(min_thickness 0.25)
		(keepout
			(tracks allowed)
			(vias allowed)
			(pads allowed)
			(copperpour allowed)
			(footprints allowed)
		)
		(placement
			(enabled no)
			(sheetname "")
		)
		(fill
			(thermal_gap 0.5)
			(thermal_bridge_width 0.5)
			(island_removal_mode 0)
		)
		(polygon
			(pts
				(xy 298.68622 -197.59676) (xy 298.68622 -197.047104) (xy 299.31614 -197.047104) (xy 299.31614 -197.59676)
			)
		)
	)
	(zone
		(layer "In11.Cu")
		(hatch none 0.5)
		(connect_pads
			(clearance 0)
		)
		(min_thickness 0.25)
		(keepout
			(tracks allowed)
			(vias allowed)
			(pads allowed)
			(copperpour allowed)
			(footprints allowed)
		)
		(placement
			(enabled no)
			(sheetname "")
		)
		(fill
			(thermal_gap 0.5)
			(thermal_bridge_width 0.5)
			(island_removal_mode 0)
		)
		(polygon
			(pts
				(xy 424.561254 -284.918404) (xy 424.561254 -284.642814) (xy 425.120054 -284.642814) (xy 425.120054 -284.918404)
			)
		)
	)
	(zone
		(layer "In11.Cu")
		(hatch none 0.5)
		(connect_pads
			(clearance 0)
		)
		(min_thickness 0.25)
		(keepout
			(tracks allowed)
			(vias allowed)
			(pads allowed)
			(copperpour allowed)
			(footprints allowed)
		)
		(placement
			(enabled no)
			(sheetname "")
		)
		(fill
			(thermal_gap 0.5)
			(thermal_bridge_width 0.5)
			(island_removal_mode 0)
		)
		(polygon
			(pts
				(xy 202.696318 -273.868388) (xy 202.696318 -273.592798) (xy 203.255118 -273.592798) (xy 203.255118 -273.868388)
			)
		)
	)
	(zone
		(layer "In11.Cu")
		(hatch none 0.5)
		(connect_pads
			(clearance 0)
		)
		(min_thickness 0.25)
		(keepout
			(tracks allowed)
			(vias allowed)
			(pads allowed)
			(copperpour allowed)
			(footprints allowed)
		)
		(placement
			(enabled no)
			(sheetname "")
		)
		(fill
			(thermal_gap 0.5)
			(thermal_bridge_width 0.5)
			(island_removal_mode 0)
		)
		(polygon
			(pts
				(xy 172.521118 -205.018386) (xy 172.521118 -204.742796) (xy 173.079918 -204.742796) (xy 173.079918 -205.018386)
			)
		)
	)
	(zone
		(layer "In11.Cu")
		(hatch none 0.5)
		(connect_pads
			(clearance 0)
		)
		(min_thickness 0.25)
		(keepout
			(tracks allowed)
			(vias allowed)
			(pads allowed)
			(copperpour allowed)
			(footprints allowed)
		)
		(placement
			(enabled no)
			(sheetname "")
		)
		(fill
			(thermal_gap 0.5)
			(thermal_bridge_width 0.5)
			(island_removal_mode 0)
		)
		(polygon
			(pts
				(xy 425.11091 -314.564776) (xy 425.11091 -314.840366) (xy 424.55211 -314.840366) (xy 424.55211 -314.564776)
			)
		)
	)
	(zone
		(layer "In11.Cu")
		(hatch none 0.5)
		(connect_pads
			(clearance 0)
		)
		(min_thickness 0.25)
		(keepout
			(tracks allowed)
			(vias allowed)
			(pads allowed)
			(copperpour allowed)
			(footprints allowed)
		)
		(placement
			(enabled no)
			(sheetname "")
		)
		(fill
			(thermal_gap 0.5)
			(thermal_bridge_width 0.5)
			(island_removal_mode 0)
		)
		(polygon
			(pts
				(xy 172.521118 -309.568596) (xy 172.521118 -309.293006) (xy 173.079918 -309.293006) (xy 173.079918 -309.568596)
			)
		)
	)
	(zone
		(layer "In11.Cu")
		(hatch none 0.5)
		(connect_pads
			(clearance 0)
		)
		(min_thickness 0.25)
		(keepout
			(tracks allowed)
			(vias allowed)
			(pads allowed)
			(copperpour allowed)
			(footprints allowed)
		)
		(placement
			(enabled no)
			(sheetname "")
		)
		(fill
			(thermal_gap 0.5)
			(thermal_bridge_width 0.5)
			(island_removal_mode 0)
		)
		(polygon
			(pts
				(xy 436.098442 -307.764688) (xy 436.098442 -308.040278) (xy 435.539642 -308.040278) (xy 435.539642 -307.764688)
			)
		)
	)
	(zone
		(layer "In11.Cu")
		(hatch none 0.5)
		(connect_pads
			(clearance 0)
		)
		(min_thickness 0.25)
		(keepout
			(tracks allowed)
			(vias allowed)
			(pads allowed)
			(copperpour allowed)
			(footprints allowed)
		)
		(placement
			(enabled no)
			(sheetname "")
		)
		(fill
			(thermal_gap 0.5)
			(thermal_bridge_width 0.5)
			(island_removal_mode 0)
		)
		(polygon
			(pts
				(xy 202.696318 -201.618596) (xy 202.696318 -201.343006) (xy 203.255118 -201.343006) (xy 203.255118 -201.618596)
			)
		)
	)
	(zone
		(layer "In11.Cu")
		(hatch none 0.5)
		(connect_pads
			(clearance 0)
		)
		(min_thickness 0.25)
		(keepout
			(tracks allowed)
			(vias allowed)
			(pads allowed)
			(copperpour allowed)
			(footprints allowed)
		)
		(placement
			(enabled no)
			(sheetname "")
		)
		(fill
			(thermal_gap 0.5)
			(thermal_bridge_width 0.5)
			(island_removal_mode 0)
		)
		(polygon
			(pts
				(xy 420.461186 -215.218518) (xy 420.461186 -214.942928) (xy 421.019986 -214.942928) (xy 421.019986 -215.218518)
			)
		)
	)
	(zone
		(layer "In11.Cu")
		(hatch none 0.5)
		(connect_pads
			(clearance 0)
		)
		(min_thickness 0.25)
		(keepout
			(tracks allowed)
			(vias allowed)
			(pads allowed)
			(copperpour allowed)
			(footprints allowed)
		)
		(placement
			(enabled no)
			(sheetname "")
		)
		(fill
			(thermal_gap 0.5)
			(thermal_bridge_width 0.5)
			(island_removal_mode 0)
		)
		(polygon
			(pts
				(xy 451.186042 -226.164648) (xy 451.186042 -226.440238) (xy 450.627242 -226.440238) (xy 450.627242 -226.164648)
			)
		)
	)
	(zone
		(layer "In11.Cu")
		(hatch none 0.5)
		(connect_pads
			(clearance 0)
		)
		(min_thickness 0.25)
		(keepout
			(tracks allowed)
			(vias allowed)
			(pads allowed)
			(copperpour allowed)
			(footprints allowed)
		)
		(placement
			(enabled no)
			(sheetname "")
		)
		(fill
			(thermal_gap 0.5)
			(thermal_bridge_width 0.5)
			(island_removal_mode 0)
		)
		(polygon
			(pts
				(xy 46.646084 -285.14675) (xy 46.646084 -284.597094) (xy 47.276004 -284.597094) (xy 47.276004 -285.14675)
			)
		)
	)
	(zone
		(layer "In11.Cu")
		(hatch none 0.5)
		(connect_pads
			(clearance 0)
		)
		(min_thickness 0.25)
		(keepout
			(tracks allowed)
			(vias allowed)
			(pads allowed)
			(copperpour allowed)
			(footprints allowed)
		)
		(placement
			(enabled no)
			(sheetname "")
		)
		(fill
			(thermal_gap 0.5)
			(thermal_bridge_width 0.5)
			(island_removal_mode 0)
		)
		(polygon
			(pts
				(xy 20.570952 -201.846942) (xy 20.570952 -201.297286) (xy 21.200872 -201.297286) (xy 21.200872 -201.846942)
			)
		)
	)
	(zone
		(layer "In11.Cu")
		(hatch none 0.5)
		(connect_pads
			(clearance 0)
		)
		(min_thickness 0.25)
		(keepout
			(tracks allowed)
			(vias allowed)
			(pads allowed)
			(copperpour allowed)
			(footprints allowed)
		)
		(placement
			(enabled no)
			(sheetname "")
		)
		(fill
			(thermal_gap 0.5)
			(thermal_bridge_width 0.5)
			(island_removal_mode 0)
		)
		(polygon
			(pts
				(xy 184.714642 -258.464812) (xy 184.714642 -258.740402) (xy 184.155842 -258.740402) (xy 184.155842 -258.464812)
			)
		)
	)
	(zone
		(layer "In11.Cu")
		(hatch none 0.5)
		(connect_pads
			(clearance 0)
		)
		(min_thickness 0.25)
		(keepout
			(tracks allowed)
			(vias allowed)
			(pads allowed)
			(copperpour allowed)
			(footprints allowed)
		)
		(placement
			(enabled no)
			(sheetname "")
		)
		(fill
			(thermal_gap 0.5)
			(thermal_bridge_width 0.5)
			(island_removal_mode 0)
		)
		(polygon
			(pts
				(xy 440.19851 -307.764688) (xy 440.19851 -308.040278) (xy 439.63971 -308.040278) (xy 439.63971 -307.764688)
			)
		)
	)
	(zone
		(layer "In11.Cu")
		(hatch none 0.5)
		(connect_pads
			(clearance 0)
		)
		(min_thickness 0.25)
		(keepout
			(tracks allowed)
			(vias allowed)
			(pads allowed)
			(copperpour allowed)
			(footprints allowed)
		)
		(placement
			(enabled no)
			(sheetname "")
		)
		(fill
			(thermal_gap 0.5)
			(thermal_bridge_width 0.5)
			(island_removal_mode 0)
		)
		(polygon
			(pts
				(xy 176.621186 -310.41848) (xy 176.621186 -310.14289) (xy 177.179986 -310.14289) (xy 177.179986 -310.41848)
			)
		)
	)
	(zone
		(layer "In11.Cu")
		(hatch none 0.5)
		(connect_pads
			(clearance 0)
		)
		(min_thickness 0.25)
		(keepout
			(tracks allowed)
			(vias allowed)
			(pads allowed)
			(copperpour allowed)
			(footprints allowed)
		)
		(placement
			(enabled no)
			(sheetname "")
		)
		(fill
			(thermal_gap 0.5)
			(thermal_bridge_width 0.5)
			(island_removal_mode 0)
		)
		(polygon
			(pts
				(xy 451.186042 -236.36478) (xy 451.186042 -236.64037) (xy 450.627242 -236.64037) (xy 450.627242 -236.36478)
			)
		)
	)
	(zone
		(layer "In11.Cu")
		(hatch none 0.5)
		(connect_pads
			(clearance 0)
		)
		(min_thickness 0.25)
		(keepout
			(tracks allowed)
			(vias allowed)
			(pads allowed)
			(copperpour allowed)
			(footprints allowed)
		)
		(placement
			(enabled no)
			(sheetname "")
		)
		(fill
			(thermal_gap 0.5)
			(thermal_bridge_width 0.5)
			(island_removal_mode 0)
		)
		(polygon
			(pts
				(xy 440.19851 -281.414728) (xy 440.19851 -281.690318) (xy 439.63971 -281.690318) (xy 439.63971 -281.414728)
			)
		)
	)
	(zone
		(layer "In11.Cu")
		(hatch none 0.5)
		(connect_pads
			(clearance 0)
		)
		(min_thickness 0.25)
		(keepout
			(tracks allowed)
			(vias allowed)
			(pads allowed)
			(copperpour allowed)
			(footprints allowed)
		)
		(placement
			(enabled no)
			(sheetname "")
		)
		(fill
			(thermal_gap 0.5)
			(thermal_bridge_width 0.5)
			(island_removal_mode 0)
		)
		(polygon
			(pts
				(xy 440.19851 -278.864822) (xy 440.19851 -279.140412) (xy 439.63971 -279.140412) (xy 439.63971 -278.864822)
			)
		)
	)
	(zone
		(layer "In11.Cu")
		(hatch none 0.5)
		(connect_pads
			(clearance 0)
		)
		(min_thickness 0.25)
		(keepout
			(tracks allowed)
			(vias allowed)
			(pads allowed)
			(copperpour allowed)
			(footprints allowed)
		)
		(placement
			(enabled no)
			(sheetname "")
		)
		(fill
			(thermal_gap 0.5)
			(thermal_bridge_width 0.5)
			(island_removal_mode 0)
		)
		(polygon
			(pts
				(xy 46.646084 -266.446762) (xy 46.646084 -265.897106) (xy 47.276004 -265.897106) (xy 47.276004 -266.446762)
			)
		)
	)
	(zone
		(layer "In11.Cu")
		(hatch none 0.5)
		(connect_pads
			(clearance 0)
		)
		(min_thickness 0.25)
		(keepout
			(tracks allowed)
			(vias allowed)
			(pads allowed)
			(copperpour allowed)
			(footprints allowed)
		)
		(placement
			(enabled no)
			(sheetname "")
		)
		(fill
			(thermal_gap 0.5)
			(thermal_bridge_width 0.5)
			(island_removal_mode 0)
		)
		(polygon
			(pts
				(xy 294.586152 -232.44683) (xy 294.586152 -231.897174) (xy 295.216072 -231.897174) (xy 295.216072 -232.44683)
			)
		)
	)
	(zone
		(layer "In11.Cu")
		(hatch none 0.5)
		(connect_pads
			(clearance 0)
		)
		(min_thickness 0.25)
		(keepout
			(tracks allowed)
			(vias allowed)
			(pads allowed)
			(copperpour allowed)
			(footprints allowed)
		)
		(placement
			(enabled no)
			(sheetname "")
		)
		(fill
			(thermal_gap 0.5)
			(thermal_bridge_width 0.5)
			(island_removal_mode 0)
		)
		(polygon
			(pts
				(xy 424.561254 -266.218416) (xy 424.561254 -265.942826) (xy 425.120054 -265.942826) (xy 425.120054 -266.218416)
			)
		)
	)
	(zone
		(layer "In11.Cu")
		(hatch none 0.5)
		(connect_pads
			(clearance 0)
		)
		(min_thickness 0.25)
		(keepout
			(tracks allowed)
			(vias allowed)
			(pads allowed)
			(copperpour allowed)
			(footprints allowed)
		)
		(placement
			(enabled no)
			(sheetname "")
		)
		(fill
			(thermal_gap 0.5)
			(thermal_bridge_width 0.5)
			(island_removal_mode 0)
		)
		(polygon
			(pts
				(xy 268.51102 -225.646742) (xy 268.51102 -225.097086) (xy 269.14094 -225.097086) (xy 269.14094 -225.646742)
			)
		)
	)
	(zone
		(layer "In11.Cu")
		(hatch none 0.5)
		(connect_pads
			(clearance 0)
		)
		(min_thickness 0.25)
		(keepout
			(tracks allowed)
			(vias allowed)
			(pads allowed)
			(copperpour allowed)
			(footprints allowed)
		)
		(placement
			(enabled no)
			(sheetname "")
		)
		(fill
			(thermal_gap 0.5)
			(thermal_bridge_width 0.5)
			(island_removal_mode 0)
		)
		(polygon
			(pts
				(xy 421.010842 -292.464744) (xy 421.010842 -292.740334) (xy 420.452042 -292.740334) (xy 420.452042 -292.464744)
			)
		)
	)
	(zone
		(layer "In11.Cu")
		(hatch none 0.5)
		(connect_pads
			(clearance 0)
		)
		(min_thickness 0.25)
		(keepout
			(tracks allowed)
			(vias allowed)
			(pads allowed)
			(copperpour allowed)
			(footprints allowed)
		)
		(placement
			(enabled no)
			(sheetname "")
		)
		(fill
			(thermal_gap 0.5)
			(thermal_bridge_width 0.5)
			(island_removal_mode 0)
		)
		(polygon
			(pts
				(xy 176.621186 -214.36838) (xy 176.621186 -214.09279) (xy 177.179986 -214.09279) (xy 177.179986 -214.36838)
			)
		)
	)
	(zone
		(layer "In11.Cu")
		(hatch none 0.5)
		(connect_pads
			(clearance 0)
		)
		(min_thickness 0.25)
		(keepout
			(tracks allowed)
			(vias allowed)
			(pads allowed)
			(copperpour allowed)
			(footprints allowed)
		)
		(placement
			(enabled no)
			(sheetname "")
		)
		(fill
			(thermal_gap 0.5)
			(thermal_bridge_width 0.5)
			(island_removal_mode 0)
		)
		(polygon
			(pts
				(xy 177.170842 -270.364712) (xy 177.170842 -270.640302) (xy 176.612042 -270.640302) (xy 176.612042 -270.364712)
			)
		)
	)
	(zone
		(layer "In11.Cu")
		(hatch none 0.5)
		(connect_pads
			(clearance 0)
		)
		(min_thickness 0.25)
		(keepout
			(tracks allowed)
			(vias allowed)
			(pads allowed)
			(copperpour allowed)
			(footprints allowed)
		)
		(placement
			(enabled no)
			(sheetname "")
		)
		(fill
			(thermal_gap 0.5)
			(thermal_bridge_width 0.5)
			(island_removal_mode 0)
		)
		(polygon
			(pts
				(xy 46.646084 -234.146852) (xy 46.646084 -233.597196) (xy 47.276004 -233.597196) (xy 47.276004 -234.146852)
			)
		)
	)
	(zone
		(layer "In11.Cu")
		(hatch none 0.5)
		(connect_pads
			(clearance 0)
		)
		(min_thickness 0.25)
		(keepout
			(tracks allowed)
			(vias allowed)
			(pads allowed)
			(copperpour allowed)
			(footprints allowed)
		)
		(placement
			(enabled no)
			(sheetname "")
		)
		(fill
			(thermal_gap 0.5)
			(thermal_bridge_width 0.5)
			(island_removal_mode 0)
		)
		(polygon
			(pts
				(xy 424.561254 -303.618392) (xy 424.561254 -303.342802) (xy 425.120054 -303.342802) (xy 425.120054 -303.618392)
			)
		)
	)
	(zone
		(layer "In11.Cu")
		(hatch none 0.5)
		(connect_pads
			(clearance 0)
		)
		(min_thickness 0.25)
		(keepout
			(tracks allowed)
			(vias allowed)
			(pads allowed)
			(copperpour allowed)
			(footprints allowed)
		)
		(placement
			(enabled no)
			(sheetname "")
		)
		(fill
			(thermal_gap 0.5)
			(thermal_bridge_width 0.5)
			(island_removal_mode 0)
		)
		(polygon
			(pts
				(xy 298.68622 -216.296748) (xy 298.68622 -215.747092) (xy 299.31614 -215.747092) (xy 299.31614 -216.296748)
			)
		)
	)
	(zone
		(layer "In11.Cu")
		(hatch none 0.5)
		(connect_pads
			(clearance 0)
		)
		(min_thickness 0.25)
		(keepout
			(tracks allowed)
			(vias allowed)
			(pads allowed)
			(copperpour allowed)
			(footprints allowed)
		)
		(placement
			(enabled no)
			(sheetname "")
		)
		(fill
			(thermal_gap 0.5)
			(thermal_bridge_width 0.5)
			(island_removal_mode 0)
		)
		(polygon
			(pts
				(xy 294.586152 -293.64686) (xy 294.586152 -293.097204) (xy 295.216072 -293.097204) (xy 295.216072 -293.64686)
			)
		)
	)
	(zone
		(layer "In11.Cu")
		(hatch none 0.5)
		(connect_pads
			(clearance 0)
		)
		(min_thickness 0.25)
		(keepout
			(tracks allowed)
			(vias allowed)
			(pads allowed)
			(copperpour allowed)
			(footprints allowed)
		)
		(placement
			(enabled no)
			(sheetname "")
		)
		(fill
			(thermal_gap 0.5)
			(thermal_bridge_width 0.5)
			(island_removal_mode 0)
		)
		(polygon
			(pts
				(xy 202.696318 -289.74288) (xy 203.255118 -289.74288) (xy 203.255118 -290.01847) (xy 203.255118 -290.385754)
				(xy 202.328526 -290.385754) (xy 202.328526 -289.74288)
			)
		)
	)
	(zone
		(layer "In11.Cu")
		(hatch none 0.5)
		(connect_pads
			(clearance 0)
		)
		(min_thickness 0.25)
		(keepout
			(tracks allowed)
			(vias allowed)
			(pads allowed)
			(copperpour allowed)
			(footprints allowed)
		)
		(placement
			(enabled no)
			(sheetname "")
		)
		(fill
			(thermal_gap 0.5)
			(thermal_bridge_width 0.5)
			(island_removal_mode 0)
		)
		(polygon
			(pts
				(xy 120.32488 -361.551728) (xy 121.99112 -361.551728) (xy 122.301 -361.241848) (xy 122.301 -359.423208)
				(xy 121.96826 -359.090468) (xy 121.96826 -357.279448) (xy 122.44578 -356.801928) (xy 122.44578 -352.656648)
				(xy 124.85878 -350.243648) (xy 131.73964 -350.243648) (xy 132.4356 -350.939608) (xy 136.91616 -350.939608)
				(xy 137.4267 -350.429068) (xy 143.86052 -350.429068) (xy 147.17776 -347.111828) (xy 147.17776 -343.837768)
				(xy 148.92274 -342.092788) (xy 148.92274 -323.337428) (xy 148.39442 -322.809108) (xy 147.02028 -322.809108)
				(xy 146.6469 -323.182488) (xy 146.6469 -342.021668) (xy 145.9611 -342.707468) (xy 145.9611 -344.183208)
				(xy 145.62836 -344.515948) (xy 145.62836 -346.159328) (xy 142.92834 -348.859348) (xy 123.65228 -348.859348)
				(xy 120.03532 -352.476308) (xy 120.03532 -361.262168)
			)
		)
	)
	(zone
		(layer "In11.Cu")
		(hatch none 0.5)
		(connect_pads
			(clearance 0)
		)
		(min_thickness 0.25)
		(keepout
			(tracks not_allowed)
			(vias allowed)
			(pads allowed)
			(copperpour not_allowed)
			(footprints allowed)
		)
		(placement
			(enabled no)
			(sheetname "")
		)
		(fill
			(thermal_gap 0.5)
			(thermal_bridge_width 0.5)
			(island_removal_mode 0)
		)
		(polygon
			(pts
				(arc
					(start 144.242028 -428.960788)
					(mid 144.264346 -429.01467)
					(end 144.318228 -429.036988)
				)
				(arc
					(start 145.258028 -429.036988)
					(mid 145.31191 -429.01467)
					(end 145.334228 -428.960788)
				)
				(arc
					(start 145.334228 -426.419264)
					(mid 145.31191 -426.365382)
					(end 145.258028 -426.343064)
				)
				(arc
					(start 144.318228 -426.343064)
					(mid 144.264346 -426.365382)
					(end 144.242028 -426.419264)
				)
			)
		)
	)
	(zone
		(layer "In11.Cu")
		(hatch none 0.5)
		(connect_pads
			(clearance 0)
		)
		(min_thickness 0.25)
		(keepout
			(tracks allowed)
			(vias allowed)
			(pads allowed)
			(copperpour allowed)
			(footprints allowed)
		)
		(placement
			(enabled no)
			(sheetname "")
		)
		(fill
			(thermal_gap 0.5)
			(thermal_bridge_width 0.5)
			(island_removal_mode 0)
		)
		(polygon
			(pts
				(xy 340.20506 -339.065108) (xy 340.20506 -335.575148) (xy 353.19716 -335.575148) (xy 353.19716 -339.065108)
			)
		)
	)
	(zone
		(layer "In11.Cu")
		(hatch none 0.5)
		(connect_pads
			(clearance 0)
		)
		(min_thickness 0.25)
		(keepout
			(tracks allowed)
			(vias allowed)
			(pads allowed)
			(copperpour allowed)
			(footprints allowed)
		)
		(placement
			(enabled no)
			(sheetname "")
		)
		(fill
			(thermal_gap 0.5)
			(thermal_bridge_width 0.5)
			(island_removal_mode 0)
		)
		(polygon
			(pts
				(xy 268.56436 -291.100764) (xy 268.56436 -290.550346) (xy 269.12316 -290.550346) (xy 269.12316 -291.100764)
			)
		)
	)
	(zone
		(layer "In11.Cu")
		(hatch none 0.5)
		(connect_pads
			(clearance 0)
		)
		(min_thickness 0.25)
		(keepout
			(tracks allowed)
			(vias allowed)
			(pads allowed)
			(copperpour allowed)
			(footprints allowed)
		)
		(placement
			(enabled no)
			(sheetname "")
		)
		(fill
			(thermal_gap 0.5)
			(thermal_bridge_width 0.5)
			(island_removal_mode 0)
		)
		(polygon
			(pts
				(xy 420.461186 -259.418582) (xy 420.461186 -259.142992) (xy 421.019986 -259.142992) (xy 421.019986 -259.418582)
			)
		)
	)
	(zone
		(layer "In11.Cu")
		(hatch none 0.5)
		(connect_pads
			(clearance 0)
		)
		(min_thickness 0.25)
		(keepout
			(tracks allowed)
			(vias allowed)
			(pads allowed)
			(copperpour allowed)
			(footprints allowed)
		)
		(placement
			(enabled no)
			(sheetname "")
		)
		(fill
			(thermal_gap 0.5)
			(thermal_bridge_width 0.5)
			(island_removal_mode 0)
		)
		(polygon
			(pts
				(xy 139.39266 -272.35531) (xy 141.213078 -272.35531) (xy 141.479778 -272.62201) (xy 141.479778 -274.37207)
				(xy 141.373098 -274.47875) (xy 140.054838 -274.47875) (xy 139.691618 -274.11553) (xy 139.39266 -274.11553)
			)
		)
	)
	(zone
		(layer "In11.Cu")
		(hatch none 0.5)
		(connect_pads
			(clearance 0)
		)
		(min_thickness 0.25)
		(keepout
			(tracks allowed)
			(vias allowed)
			(pads allowed)
			(copperpour allowed)
			(footprints allowed)
		)
		(placement
			(enabled no)
			(sheetname "")
		)
		(fill
			(thermal_gap 0.5)
			(thermal_bridge_width 0.5)
			(island_removal_mode 0)
		)
		(polygon
			(pts
				(xy 450.636386 -235.342938) (xy 451.195186 -235.342938) (xy 451.195186 -235.618528) (xy 450.636386 -235.618528)
				(xy 450.067426 -235.618528) (xy 450.067426 -235.342938)
			)
		)
	)
	(zone
		(layer "In11.Cu")
		(hatch none 0.5)
		(connect_pads
			(clearance 0)
		)
		(min_thickness 0.25)
		(keepout
			(tracks allowed)
			(vias allowed)
			(pads allowed)
			(copperpour allowed)
			(footprints allowed)
		)
		(placement
			(enabled no)
			(sheetname "")
		)
		(fill
			(thermal_gap 0.5)
			(thermal_bridge_width 0.5)
			(island_removal_mode 0)
		)
		(polygon
			(pts
				(xy 177.170842 -272.064734) (xy 177.170842 -272.340324) (xy 176.612042 -272.340324) (xy 176.612042 -272.064734)
			)
		)
	)
	(zone
		(layer "In11.Cu")
		(hatch none 0.5)
		(connect_pads
			(clearance 0)
		)
		(min_thickness 0.25)
		(keepout
			(tracks allowed)
			(vias allowed)
			(pads allowed)
			(copperpour allowed)
			(footprints allowed)
		)
		(placement
			(enabled no)
			(sheetname "")
		)
		(fill
			(thermal_gap 0.5)
			(thermal_bridge_width 0.5)
			(island_removal_mode 0)
		)
		(polygon
			(pts
				(xy 116.41074 -339.245448) (xy 116.41074 -335.059528) (xy 122.0724 -335.059528) (xy 122.0724 -339.245448)
			)
		)
	)
	(zone
		(layer "In11.Cu")
		(hatch none 0.5)
		(connect_pads
			(clearance 0)
		)
		(min_thickness 0.25)
		(keepout
			(tracks allowed)
			(vias allowed)
			(pads allowed)
			(copperpour allowed)
			(footprints allowed)
		)
		(placement
			(enabled no)
			(sheetname "")
		)
		(fill
			(thermal_gap 0.5)
			(thermal_bridge_width 0.5)
			(island_removal_mode 0)
		)
		(polygon
			(pts
				(xy 450.636386 -233.918506) (xy 450.636386 -233.642916) (xy 451.195186 -233.642916) (xy 451.195186 -233.918506)
			)
		)
	)
	(zone
		(layer "In11.Cu")
		(hatch none 0.5)
		(connect_pads
			(clearance 0)
		)
		(min_thickness 0.25)
		(keepout
			(tracks allowed)
			(vias allowed)
			(pads allowed)
			(copperpour allowed)
			(footprints allowed)
		)
		(placement
			(enabled no)
			(sheetname "")
		)
		(fill
			(thermal_gap 0.5)
			(thermal_bridge_width 0.5)
			(island_removal_mode 0)
		)
		(polygon
			(pts
				(xy 173.070774 -210.864704) (xy 173.070774 -211.140294) (xy 172.511974 -211.140294) (xy 172.511974 -210.864704)
			)
		)
	)
	(zone
		(layer "In11.Cu")
		(hatch none 0.5)
		(connect_pads
			(clearance 0)
		)
		(min_thickness 0.25)
		(keepout
			(tracks allowed)
			(vias allowed)
			(pads allowed)
			(copperpour allowed)
			(footprints allowed)
		)
		(placement
			(enabled no)
			(sheetname "")
		)
		(fill
			(thermal_gap 0.5)
			(thermal_bridge_width 0.5)
			(island_removal_mode 0)
		)
		(polygon
			(pts
				(xy 420.461186 -205.018386) (xy 420.461186 -204.742796) (xy 421.019986 -204.742796) (xy 421.019986 -205.018386)
			)
		)
	)
	(zone
		(layer "In11.Cu")
		(hatch none 0.5)
		(connect_pads
			(clearance 0)
		)
		(min_thickness 0.25)
		(keepout
			(tracks allowed)
			(vias allowed)
			(pads allowed)
			(copperpour allowed)
			(footprints allowed)
		)
		(placement
			(enabled no)
			(sheetname "")
		)
		(fill
			(thermal_gap 0.5)
			(thermal_bridge_width 0.5)
			(island_removal_mode 0)
		)
		(polygon
			(pts
				(xy 352.13544 -351.772728) (xy 352.13544 -350.926908) (xy 353.49434 -350.926908) (xy 353.49434 -351.772728)
			)
		)
	)
	(zone
		(layer "In11.Cu")
		(hatch none 0.5)
		(connect_pads
			(clearance 0)
		)
		(min_thickness 0.25)
		(keepout
			(tracks allowed)
			(vias allowed)
			(pads allowed)
			(copperpour allowed)
			(footprints allowed)
		)
		(placement
			(enabled no)
			(sheetname "")
		)
		(fill
			(thermal_gap 0.5)
			(thermal_bridge_width 0.5)
			(island_removal_mode 0)
		)
		(polygon
			(pts
				(xy 268.51102 -203.546964) (xy 268.51102 -202.997308) (xy 269.14094 -202.997308) (xy 269.14094 -203.546964)
			)
		)
	)
	(zone
		(layer "In11.Cu")
		(hatch none 0.5)
		(connect_pads
			(clearance 0)
		)
		(min_thickness 0.25)
		(keepout
			(tracks allowed)
			(vias allowed)
			(pads allowed)
			(copperpour allowed)
			(footprints allowed)
		)
		(placement
			(enabled no)
			(sheetname "")
		)
		(fill
			(thermal_gap 0.5)
			(thermal_bridge_width 0.5)
			(island_removal_mode 0)
		)
		(polygon
			(pts
				(xy 202.696318 -261.968488) (xy 202.696318 -261.692898) (xy 203.255118 -261.692898) (xy 203.255118 -261.968488)
			)
		)
	)
	(zone
		(layer "In11.Cu")
		(hatch none 0.5)
		(connect_pads
			(clearance 0)
		)
		(min_thickness 0.25)
		(keepout
			(tracks allowed)
			(vias allowed)
			(pads allowed)
			(copperpour allowed)
			(footprints allowed)
		)
		(placement
			(enabled no)
			(sheetname "")
		)
		(fill
			(thermal_gap 0.5)
			(thermal_bridge_width 0.5)
			(island_removal_mode 0)
		)
		(polygon
			(pts
				(xy 294.586152 -196.746876) (xy 294.586152 -196.19722) (xy 295.216072 -196.19722) (xy 295.216072 -196.746876)
			)
		)
	)
	(zone
		(layer "In11.Cu")
		(hatch none 0.5)
		(connect_pads
			(clearance 0)
		)
		(min_thickness 0.25)
		(keepout
			(tracks allowed)
			(vias allowed)
			(pads allowed)
			(copperpour allowed)
			(footprints allowed)
		)
		(placement
			(enabled no)
			(sheetname "")
		)
		(fill
			(thermal_gap 0.5)
			(thermal_bridge_width 0.5)
			(island_removal_mode 0)
		)
		(polygon
			(pts
				(xy 46.646084 -198.446898) (xy 46.646084 -197.897242) (xy 47.276004 -197.897242) (xy 47.276004 -198.446898)
			)
		)
	)
	(zone
		(layer "In11.Cu")
		(hatch none 0.5)
		(connect_pads
			(clearance 0)
		)
		(min_thickness 0.25)
		(keepout
			(tracks allowed)
			(vias allowed)
			(pads allowed)
			(copperpour allowed)
			(footprints allowed)
		)
		(placement
			(enabled no)
			(sheetname "")
		)
		(fill
			(thermal_gap 0.5)
			(thermal_bridge_width 0.5)
			(island_removal_mode 0)
		)
		(polygon
			(pts
				(xy 176.621186 -293.418514) (xy 176.621186 -293.142924) (xy 177.179986 -293.142924) (xy 177.179986 -293.418514)
			)
		)
	)
	(zone
		(layer "In11.Cu")
		(hatch none 0.5)
		(connect_pads
			(clearance 0)
		)
		(min_thickness 0.25)
		(keepout
			(tracks allowed)
			(vias allowed)
			(pads allowed)
			(copperpour allowed)
			(footprints allowed)
		)
		(placement
			(enabled no)
			(sheetname "")
		)
		(fill
			(thermal_gap 0.5)
			(thermal_bridge_width 0.5)
			(island_removal_mode 0)
		)
		(polygon
			(pts
				(xy 425.11091 -204.914754) (xy 425.11091 -205.190344) (xy 424.55211 -205.190344) (xy 424.55211 -204.914754)
			)
		)
	)
	(zone
		(layer "In11.Cu")
		(hatch none 0.5)
		(connect_pads
			(clearance 0)
		)
		(min_thickness 0.25)
		(keepout
			(tracks allowed)
			(vias allowed)
			(pads allowed)
			(copperpour allowed)
			(footprints allowed)
		)
		(placement
			(enabled no)
			(sheetname "")
		)
		(fill
			(thermal_gap 0.5)
			(thermal_bridge_width 0.5)
			(island_removal_mode 0)
		)
		(polygon
			(pts
				(xy 451.186042 -262.71474) (xy 451.186042 -262.99033) (xy 450.627242 -262.99033) (xy 450.627242 -262.71474)
			)
		)
	)
	(zone
		(layer "In11.Cu")
		(hatch none 0.5)
		(connect_pads
			(clearance 0)
		)
		(min_thickness 0.25)
		(keepout
			(tracks allowed)
			(vias allowed)
			(pads allowed)
			(copperpour allowed)
			(footprints allowed)
		)
		(placement
			(enabled no)
			(sheetname "")
		)
		(fill
			(thermal_gap 0.5)
			(thermal_bridge_width 0.5)
			(island_removal_mode 0)
		)
		(polygon
			(pts
				(xy 405.348186 -227.968556) (xy 405.348186 -227.692966) (xy 405.906986 -227.692966) (xy 405.906986 -227.968556)
			)
		)
	)
	(zone
		(layer "In11.Cu")
		(hatch none 0.5)
		(connect_pads
			(clearance 0)
		)
		(min_thickness 0.25)
		(keepout
			(tracks allowed)
			(vias allowed)
			(pads allowed)
			(copperpour allowed)
			(footprints allowed)
		)
		(placement
			(enabled no)
			(sheetname "")
		)
		(fill
			(thermal_gap 0.5)
			(thermal_bridge_width 0.5)
			(island_removal_mode 0)
		)
		(polygon
			(pts
				(xy 203.245974 -234.664758) (xy 203.245974 -234.940348) (xy 202.687174 -234.940348) (xy 202.687174 -234.664758)
			)
		)
	)
	(zone
		(layer "In11.Cu")
		(hatch none 0.5)
		(connect_pads
			(clearance 0)
		)
		(min_thickness 0.25)
		(keepout
			(tracks allowed)
			(vias allowed)
			(pads allowed)
			(copperpour allowed)
			(footprints allowed)
		)
		(placement
			(enabled no)
			(sheetname "")
		)
		(fill
			(thermal_gap 0.5)
			(thermal_bridge_width 0.5)
			(island_removal_mode 0)
		)
		(polygon
			(pts
				(xy 43.25493 -260.501638) (xy 43.25493 -259.933186) (xy 43.78071 -259.933186) (xy 43.78071 -260.501638)
			)
		)
	)
	(zone
		(layer "In11.Cu")
		(hatch none 0.5)
		(connect_pads
			(clearance 0)
		)
		(min_thickness 0.25)
		(keepout
			(tracks allowed)
			(vias allowed)
			(pads allowed)
			(copperpour allowed)
			(footprints allowed)
		)
		(placement
			(enabled no)
			(sheetname "")
		)
		(fill
			(thermal_gap 0.5)
			(thermal_bridge_width 0.5)
			(island_removal_mode 0)
		)
		(polygon
			(pts
				(xy 177.170842 -222.764604) (xy 177.170842 -223.040194) (xy 176.612042 -223.040194) (xy 176.612042 -222.764604)
			)
		)
	)
	(zone
		(layer "In11.Cu")
		(hatch none 0.5)
		(connect_pads
			(clearance 0)
		)
		(min_thickness 0.25)
		(keepout
			(tracks allowed)
			(vias allowed)
			(pads allowed)
			(copperpour allowed)
			(footprints allowed)
		)
		(placement
			(enabled no)
			(sheetname "")
		)
		(fill
			(thermal_gap 0.5)
			(thermal_bridge_width 0.5)
			(island_removal_mode 0)
		)
		(polygon
			(pts
				(xy 298.68622 -240.94694) (xy 298.68622 -240.397284) (xy 299.31614 -240.397284) (xy 299.31614 -240.94694)
			)
		)
	)
	(zone
		(layer "In11.Cu")
		(hatch none 0.5)
		(connect_pads
			(clearance 0)
		)
		(min_thickness 0.25)
		(keepout
			(tracks allowed)
			(vias allowed)
			(pads allowed)
			(copperpour allowed)
			(footprints allowed)
		)
		(placement
			(enabled no)
			(sheetname "")
		)
		(fill
			(thermal_gap 0.5)
			(thermal_bridge_width 0.5)
			(island_removal_mode 0)
		)
		(polygon
			(pts
				(xy 20.624292 -284.300676) (xy 20.624292 -283.750258) (xy 21.183092 -283.750258) (xy 21.183092 -284.300676)
			)
		)
	)
	(zone
		(layer "In11.Cu")
		(hatch none 0.5)
		(connect_pads
			(clearance 0)
		)
		(min_thickness 0.25)
		(keepout
			(tracks allowed)
			(vias allowed)
			(pads allowed)
			(copperpour allowed)
			(footprints allowed)
		)
		(placement
			(enabled no)
			(sheetname "")
		)
		(fill
			(thermal_gap 0.5)
			(thermal_bridge_width 0.5)
			(island_removal_mode 0)
		)
		(polygon
			(pts
				(xy 439.648854 -282.368498) (xy 439.648854 -282.092908) (xy 440.207654 -282.092908) (xy 440.207654 -282.368498)
			)
		)
	)
	(zone
		(layer "In11.Cu")
		(hatch none 0.5)
		(connect_pads
			(clearance 0)
		)
		(min_thickness 0.25)
		(keepout
			(tracks allowed)
			(vias allowed)
			(pads allowed)
			(copperpour allowed)
			(footprints allowed)
		)
		(placement
			(enabled no)
			(sheetname "")
		)
		(fill
			(thermal_gap 0.5)
			(thermal_bridge_width 0.5)
			(island_removal_mode 0)
		)
		(polygon
			(pts
				(xy 176.621186 -259.418582) (xy 176.621186 -259.142992) (xy 177.179986 -259.142992) (xy 177.179986 -259.418582)
			)
		)
	)
	(zone
		(layer "In11.Cu")
		(hatch none 0.5)
		(connect_pads
			(clearance 0)
		)
		(min_thickness 0.25)
		(keepout
			(tracks allowed)
			(vias allowed)
			(pads allowed)
			(copperpour allowed)
			(footprints allowed)
		)
		(placement
			(enabled no)
			(sheetname "")
		)
		(fill
			(thermal_gap 0.5)
			(thermal_bridge_width 0.5)
			(island_removal_mode 0)
		)
		(polygon
			(pts
				(xy 50.771552 -284.29712) (xy 50.771552 -283.747464) (xy 51.401472 -283.747464) (xy 51.401472 -284.29712)
			)
		)
	)
	(zone
		(layer "In11.Cu")
		(hatch none 0.5)
		(connect_pads
			(clearance 0)
		)
		(min_thickness 0.25)
		(keepout
			(tracks allowed)
			(vias allowed)
			(pads allowed)
			(copperpour allowed)
			(footprints allowed)
		)
		(placement
			(enabled no)
			(sheetname "")
		)
		(fill
			(thermal_gap 0.5)
			(thermal_bridge_width 0.5)
			(island_removal_mode 0)
		)
		(polygon
			(pts
				(xy 451.186042 -241.464846) (xy 451.186042 -241.740436) (xy 450.627242 -241.740436) (xy 450.627242 -241.464846)
			)
		)
	)
	(zone
		(layer "In11.Cu")
		(hatch none 0.5)
		(connect_pads
			(clearance 0)
		)
		(min_thickness 0.25)
		(keepout
			(tracks allowed)
			(vias allowed)
			(pads allowed)
			(copperpour allowed)
			(footprints allowed)
		)
		(placement
			(enabled no)
			(sheetname "")
		)
		(fill
			(thermal_gap 0.5)
			(thermal_bridge_width 0.5)
			(island_removal_mode 0)
		)
		(polygon
			(pts
				(xy 172.521118 -200.768458) (xy 172.521118 -200.492868) (xy 173.079918 -200.492868) (xy 173.079918 -200.768458)
			)
		)
	)
	(zone
		(layer "In11.Cu")
		(hatch none 0.5)
		(connect_pads
			(clearance 0)
		)
		(min_thickness 0.25)
		(keepout
			(tracks allowed)
			(vias allowed)
			(pads allowed)
			(copperpour allowed)
			(footprints allowed)
		)
		(placement
			(enabled no)
			(sheetname "")
		)
		(fill
			(thermal_gap 0.5)
			(thermal_bridge_width 0.5)
			(island_removal_mode 0)
		)
		(polygon
			(pts
				(xy 450.636386 -225.418396) (xy 450.636386 -225.142806) (xy 451.195186 -225.142806) (xy 451.195186 -225.418396)
			)
		)
	)
	(zone
		(layer "In11.Cu")
		(hatch none 0.5)
		(connect_pads
			(clearance 0)
		)
		(min_thickness 0.25)
		(keepout
			(tracks allowed)
			(vias allowed)
			(pads allowed)
			(copperpour allowed)
			(footprints allowed)
		)
		(placement
			(enabled no)
			(sheetname "")
		)
		(fill
			(thermal_gap 0.5)
			(thermal_bridge_width 0.5)
			(island_removal_mode 0)
		)
		(polygon
			(pts
				(xy 173.070774 -215.96477) (xy 173.070774 -216.24036) (xy 172.511974 -216.24036) (xy 172.511974 -215.96477)
			)
		)
	)
	(zone
		(layer "In11.Cu")
		(hatch none 0.5)
		(connect_pads
			(clearance 0)
		)
		(min_thickness 0.25)
		(keepout
			(tracks allowed)
			(vias allowed)
			(pads allowed)
			(copperpour allowed)
			(footprints allowed)
		)
		(placement
			(enabled no)
			(sheetname "")
		)
		(fill
			(thermal_gap 0.5)
			(thermal_bridge_width 0.5)
			(island_removal_mode 0)
		)
		(polygon
			(pts
				(xy 450.636386 -199.642984) (xy 451.195186 -199.642984) (xy 451.195186 -199.918574) (xy 451.195186 -200.05675)
				(xy 450.445886 -200.05675) (xy 450.445886 -199.642984)
			)
		)
	)
	(zone
		(layer "In11.Cu")
		(hatch none 0.5)
		(connect_pads
			(clearance 0)
		)
		(min_thickness 0.25)
		(keepout
			(tracks allowed)
			(vias allowed)
			(pads allowed)
			(copperpour allowed)
			(footprints allowed)
		)
		(placement
			(enabled no)
			(sheetname "")
		)
		(fill
			(thermal_gap 0.5)
			(thermal_bridge_width 0.5)
			(island_removal_mode 0)
		)
		(polygon
			(pts
				(xy 268.51102 -228.196902) (xy 268.51102 -227.647246) (xy 269.14094 -227.647246) (xy 269.14094 -228.196902)
			)
		)
	)
	(zone
		(layer "In11.Cu")
		(hatch none 0.5)
		(connect_pads
			(clearance 0)
		)
		(min_thickness 0.25)
		(keepout
			(tracks allowed)
			(vias allowed)
			(pads allowed)
			(copperpour allowed)
			(footprints allowed)
		)
		(placement
			(enabled no)
			(sheetname "")
		)
		(fill
			(thermal_gap 0.5)
			(thermal_bridge_width 0.5)
			(island_removal_mode 0)
		)
		(polygon
			(pts
				(xy 46.646084 -297.896788) (xy 46.646084 -297.347132) (xy 47.276004 -297.347132) (xy 47.276004 -297.896788)
			)
		)
	)
	(zone
		(layer "In11.Cu")
		(hatch none 0.5)
		(connect_pads
			(clearance 0)
		)
		(min_thickness 0.25)
		(keepout
			(tracks allowed)
			(vias allowed)
			(pads allowed)
			(copperpour allowed)
			(footprints allowed)
		)
		(placement
			(enabled no)
			(sheetname "")
		)
		(fill
			(thermal_gap 0.5)
			(thermal_bridge_width 0.5)
			(island_removal_mode 0)
		)
		(polygon
			(pts
				(xy 420.461186 -302.768508) (xy 420.461186 -302.492918) (xy 421.019986 -302.492918) (xy 421.019986 -302.768508)
			)
		)
	)
	(zone
		(layer "In11.Cu")
		(hatch none 0.5)
		(connect_pads
			(clearance 0)
		)
		(min_thickness 0.25)
		(keepout
			(tracks allowed)
			(vias allowed)
			(pads allowed)
			(copperpour allowed)
			(footprints allowed)
		)
		(placement
			(enabled no)
			(sheetname "")
		)
		(fill
			(thermal_gap 0.5)
			(thermal_bridge_width 0.5)
			(island_removal_mode 0)
		)
		(polygon
			(pts
				(xy 298.71162 -272.396966) (xy 298.71162 -271.84731) (xy 299.34154 -271.84731) (xy 299.34154 -272.396966)
			)
		)
	)
	(zone
		(layer "In11.Cu")
		(hatch none 0.5)
		(connect_pads
			(clearance 0)
		)
		(min_thickness 0.25)
		(keepout
			(tracks allowed)
			(vias allowed)
			(pads allowed)
			(copperpour allowed)
			(footprints allowed)
		)
		(placement
			(enabled no)
			(sheetname "")
		)
		(fill
			(thermal_gap 0.5)
			(thermal_bridge_width 0.5)
			(island_removal_mode 0)
		)
		(polygon
			(pts
				(xy 264.464292 -268.150594) (xy 264.464292 -267.600176) (xy 265.023092 -267.600176) (xy 265.023092 -268.150594)
			)
		)
	)
	(zone
		(layer "In11.Cu")
		(hatch none 0.5)
		(connect_pads
			(clearance 0)
		)
		(min_thickness 0.25)
		(keepout
			(tracks allowed)
			(vias allowed)
			(pads allowed)
			(copperpour allowed)
			(footprints allowed)
		)
		(placement
			(enabled no)
			(sheetname "")
		)
		(fill
			(thermal_gap 0.5)
			(thermal_bridge_width 0.5)
			(island_removal_mode 0)
		)
		(polygon
			(pts
				(xy 173.070774 -313.714638) (xy 173.070774 -313.990228) (xy 172.511974 -313.990228) (xy 172.511974 -313.714638)
			)
		)
	)
	(zone
		(layer "In11.Cu")
		(hatch none 0.5)
		(connect_pads
			(clearance 0)
		)
		(min_thickness 0.25)
		(keepout
			(tracks allowed)
			(vias allowed)
			(pads allowed)
			(copperpour allowed)
			(footprints allowed)
		)
		(placement
			(enabled no)
			(sheetname "")
		)
		(fill
			(thermal_gap 0.5)
			(thermal_bridge_width 0.5)
			(island_removal_mode 0)
		)
		(polygon
			(pts
				(xy 20.61845 -260.49224) (xy 20.61845 -259.951982) (xy 21.17725 -259.951982) (xy 21.17725 -260.49224)
			)
		)
	)
	(zone
		(layer "In11.Cu")
		(hatch none 0.5)
		(connect_pads
			(clearance 0)
		)
		(min_thickness 0.25)
		(keepout
			(tracks allowed)
			(vias allowed)
			(pads allowed)
			(copperpour allowed)
			(footprints allowed)
		)
		(placement
			(enabled no)
			(sheetname "")
		)
		(fill
			(thermal_gap 0.5)
			(thermal_bridge_width 0.5)
			(island_removal_mode 0)
		)
		(polygon
			(pts
				(xy 177.170842 -260.164834) (xy 177.170842 -260.440424) (xy 176.612042 -260.440424) (xy 176.612042 -260.164834)
			)
		)
	)
	(zone
		(layer "In11.Cu")
		(hatch none 0.5)
		(connect_pads
			(clearance 0)
		)
		(min_thickness 0.25)
		(keepout
			(tracks allowed)
			(vias allowed)
			(pads allowed)
			(copperpour allowed)
			(footprints allowed)
		)
		(placement
			(enabled no)
			(sheetname "")
		)
		(fill
			(thermal_gap 0.5)
			(thermal_bridge_width 0.5)
			(island_removal_mode 0)
		)
		(polygon
			(pts
				(xy 421.010842 -212.564726) (xy 421.010842 -212.840316) (xy 420.452042 -212.840316) (xy 420.452042 -212.564726)
			)
		)
	)
	(zone
		(layer "In11.Cu")
		(hatch none 0.5)
		(connect_pads
			(clearance 0)
		)
		(min_thickness 0.25)
		(keepout
			(tracks allowed)
			(vias allowed)
			(pads allowed)
			(copperpour allowed)
			(footprints allowed)
		)
		(placement
			(enabled no)
			(sheetname "")
		)
		(fill
			(thermal_gap 0.5)
			(thermal_bridge_width 0.5)
			(island_removal_mode 0)
		)
		(polygon
			(pts
				(xy 294.586152 -223.096836) (xy 294.586152 -222.54718) (xy 295.216072 -222.54718) (xy 295.216072 -223.096836)
			)
		)
	)
	(zone
		(layer "In11.Cu")
		(hatch none 0.5)
		(connect_pads
			(clearance 0)
		)
		(min_thickness 0.25)
		(keepout
			(tracks allowed)
			(vias allowed)
			(pads allowed)
			(copperpour allowed)
			(footprints allowed)
		)
		(placement
			(enabled no)
			(sheetname "")
		)
		(fill
			(thermal_gap 0.5)
			(thermal_bridge_width 0.5)
			(island_removal_mode 0)
		)
		(polygon
			(pts
				(xy 184.164986 -261.118604) (xy 184.164986 -260.843014) (xy 184.723786 -260.843014) (xy 184.723786 -261.118604)
			)
		)
	)
	(zone
		(layer "In11.Cu")
		(hatch none 0.5)
		(connect_pads
			(clearance 0)
		)
		(min_thickness 0.25)
		(keepout
			(tracks allowed)
			(vias allowed)
			(pads allowed)
			(copperpour allowed)
			(footprints allowed)
		)
		(placement
			(enabled no)
			(sheetname "")
		)
		(fill
			(thermal_gap 0.5)
			(thermal_bridge_width 0.5)
			(island_removal_mode 0)
		)
		(polygon
			(pts
				(xy 177.170842 -304.364644) (xy 177.170842 -304.640234) (xy 176.612042 -304.640234) (xy 176.612042 -304.364644)
			)
		)
	)
	(zone
		(layer "In11.Cu")
		(hatch none 0.5)
		(connect_pads
			(clearance 0)
		)
		(min_thickness 0.25)
		(keepout
			(tracks allowed)
			(vias allowed)
			(pads allowed)
			(copperpour allowed)
			(footprints allowed)
		)
		(placement
			(enabled no)
			(sheetname "")
		)
		(fill
			(thermal_gap 0.5)
			(thermal_bridge_width 0.5)
			(island_removal_mode 0)
		)
		(polygon
			(pts
				(xy 294.586152 -202.696826) (xy 294.586152 -202.14717) (xy 295.216072 -202.14717) (xy 295.216072 -202.696826)
			)
		)
	)
	(zone
		(layer "In11.Cu")
		(hatch none 0.5)
		(connect_pads
			(clearance 0)
		)
		(min_thickness 0.25)
		(keepout
			(tracks allowed)
			(vias allowed)
			(pads allowed)
			(copperpour allowed)
			(footprints allowed)
		)
		(placement
			(enabled no)
			(sheetname "")
		)
		(fill
			(thermal_gap 0.5)
			(thermal_bridge_width 0.5)
			(island_removal_mode 0)
		)
		(polygon
			(pts
				(xy 298.68622 -246.89689) (xy 298.68622 -246.347234) (xy 299.31614 -246.347234) (xy 299.31614 -246.89689)
			)
		)
	)
	(zone
		(layer "In11.Cu")
		(hatch none 0.5)
		(connect_pads
			(clearance 0)
		)
		(min_thickness 0.25)
		(keepout
			(tracks allowed)
			(vias allowed)
			(pads allowed)
			(copperpour allowed)
			(footprints allowed)
		)
		(placement
			(enabled no)
			(sheetname "")
		)
		(fill
			(thermal_gap 0.5)
			(thermal_bridge_width 0.5)
			(island_removal_mode 0)
		)
		(polygon
			(pts
				(xy 294.586152 -279.1968) (xy 294.586152 -278.647144) (xy 295.216072 -278.647144) (xy 295.216072 -279.1968)
			)
		)
	)
	(zone
		(layer "In11.Cu")
		(hatch none 0.5)
		(connect_pads
			(clearance 0)
		)
		(min_thickness 0.25)
		(keepout
			(tracks allowed)
			(vias allowed)
			(pads allowed)
			(copperpour allowed)
			(footprints allowed)
		)
		(placement
			(enabled no)
			(sheetname "")
		)
		(fill
			(thermal_gap 0.5)
			(thermal_bridge_width 0.5)
			(island_removal_mode 0)
		)
		(polygon
			(pts
				(xy 425.11091 -287.364678) (xy 425.11091 -287.640268) (xy 424.55211 -287.640268) (xy 424.55211 -287.364678)
			)
		)
	)
	(zone
		(layer "In11.Cu")
		(hatch none 0.5)
		(connect_pads
			(clearance 0)
		)
		(min_thickness 0.25)
		(keepout
			(tracks not_allowed)
			(vias allowed)
			(pads allowed)
			(copperpour not_allowed)
			(footprints allowed)
		)
		(placement
			(enabled no)
			(sheetname "")
		)
		(fill
			(thermal_gap 0.5)
			(thermal_bridge_width 0.5)
			(island_removal_mode 0)
		)
		(polygon
			(pts
				(arc
					(start 127.242062 -428.960788)
					(mid 127.26438 -429.01467)
					(end 127.318262 -429.036988)
				)
				(arc
					(start 128.258062 -429.036988)
					(mid 128.311944 -429.01467)
					(end 128.334262 -428.960788)
				)
				(arc
					(start 128.334262 -426.419264)
					(mid 128.311944 -426.365382)
					(end 128.258062 -426.343064)
				)
				(arc
					(start 127.318262 -426.343064)
					(mid 127.26438 -426.365382)
					(end 127.242062 -426.419264)
				)
			)
		)
	)
	(zone
		(layer "In11.Cu")
		(hatch none 0.5)
		(connect_pads
			(clearance 0)
		)
		(min_thickness 0.25)
		(keepout
			(tracks allowed)
			(vias allowed)
			(pads allowed)
			(copperpour allowed)
			(footprints allowed)
		)
		(placement
			(enabled no)
			(sheetname "")
		)
		(fill
			(thermal_gap 0.5)
			(thermal_bridge_width 0.5)
			(island_removal_mode 0)
		)
		(polygon
			(pts
				(xy 46.646084 -232.44683) (xy 46.646084 -231.897174) (xy 47.276004 -231.897174) (xy 47.276004 -232.44683)
			)
		)
	)
	(zone
		(layer "In11.Cu")
		(hatch none 0.5)
		(connect_pads
			(clearance 0)
		)
		(min_thickness 0.25)
		(keepout
			(tracks allowed)
			(vias allowed)
			(pads allowed)
			(copperpour allowed)
			(footprints allowed)
		)
		(placement
			(enabled no)
			(sheetname "")
		)
		(fill
			(thermal_gap 0.5)
			(thermal_bridge_width 0.5)
			(island_removal_mode 0)
		)
		(polygon
			(pts
				(xy 424.561254 -223.718374) (xy 424.561254 -223.442784) (xy 425.120054 -223.442784) (xy 425.120054 -223.718374)
			)
		)
	)
	(zone
		(layer "In11.Cu")
		(hatch none 0.5)
		(connect_pads
			(clearance 0)
		)
		(min_thickness 0.25)
		(keepout
			(tracks allowed)
			(vias allowed)
			(pads allowed)
			(copperpour allowed)
			(footprints allowed)
		)
		(placement
			(enabled no)
			(sheetname "")
		)
		(fill
			(thermal_gap 0.5)
			(thermal_bridge_width 0.5)
			(island_removal_mode 0)
		)
		(polygon
			(pts
				(xy 450.636386 -237.04296) (xy 451.195186 -237.04296) (xy 451.195186 -237.31855) (xy 451.195186 -237.70717)
				(xy 450.577966 -237.70717) (xy 450.577966 -237.04296)
			)
		)
	)
	(zone
		(layer "In11.Cu")
		(hatch none 0.5)
		(connect_pads
			(clearance 0)
		)
		(min_thickness 0.25)
		(keepout
			(tracks allowed)
			(vias allowed)
			(pads allowed)
			(copperpour allowed)
			(footprints allowed)
		)
		(placement
			(enabled no)
			(sheetname "")
		)
		(fill
			(thermal_gap 0.5)
			(thermal_bridge_width 0.5)
			(island_removal_mode 0)
		)
		(polygon
			(pts
				(xy 294.586152 -305.54676) (xy 294.586152 -304.997104) (xy 295.216072 -304.997104) (xy 295.216072 -305.54676)
			)
		)
	)
	(zone
		(layer "In11.Cu")
		(hatch none 0.5)
		(connect_pads
			(clearance 0)
		)
		(min_thickness 0.25)
		(keepout
			(tracks allowed)
			(vias allowed)
			(pads allowed)
			(copperpour allowed)
			(footprints allowed)
		)
		(placement
			(enabled no)
			(sheetname "")
		)
		(fill
			(thermal_gap 0.5)
			(thermal_bridge_width 0.5)
			(island_removal_mode 0)
		)
		(polygon
			(pts
				(xy 424.561254 -209.268568) (xy 424.561254 -208.992978) (xy 425.120054 -208.992978) (xy 425.120054 -209.268568)
			)
		)
	)
	(zone
		(layer "In11.Cu")
		(hatch none 0.5)
		(connect_pads
			(clearance 0)
		)
		(min_thickness 0.25)
		(keepout
			(tracks allowed)
			(vias allowed)
			(pads allowed)
			(copperpour allowed)
			(footprints allowed)
		)
		(placement
			(enabled no)
			(sheetname "")
		)
		(fill
			(thermal_gap 0.5)
			(thermal_bridge_width 0.5)
			(island_removal_mode 0)
		)
		(polygon
			(pts
				(xy 20.624292 -295.350692) (xy 20.624292 -294.800274) (xy 21.183092 -294.800274) (xy 21.183092 -295.350692)
			)
		)
	)
	(zone
		(layer "In11.Cu")
		(hatch none 0.5)
		(connect_pads
			(clearance 0)
		)
		(min_thickness 0.25)
		(keepout
			(tracks allowed)
			(vias allowed)
			(pads allowed)
			(copperpour allowed)
			(footprints allowed)
		)
		(placement
			(enabled no)
			(sheetname "")
		)
		(fill
			(thermal_gap 0.5)
			(thermal_bridge_width 0.5)
			(island_removal_mode 0)
		)
		(polygon
			(pts
				(xy 294.586152 -217.146886) (xy 294.586152 -216.59723) (xy 295.216072 -216.59723) (xy 295.216072 -217.146886)
			)
		)
	)
	(zone
		(layer "In11.Cu")
		(hatch none 0.5)
		(connect_pads
			(clearance 0)
		)
		(min_thickness 0.25)
		(keepout
			(tracks allowed)
			(vias allowed)
			(pads allowed)
			(copperpour allowed)
			(footprints allowed)
		)
		(placement
			(enabled no)
			(sheetname "")
		)
		(fill
			(thermal_gap 0.5)
			(thermal_bridge_width 0.5)
			(island_removal_mode 0)
		)
		(polygon
			(pts
				(xy 46.646084 -261.34695) (xy 46.646084 -260.797294) (xy 47.276004 -260.797294) (xy 47.276004 -261.34695)
			)
		)
	)
	(zone
		(layer "In11.Cu")
		(hatch none 0.5)
		(connect_pads
			(clearance 0)
		)
		(min_thickness 0.25)
		(keepout
			(tracks allowed)
			(vias allowed)
			(pads allowed)
			(copperpour allowed)
			(footprints allowed)
		)
		(placement
			(enabled no)
			(sheetname "")
		)
		(fill
			(thermal_gap 0.5)
			(thermal_bridge_width 0.5)
			(island_removal_mode 0)
		)
		(polygon
			(pts
				(xy 176.621186 -225.418396) (xy 176.621186 -225.142806) (xy 177.179986 -225.142806) (xy 177.179986 -225.418396)
			)
		)
	)
	(zone
		(layer "In11.Cu")
		(hatch none 0.5)
		(connect_pads
			(clearance 0)
		)
		(min_thickness 0.25)
		(keepout
			(tracks allowed)
			(vias allowed)
			(pads allowed)
			(copperpour allowed)
			(footprints allowed)
		)
		(placement
			(enabled no)
			(sheetname "")
		)
		(fill
			(thermal_gap 0.5)
			(thermal_bridge_width 0.5)
			(island_removal_mode 0)
		)
		(polygon
			(pts
				(xy 202.696318 -295.69283) (xy 203.255118 -295.69283) (xy 203.255118 -295.96842) (xy 203.255118 -296.207942)
				(xy 202.37577 -296.207942) (xy 202.37577 -295.69283)
			)
		)
	)
	(zone
		(layer "In11.Cu")
		(hatch none 0.5)
		(connect_pads
			(clearance 0)
		)
		(min_thickness 0.25)
		(keepout
			(tracks allowed)
			(vias allowed)
			(pads allowed)
			(copperpour allowed)
			(footprints allowed)
		)
		(placement
			(enabled no)
			(sheetname "")
		)
		(fill
			(thermal_gap 0.5)
			(thermal_bridge_width 0.5)
			(island_removal_mode 0)
		)
		(polygon
			(pts
				(xy 424.561254 -281.51836) (xy 424.561254 -281.24277) (xy 425.120054 -281.24277) (xy 425.120054 -281.51836)
			)
		)
	)
	(zone
		(layer "In11.Cu")
		(hatch none 0.5)
		(connect_pads
			(clearance 0)
		)
		(min_thickness 0.25)
		(keepout
			(tracks allowed)
			(vias allowed)
			(pads allowed)
			(copperpour allowed)
			(footprints allowed)
		)
		(placement
			(enabled no)
			(sheetname "")
		)
		(fill
			(thermal_gap 0.5)
			(thermal_bridge_width 0.5)
			(island_removal_mode 0)
		)
		(polygon
			(pts
				(xy 173.070774 -288.214816) (xy 173.070774 -288.490406) (xy 172.511974 -288.490406) (xy 172.511974 -288.214816)
			)
		)
	)
	(zone
		(layer "In11.Cu")
		(hatch none 0.5)
		(connect_pads
			(clearance 0)
		)
		(min_thickness 0.25)
		(keepout
			(tracks allowed)
			(vias allowed)
			(pads allowed)
			(copperpour allowed)
			(footprints allowed)
		)
		(placement
			(enabled no)
			(sheetname "")
		)
		(fill
			(thermal_gap 0.5)
			(thermal_bridge_width 0.5)
			(island_removal_mode 0)
		)
		(polygon
			(pts
				(xy 176.621186 -229.668578) (xy 176.621186 -229.392988) (xy 177.179986 -229.392988) (xy 177.179986 -229.668578)
			)
		)
	)
	(zone
		(layer "In11.Cu")
		(hatch none 0.5)
		(connect_pads
			(clearance 0)
		)
		(min_thickness 0.25)
		(keepout
			(tracks allowed)
			(vias allowed)
			(pads allowed)
			(copperpour allowed)
			(footprints allowed)
		)
		(placement
			(enabled no)
			(sheetname "")
		)
		(fill
			(thermal_gap 0.5)
			(thermal_bridge_width 0.5)
			(island_removal_mode 0)
		)
		(polygon
			(pts
				(xy 420.461186 -304.46853) (xy 420.461186 -304.19294) (xy 421.019986 -304.19294) (xy 421.019986 -304.46853)
			)
		)
	)
	(zone
		(layer "In11.Cu")
		(hatch none 0.5)
		(connect_pads
			(clearance 0)
		)
		(min_thickness 0.25)
		(keepout
			(tracks allowed)
			(vias allowed)
			(pads allowed)
			(copperpour allowed)
			(footprints allowed)
		)
		(placement
			(enabled no)
			(sheetname "")
		)
		(fill
			(thermal_gap 0.5)
			(thermal_bridge_width 0.5)
			(island_removal_mode 0)
		)
		(polygon
			(pts
				(xy 176.621186 -286.618426) (xy 176.621186 -286.342836) (xy 177.179986 -286.342836) (xy 177.179986 -286.618426)
			)
		)
	)
	(zone
		(layer "In11.Cu")
		(hatch none 0.5)
		(connect_pads
			(clearance 0)
		)
		(min_thickness 0.25)
		(keepout
			(tracks allowed)
			(vias allowed)
			(pads allowed)
			(copperpour allowed)
			(footprints allowed)
		)
		(placement
			(enabled no)
			(sheetname "")
		)
		(fill
			(thermal_gap 0.5)
			(thermal_bridge_width 0.5)
			(island_removal_mode 0)
		)
		(polygon
			(pts
				(xy 294.586152 -280.896822) (xy 294.586152 -280.347166) (xy 295.216072 -280.347166) (xy 295.216072 -280.896822)
			)
		)
	)
	(zone
		(layer "In11.Cu")
		(hatch none 0.5)
		(connect_pads
			(clearance 0)
		)
		(min_thickness 0.25)
		(keepout
			(tracks allowed)
			(vias allowed)
			(pads allowed)
			(copperpour allowed)
			(footprints allowed)
		)
		(placement
			(enabled no)
			(sheetname "")
		)
		(fill
			(thermal_gap 0.5)
			(thermal_bridge_width 0.5)
			(island_removal_mode 0)
		)
		(polygon
			(pts
				(xy 172.444918 -261.118604) (xy 172.444918 -260.843014) (xy 173.003718 -260.843014) (xy 173.003718 -261.118604)
			)
		)
	)
	(zone
		(layer "In11.Cu")
		(hatch none 0.5)
		(connect_pads
			(clearance 0)
		)
		(min_thickness 0.25)
		(keepout
			(tracks allowed)
			(vias allowed)
			(pads allowed)
			(copperpour allowed)
			(footprints allowed)
		)
		(placement
			(enabled no)
			(sheetname "")
		)
		(fill
			(thermal_gap 0.5)
			(thermal_bridge_width 0.5)
			(island_removal_mode 0)
		)
		(polygon
			(pts
				(xy 451.186042 -200.664826) (xy 451.186042 -200.940416) (xy 450.627242 -200.940416) (xy 450.407786 -200.940416)
				(xy 450.407786 -200.36409) (xy 451.186042 -200.36409)
			)
		)
	)
	(zone
		(layer "In11.Cu")
		(hatch none 0.5)
		(connect_pads
			(clearance 0)
		)
		(min_thickness 0.25)
		(keepout
			(tracks allowed)
			(vias allowed)
			(pads allowed)
			(copperpour allowed)
			(footprints allowed)
		)
		(placement
			(enabled no)
			(sheetname "")
		)
		(fill
			(thermal_gap 0.5)
			(thermal_bridge_width 0.5)
			(island_removal_mode 0)
		)
		(polygon
			(pts
				(xy 449.95211 -269.514828) (xy 449.95211 -269.790418) (xy 449.39331 -269.790418) (xy 449.39331 -269.514828)
			)
		)
	)
	(zone
		(layer "In11.Cu")
		(hatch none 0.5)
		(connect_pads
			(clearance 0)
		)
		(min_thickness 0.25)
		(keepout
			(tracks allowed)
			(vias allowed)
			(pads allowed)
			(copperpour allowed)
			(footprints allowed)
		)
		(placement
			(enabled no)
			(sheetname "")
		)
		(fill
			(thermal_gap 0.5)
			(thermal_bridge_width 0.5)
			(island_removal_mode 0)
		)
		(polygon
			(pts
				(xy 202.696318 -221.168468) (xy 202.696318 -220.892878) (xy 203.255118 -220.892878) (xy 203.255118 -221.168468)
			)
		)
	)
	(zone
		(layer "In11.Cu")
		(hatch none 0.5)
		(connect_pads
			(clearance 0)
		)
		(min_thickness 0.25)
		(keepout
			(tracks allowed)
			(vias allowed)
			(pads allowed)
			(copperpour allowed)
			(footprints allowed)
		)
		(placement
			(enabled no)
			(sheetname "")
		)
		(fill
			(thermal_gap 0.5)
			(thermal_bridge_width 0.5)
			(island_removal_mode 0)
		)
		(polygon
			(pts
				(xy 176.621186 -284.918404) (xy 176.621186 -284.642814) (xy 177.179986 -284.642814) (xy 177.179986 -284.918404)
			)
		)
	)
	(zone
		(layer "In11.Cu")
		(hatch none 0.5)
		(connect_pads
			(clearance 0)
		)
		(min_thickness 0.25)
		(keepout
			(tracks allowed)
			(vias allowed)
			(pads allowed)
			(copperpour allowed)
			(footprints allowed)
		)
		(placement
			(enabled no)
			(sheetname "")
		)
		(fill
			(thermal_gap 0.5)
			(thermal_bridge_width 0.5)
			(island_removal_mode 0)
		)
		(polygon
			(pts
				(xy 203.245974 -290.764722) (xy 203.245974 -291.040312) (xy 202.687174 -291.040312) (xy 202.687174 -290.764722)
			)
		)
	)
	(zone
		(layer "In11.Cu")
		(hatch none 0.5)
		(connect_pads
			(clearance 0)
		)
		(min_thickness 0.25)
		(keepout
			(tracks not_allowed)
			(vias allowed)
			(pads allowed)
			(copperpour not_allowed)
			(footprints allowed)
		)
		(placement
			(enabled no)
			(sheetname "")
		)
		(fill
			(thermal_gap 0.5)
			(thermal_bridge_width 0.5)
			(island_removal_mode 0)
		)
		(polygon
			(pts
				(arc
					(start 77.142086 -428.960788)
					(mid 77.164404 -429.01467)
					(end 77.218286 -429.036988)
				)
				(arc
					(start 78.158086 -429.036988)
					(mid 78.211968 -429.01467)
					(end 78.234286 -428.960788)
				)
				(arc
					(start 78.234286 -426.419264)
					(mid 78.211968 -426.365382)
					(end 78.158086 -426.343064)
				)
				(arc
					(start 77.218286 -426.343064)
					(mid 77.164404 -426.365382)
					(end 77.142086 -426.419264)
				)
			)
		)
	)
	(zone
		(layer "In11.Cu")
		(hatch none 0.5)
		(connect_pads
			(clearance 0)
		)
		(min_thickness 0.25)
		(keepout
			(tracks allowed)
			(vias allowed)
			(pads allowed)
			(copperpour allowed)
			(footprints allowed)
		)
		(placement
			(enabled no)
			(sheetname "")
		)
		(fill
			(thermal_gap 0.5)
			(thermal_bridge_width 0.5)
			(island_removal_mode 0)
		)
		(polygon
			(pts
				(xy 421.010842 -210.864704) (xy 421.010842 -211.140294) (xy 420.452042 -211.140294) (xy 420.452042 -210.864704)
			)
		)
	)
	(zone
		(layer "In11.Cu")
		(hatch none 0.5)
		(connect_pads
			(clearance 0)
		)
		(min_thickness 0.25)
		(keepout
			(tracks allowed)
			(vias allowed)
			(pads allowed)
			(copperpour allowed)
			(footprints allowed)
		)
		(placement
			(enabled no)
			(sheetname "")
		)
		(fill
			(thermal_gap 0.5)
			(thermal_bridge_width 0.5)
			(island_removal_mode 0)
		)
		(polygon
			(pts
				(xy 20.61845 -267.292328) (xy 20.61845 -266.75207) (xy 21.186394 -266.75207) (xy 21.486876 -266.75207)
				(xy 21.591016 -266.85621) (xy 21.591016 -267.12164) (xy 21.420328 -267.292328) (xy 21.17725 -267.292328)
			)
		)
	)
	(zone
		(layer "In11.Cu")
		(hatch none 0.5)
		(connect_pads
			(clearance 0)
		)
		(min_thickness 0.25)
		(keepout
			(tracks allowed)
			(vias allowed)
			(pads allowed)
			(copperpour allowed)
			(footprints allowed)
		)
		(placement
			(enabled no)
			(sheetname "")
		)
		(fill
			(thermal_gap 0.5)
			(thermal_bridge_width 0.5)
			(island_removal_mode 0)
		)
		(polygon
			(pts
				(xy 172.521118 -302.768508) (xy 172.521118 -302.492918) (xy 173.079918 -302.492918) (xy 173.079918 -302.768508)
			)
		)
	)
	(zone
		(layer "In11.Cu")
		(hatch none 0.5)
		(connect_pads
			(clearance 0)
		)
		(min_thickness 0.25)
		(keepout
			(tracks allowed)
			(vias allowed)
			(pads allowed)
			(copperpour allowed)
			(footprints allowed)
		)
		(placement
			(enabled no)
			(sheetname "")
		)
		(fill
			(thermal_gap 0.5)
			(thermal_bridge_width 0.5)
			(island_removal_mode 0)
		)
		(polygon
			(pts
				(xy 432.105054 -261.118604) (xy 432.105054 -260.843014) (xy 432.663854 -260.843014) (xy 432.663854 -261.118604)
			)
		)
	)
	(zone
		(layer "In11.Cu")
		(hatch none 0.5)
		(connect_pads
			(clearance 0)
		)
		(min_thickness 0.25)
		(keepout
			(tracks allowed)
			(vias allowed)
			(pads allowed)
			(copperpour allowed)
			(footprints allowed)
		)
		(placement
			(enabled no)
			(sheetname "")
		)
		(fill
			(thermal_gap 0.5)
			(thermal_bridge_width 0.5)
			(island_removal_mode 0)
		)
		(polygon
			(pts
				(xy 435.548786 -234.76839) (xy 435.548786 -234.4928) (xy 436.107586 -234.4928) (xy 436.107586 -234.76839)
			)
		)
	)
	(zone
		(layer "In11.Cu")
		(hatch none 0.5)
		(connect_pads
			(clearance 0)
		)
		(min_thickness 0.25)
		(keepout
			(tracks allowed)
			(vias allowed)
			(pads allowed)
			(copperpour allowed)
			(footprints allowed)
		)
		(placement
			(enabled no)
			(sheetname "")
		)
		(fill
			(thermal_gap 0.5)
			(thermal_bridge_width 0.5)
			(island_removal_mode 0)
		)
		(polygon
			(pts
				(xy 294.586152 -200.14692) (xy 294.586152 -199.597264) (xy 295.216072 -199.597264) (xy 295.216072 -200.14692)
			)
		)
	)
	(zone
		(layer "In11.Cu")
		(hatch none 0.5)
		(connect_pads
			(clearance 0)
		)
		(min_thickness 0.25)
		(keepout
			(tracks allowed)
			(vias allowed)
			(pads allowed)
			(copperpour allowed)
			(footprints allowed)
		)
		(placement
			(enabled no)
			(sheetname "")
		)
		(fill
			(thermal_gap 0.5)
			(thermal_bridge_width 0.5)
			(island_removal_mode 0)
		)
		(polygon
			(pts
				(xy 425.11091 -276.314662) (xy 425.11091 -276.590252) (xy 424.55211 -276.590252) (xy 424.55211 -276.314662)
			)
		)
	)
	(zone
		(layer "In11.Cu")
		(hatch none 0.5)
		(connect_pads
			(clearance 0)
		)
		(min_thickness 0.25)
		(keepout
			(tracks allowed)
			(vias allowed)
			(pads allowed)
			(copperpour allowed)
			(footprints allowed)
		)
		(placement
			(enabled no)
			(sheetname "")
		)
		(fill
			(thermal_gap 0.5)
			(thermal_bridge_width 0.5)
			(island_removal_mode 0)
		)
		(polygon
			(pts
				(xy 203.245974 -218.514676) (xy 203.245974 -218.790266) (xy 202.687174 -218.790266) (xy 202.687174 -218.514676)
			)
		)
	)
	(zone
		(layer "In11.Cu")
		(hatch none 0.5)
		(connect_pads
			(clearance 0)
		)
		(min_thickness 0.25)
		(keepout
			(tracks allowed)
			(vias allowed)
			(pads allowed)
			(copperpour allowed)
			(footprints allowed)
		)
		(placement
			(enabled no)
			(sheetname "")
		)
		(fill
			(thermal_gap 0.5)
			(thermal_bridge_width 0.5)
			(island_removal_mode 0)
		)
		(polygon
			(pts
				(xy 172.444918 -262.818372) (xy 172.444918 -262.542782) (xy 173.003718 -262.542782) (xy 173.003718 -262.818372)
			)
		)
	)
	(zone
		(layer "In11.Cu")
		(hatch none 0.5)
		(connect_pads
			(clearance 0)
		)
		(min_thickness 0.25)
		(keepout
			(tracks allowed)
			(vias allowed)
			(pads allowed)
			(copperpour allowed)
			(footprints allowed)
		)
		(placement
			(enabled no)
			(sheetname "")
		)
		(fill
			(thermal_gap 0.5)
			(thermal_bridge_width 0.5)
			(island_removal_mode 0)
		)
		(polygon
			(pts
				(xy 177.170842 -236.36478) (xy 177.170842 -236.64037) (xy 176.612042 -236.64037) (xy 176.612042 -236.36478)
			)
		)
	)
	(zone
		(layer "In11.Cu")
		(hatch none 0.5)
		(connect_pads
			(clearance 0)
		)
		(min_thickness 0.25)
		(keepout
			(tracks allowed)
			(vias allowed)
			(pads allowed)
			(copperpour allowed)
			(footprints allowed)
		)
		(placement
			(enabled no)
			(sheetname "")
		)
		(fill
			(thermal_gap 0.5)
			(thermal_bridge_width 0.5)
			(island_removal_mode 0)
		)
		(polygon
			(pts
				(xy 187.608718 -308.718458) (xy 187.608718 -308.442868) (xy 188.167518 -308.442868) (xy 188.167518 -308.718458)
			)
		)
	)
	(zone
		(layer "In11.Cu")
		(hatch none 0.5)
		(connect_pads
			(clearance 0)
		)
		(min_thickness 0.25)
		(keepout
			(tracks allowed)
			(vias allowed)
			(pads allowed)
			(copperpour allowed)
			(footprints allowed)
		)
		(placement
			(enabled no)
			(sheetname "")
		)
		(fill
			(thermal_gap 0.5)
			(thermal_bridge_width 0.5)
			(island_removal_mode 0)
		)
		(polygon
			(pts
				(xy 294.586152 -259.646928) (xy 294.586152 -259.097272) (xy 295.216072 -259.097272) (xy 295.216072 -259.646928)
			)
		)
	)
	(zone
		(layer "In11.Cu")
		(hatch none 0.5)
		(connect_pads
			(clearance 0)
		)
		(min_thickness 0.25)
		(keepout
			(tracks allowed)
			(vias allowed)
			(pads allowed)
			(copperpour allowed)
			(footprints allowed)
		)
		(placement
			(enabled no)
			(sheetname "")
		)
		(fill
			(thermal_gap 0.5)
			(thermal_bridge_width 0.5)
			(island_removal_mode 0)
		)
		(polygon
			(pts
				(xy 294.586152 -308.946804) (xy 294.586152 -308.397148) (xy 295.216072 -308.397148) (xy 295.216072 -308.946804)
			)
		)
	)
	(zone
		(layer "In11.Cu")
		(hatch none 0.5)
		(connect_pads
			(clearance 0)
		)
		(min_thickness 0.25)
		(keepout
			(tracks allowed)
			(vias allowed)
			(pads allowed)
			(copperpour allowed)
			(footprints allowed)
		)
		(placement
			(enabled no)
			(sheetname "")
		)
		(fill
			(thermal_gap 0.5)
			(thermal_bridge_width 0.5)
			(island_removal_mode 0)
		)
		(polygon
			(pts
				(xy 268.56436 -289.400742) (xy 268.56436 -288.850324) (xy 269.12316 -288.850324) (xy 269.12316 -289.400742)
			)
		)
	)
	(zone
		(layer "In11.Cu")
		(hatch none 0.5)
		(connect_pads
			(clearance 0)
		)
		(min_thickness 0.25)
		(keepout
			(tracks allowed)
			(vias allowed)
			(pads allowed)
			(copperpour allowed)
			(footprints allowed)
		)
		(placement
			(enabled no)
			(sheetname "")
		)
		(fill
			(thermal_gap 0.5)
			(thermal_bridge_width 0.5)
			(island_removal_mode 0)
		)
		(polygon
			(pts
				(xy 176.621186 -312.118502) (xy 176.621186 -311.842912) (xy 177.179986 -311.842912) (xy 177.179986 -312.118502)
			)
		)
	)
	(zone
		(layer "In11.Cu")
		(hatch none 0.5)
		(connect_pads
			(clearance 0)
		)
		(min_thickness 0.25)
		(keepout
			(tracks allowed)
			(vias allowed)
			(pads allowed)
			(copperpour allowed)
			(footprints allowed)
		)
		(placement
			(enabled no)
			(sheetname "")
		)
		(fill
			(thermal_gap 0.5)
			(thermal_bridge_width 0.5)
			(island_removal_mode 0)
		)
		(polygon
			(pts
				(xy 157.408118 -227.968556) (xy 157.408118 -227.692966) (xy 157.966918 -227.692966) (xy 157.966918 -227.968556)
			)
		)
	)
	(zone
		(layer "In11.Cu")
		(hatch none 0.5)
		(connect_pads
			(clearance 0)
		)
		(min_thickness 0.25)
		(keepout
			(tracks allowed)
			(vias allowed)
			(pads allowed)
			(copperpour allowed)
			(footprints allowed)
		)
		(placement
			(enabled no)
			(sheetname "")
		)
		(fill
			(thermal_gap 0.5)
			(thermal_bridge_width 0.5)
			(island_removal_mode 0)
		)
		(polygon
			(pts
				(xy 20.624292 -283.450538) (xy 20.624292 -282.90012) (xy 21.183092 -282.90012) (xy 21.183092 -283.450538)
			)
		)
	)
	(zone
		(layer "In11.Cu")
		(hatch none 0.5)
		(connect_pads
			(clearance 0)
		)
		(min_thickness 0.25)
		(keepout
			(tracks allowed)
			(vias allowed)
			(pads allowed)
			(copperpour allowed)
			(footprints allowed)
		)
		(placement
			(enabled no)
			(sheetname "")
		)
		(fill
			(thermal_gap 0.5)
			(thermal_bridge_width 0.5)
			(island_removal_mode 0)
		)
		(polygon
			(pts
				(xy 291.194998 -259.651754) (xy 291.194998 -259.083302) (xy 291.720778 -259.083302) (xy 291.720778 -259.651754)
			)
		)
	)
	(zone
		(layer "In11.Cu")
		(hatch none 0.5)
		(connect_pads
			(clearance 0)
		)
		(min_thickness 0.25)
		(keepout
			(tracks allowed)
			(vias allowed)
			(pads allowed)
			(copperpour allowed)
			(footprints allowed)
		)
		(placement
			(enabled no)
			(sheetname "")
		)
		(fill
			(thermal_gap 0.5)
			(thermal_bridge_width 0.5)
			(island_removal_mode 0)
		)
		(polygon
			(pts
				(xy 177.170842 -297.56481) (xy 177.170842 -297.8404) (xy 176.612042 -297.8404) (xy 176.612042 -297.56481)
			)
		)
	)
	(zone
		(layer "In11.Cu")
		(hatch none 0.5)
		(connect_pads
			(clearance 0)
		)
		(min_thickness 0.25)
		(keepout
			(tracks allowed)
			(vias allowed)
			(pads allowed)
			(copperpour allowed)
			(footprints allowed)
		)
		(placement
			(enabled no)
			(sheetname "")
		)
		(fill
			(thermal_gap 0.5)
			(thermal_bridge_width 0.5)
			(island_removal_mode 0)
		)
		(polygon
			(pts
				(xy 368.54638 -358.402128) (xy 368.54638 -351.252028) (xy 369.9383 -351.252028) (xy 372.26748 -348.922848)
				(xy 378.36094 -348.922848) (xy 379.29566 -349.857568) (xy 390.41832 -349.857568) (xy 390.89584 -349.380048)
				(xy 390.89584 -334.617568) (xy 391.0203 -334.493108) (xy 391.9982 -334.493108) (xy 392.33094 -334.825848)
				(xy 392.33094 -349.773748) (xy 391.06094 -351.043748) (xy 378.4219 -351.043748) (xy 377.75642 -350.378268)
				(xy 372.8085 -350.378268) (xy 370.85524 -352.331528) (xy 370.85524 -358.402128)
			)
		)
	)
	(zone
		(layer "In11.Cu")
		(hatch none 0.5)
		(connect_pads
			(clearance 0)
		)
		(min_thickness 0.25)
		(keepout
			(tracks allowed)
			(vias allowed)
			(pads allowed)
			(copperpour allowed)
			(footprints allowed)
		)
		(placement
			(enabled no)
			(sheetname "")
		)
		(fill
			(thermal_gap 0.5)
			(thermal_bridge_width 0.5)
			(island_removal_mode 0)
		)
		(polygon
			(pts
				(xy 46.646084 -284.296866) (xy 46.646084 -283.74721) (xy 47.276004 -283.74721) (xy 47.276004 -284.296866)
			)
		)
	)
	(zone
		(layer "In11.Cu")
		(hatch none 0.5)
		(connect_pads
			(clearance 0)
		)
		(min_thickness 0.25)
		(keepout
			(tracks allowed)
			(vias allowed)
			(pads allowed)
			(copperpour allowed)
			(footprints allowed)
		)
		(placement
			(enabled no)
			(sheetname "")
		)
		(fill
			(thermal_gap 0.5)
			(thermal_bridge_width 0.5)
			(island_removal_mode 0)
		)
		(polygon
			(pts
				(xy 187.608718 -236.468412) (xy 187.608718 -236.192822) (xy 188.167518 -236.192822) (xy 188.167518 -236.468412)
			)
		)
	)
	(zone
		(layer "In11.Cu")
		(hatch none 0.5)
		(connect_pads
			(clearance 0)
		)
		(min_thickness 0.25)
		(keepout
			(tracks allowed)
			(vias allowed)
			(pads allowed)
			(copperpour allowed)
			(footprints allowed)
		)
		(placement
			(enabled no)
			(sheetname "")
		)
		(fill
			(thermal_gap 0.5)
			(thermal_bridge_width 0.5)
			(island_removal_mode 0)
		)
		(polygon
			(pts
				(xy 50.746152 -240.94694) (xy 50.746152 -240.397284) (xy 51.376072 -240.397284) (xy 51.376072 -240.94694)
			)
		)
	)
	(zone
		(layer "In11.Cu")
		(hatch none 0.5)
		(connect_pads
			(clearance 0)
		)
		(min_thickness 0.25)
		(keepout
			(tracks allowed)
			(vias allowed)
			(pads allowed)
			(copperpour allowed)
			(footprints allowed)
		)
		(placement
			(enabled no)
			(sheetname "")
		)
		(fill
			(thermal_gap 0.5)
			(thermal_bridge_width 0.5)
			(island_removal_mode 0)
		)
		(polygon
			(pts
				(xy 268.56436 -286.000698) (xy 268.56436 -285.45028) (xy 269.12316 -285.45028) (xy 269.12316 -286.000698)
			)
		)
	)
	(zone
		(layer "In11.Cu")
		(hatch none 0.5)
		(connect_pads
			(clearance 0)
		)
		(min_thickness 0.25)
		(keepout
			(tracks allowed)
			(vias allowed)
			(pads allowed)
			(copperpour allowed)
			(footprints allowed)
		)
		(placement
			(enabled no)
			(sheetname "")
		)
		(fill
			(thermal_gap 0.5)
			(thermal_bridge_width 0.5)
			(island_removal_mode 0)
		)
		(polygon
			(pts
				(xy 450.636386 -285.768542) (xy 450.636386 -285.492952) (xy 451.195186 -285.492952) (xy 451.195186 -285.768542)
			)
		)
	)
	(zone
		(layer "In11.Cu")
		(hatch none 0.5)
		(connect_pads
			(clearance 0)
		)
		(min_thickness 0.25)
		(keepout
			(tracks allowed)
			(vias allowed)
			(pads allowed)
			(copperpour allowed)
			(footprints allowed)
		)
		(placement
			(enabled no)
			(sheetname "")
		)
		(fill
			(thermal_gap 0.5)
			(thermal_bridge_width 0.5)
			(island_removal_mode 0)
		)
		(polygon
			(pts
				(xy 298.3865 -267.592048) (xy 298.3865 -266.136628) (xy 299.69968 -266.136628) (xy 299.69968 -267.592048)
			)
		)
	)
	(zone
		(layer "In11.Cu")
		(hatch none 0.5)
		(connect_pads
			(clearance 0)
		)
		(min_thickness 0.25)
		(keepout
			(tracks allowed)
			(vias allowed)
			(pads allowed)
			(copperpour allowed)
			(footprints allowed)
		)
		(placement
			(enabled no)
			(sheetname "")
		)
		(fill
			(thermal_gap 0.5)
			(thermal_bridge_width 0.5)
			(island_removal_mode 0)
		)
		(polygon
			(pts
				(xy 202.696318 -219.468446) (xy 202.696318 -219.192856) (xy 203.255118 -219.192856) (xy 203.255118 -219.468446)
			)
		)
	)
	(zone
		(layer "In11.Cu")
		(hatch none 0.5)
		(connect_pads
			(clearance 0)
		)
		(min_thickness 0.25)
		(keepout
			(tracks allowed)
			(vias allowed)
			(pads allowed)
			(copperpour allowed)
			(footprints allowed)
		)
		(placement
			(enabled no)
			(sheetname "")
		)
		(fill
			(thermal_gap 0.5)
			(thermal_bridge_width 0.5)
			(island_removal_mode 0)
		)
		(polygon
			(pts
				(xy 425.11091 -198.114666) (xy 425.11091 -198.390256) (xy 424.55211 -198.390256) (xy 424.55211 -198.114666)
			)
		)
	)
	(zone
		(layer "In11.Cu")
		(hatch none 0.5)
		(connect_pads
			(clearance 0)
		)
		(min_thickness 0.25)
		(keepout
			(tracks allowed)
			(vias allowed)
			(pads allowed)
			(copperpour allowed)
			(footprints allowed)
		)
		(placement
			(enabled no)
			(sheetname "")
		)
		(fill
			(thermal_gap 0.5)
			(thermal_bridge_width 0.5)
			(island_removal_mode 0)
		)
		(polygon
			(pts
				(xy 202.696318 -216.068402) (xy 202.696318 -215.792812) (xy 203.255118 -215.792812) (xy 203.255118 -216.068402)
			)
		)
	)
	(zone
		(layer "In11.Cu")
		(hatch none 0.5)
		(connect_pads
			(clearance 0)
		)
		(min_thickness 0.25)
		(keepout
			(tracks allowed)
			(vias allowed)
			(pads allowed)
			(copperpour allowed)
			(footprints allowed)
		)
		(placement
			(enabled no)
			(sheetname "")
		)
		(fill
			(thermal_gap 0.5)
			(thermal_bridge_width 0.5)
			(island_removal_mode 0)
		)
		(polygon
			(pts
				(xy 268.558518 -263.892284) (xy 268.558518 -263.352026) (xy 269.117318 -263.352026) (xy 269.117318 -263.892284)
			)
		)
	)
	(zone
		(layer "In11.Cu")
		(hatch none 0.5)
		(connect_pads
			(clearance 0)
		)
		(min_thickness 0.25)
		(keepout
			(tracks allowed)
			(vias allowed)
			(pads allowed)
			(copperpour allowed)
			(footprints allowed)
		)
		(placement
			(enabled no)
			(sheetname "")
		)
		(fill
			(thermal_gap 0.5)
			(thermal_bridge_width 0.5)
			(island_removal_mode 0)
		)
		(polygon
			(pts
				(xy 424.57878 -367.165128) (xy 424.57878 -365.717328) (xy 426.28566 -365.717328) (xy 426.28566 -367.165128)
			)
		)
	)
	(zone
		(layer "In11.Cu")
		(hatch none 0.5)
		(connect_pads
			(clearance 0)
		)
		(min_thickness 0.25)
		(keepout
			(tracks allowed)
			(vias allowed)
			(pads allowed)
			(copperpour allowed)
			(footprints allowed)
		)
		(placement
			(enabled no)
			(sheetname "")
		)
		(fill
			(thermal_gap 0.5)
			(thermal_bridge_width 0.5)
			(island_removal_mode 0)
		)
		(polygon
			(pts
				(xy 162.083242 -225.314764) (xy 162.083242 -225.590354) (xy 161.524442 -225.590354) (xy 161.524442 -225.314764)
			)
		)
	)
	(zone
		(layer "In11.Cu")
		(hatch none 0.5)
		(connect_pads
			(clearance 0)
		)
		(min_thickness 0.25)
		(keepout
			(tracks allowed)
			(vias allowed)
			(pads allowed)
			(copperpour allowed)
			(footprints allowed)
		)
		(placement
			(enabled no)
			(sheetname "")
		)
		(fill
			(thermal_gap 0.5)
			(thermal_bridge_width 0.5)
			(island_removal_mode 0)
		)
		(polygon
			(pts
				(xy 268.56436 -284.300676) (xy 268.56436 -283.750258) (xy 269.12316 -283.750258) (xy 269.12316 -284.300676)
			)
		)
	)
	(zone
		(layer "In11.Cu")
		(hatch none 0.5)
		(connect_pads
			(clearance 0)
		)
		(min_thickness 0.25)
		(keepout
			(tracks allowed)
			(vias allowed)
			(pads allowed)
			(copperpour allowed)
			(footprints allowed)
		)
		(placement
			(enabled no)
			(sheetname "")
		)
		(fill
			(thermal_gap 0.5)
			(thermal_bridge_width 0.5)
			(island_removal_mode 0)
		)
		(polygon
			(pts
				(xy 421.010842 -238.914686) (xy 421.010842 -239.190276) (xy 420.452042 -239.190276) (xy 420.452042 -238.914686)
			)
		)
	)
	(zone
		(layer "In11.Cu")
		(hatch none 0.5)
		(connect_pads
			(clearance 0)
		)
		(min_thickness 0.25)
		(keepout
			(tracks allowed)
			(vias allowed)
			(pads allowed)
			(copperpour allowed)
			(footprints allowed)
		)
		(placement
			(enabled no)
			(sheetname "")
		)
		(fill
			(thermal_gap 0.5)
			(thermal_bridge_width 0.5)
			(island_removal_mode 0)
		)
		(polygon
			(pts
				(xy 180.614574 -245.714774) (xy 180.614574 -245.990364) (xy 180.055774 -245.990364) (xy 180.055774 -245.714774)
			)
		)
	)
	(zone
		(layer "In11.Cu")
		(hatch none 0.5)
		(connect_pads
			(clearance 0)
		)
		(min_thickness 0.25)
		(keepout
			(tracks allowed)
			(vias allowed)
			(pads allowed)
			(copperpour allowed)
			(footprints allowed)
		)
		(placement
			(enabled no)
			(sheetname "")
		)
		(fill
			(thermal_gap 0.5)
			(thermal_bridge_width 0.5)
			(island_removal_mode 0)
		)
		(polygon
			(pts
				(xy 268.51102 -223.94672) (xy 268.51102 -223.397064) (xy 269.14094 -223.397064) (xy 269.14094 -223.94672)
			)
		)
	)
	(zone
		(layer "In11.Cu")
		(hatch none 0.5)
		(connect_pads
			(clearance 0)
		)
		(min_thickness 0.25)
		(keepout
			(tracks allowed)
			(vias allowed)
			(pads allowed)
			(copperpour allowed)
			(footprints allowed)
		)
		(placement
			(enabled no)
			(sheetname "")
		)
		(fill
			(thermal_gap 0.5)
			(thermal_bridge_width 0.5)
			(island_removal_mode 0)
		)
		(polygon
			(pts
				(xy 436.098442 -212.564726) (xy 436.098442 -212.840316) (xy 435.539642 -212.840316) (xy 435.539642 -212.564726)
			)
		)
	)
	(zone
		(layer "In11.Cu")
		(hatch none 0.5)
		(connect_pads
			(clearance 0)
		)
		(min_thickness 0.25)
		(keepout
			(tracks allowed)
			(vias allowed)
			(pads allowed)
			(copperpour allowed)
			(footprints allowed)
		)
		(placement
			(enabled no)
			(sheetname "")
		)
		(fill
			(thermal_gap 0.5)
			(thermal_bridge_width 0.5)
			(island_removal_mode 0)
		)
		(polygon
			(pts
				(xy 450.636386 -216.068402) (xy 450.636386 -215.792812) (xy 451.195186 -215.792812) (xy 451.195186 -216.068402)
			)
		)
	)
	(zone
		(layer "In11.Cu")
		(hatch none 0.5)
		(connect_pads
			(clearance 0)
		)
		(min_thickness 0.25)
		(keepout
			(tracks not_allowed)
			(vias allowed)
			(pads allowed)
			(copperpour not_allowed)
			(footprints allowed)
		)
		(placement
			(enabled no)
			(sheetname "")
		)
		(fill
			(thermal_gap 0.5)
			(thermal_bridge_width 0.5)
			(island_removal_mode 0)
		)
		(polygon
			(pts
				(arc
					(start 391.242042 -428.960788)
					(mid 391.26436 -429.01467)
					(end 391.318242 -429.036988)
				)
				(arc
					(start 392.258042 -429.036988)
					(mid 392.311924 -429.01467)
					(end 392.334242 -428.960788)
				)
				(arc
					(start 392.334242 -426.419264)
					(mid 392.311924 -426.365382)
					(end 392.258042 -426.343064)
				)
				(arc
					(start 391.318242 -426.343064)
					(mid 391.26436 -426.365382)
					(end 391.242042 -426.419264)
				)
			)
		)
	)
	(zone
		(layer "In11.Cu")
		(hatch none 0.5)
		(connect_pads
			(clearance 0)
		)
		(min_thickness 0.25)
		(keepout
			(tracks allowed)
			(vias allowed)
			(pads allowed)
			(copperpour allowed)
			(footprints allowed)
		)
		(placement
			(enabled no)
			(sheetname "")
		)
		(fill
			(thermal_gap 0.5)
			(thermal_bridge_width 0.5)
			(island_removal_mode 0)
		)
		(polygon
			(pts
				(xy 424.561254 -197.368414) (xy 424.561254 -197.092824) (xy 425.120054 -197.092824) (xy 425.120054 -197.368414)
			)
		)
	)
	(zone
		(layer "In11.Cu")
		(hatch none 0.5)
		(connect_pads
			(clearance 0)
		)
		(min_thickness 0.25)
		(keepout
			(tracks allowed)
			(vias allowed)
			(pads allowed)
			(copperpour allowed)
			(footprints allowed)
		)
		(placement
			(enabled no)
			(sheetname "")
		)
		(fill
			(thermal_gap 0.5)
			(thermal_bridge_width 0.5)
			(island_removal_mode 0)
		)
		(polygon
			(pts
				(xy 50.746152 -197.59676) (xy 50.746152 -197.047104) (xy 51.376072 -197.047104) (xy 51.376072 -197.59676)
			)
		)
	)
	(zone
		(layer "In11.Cu")
		(hatch none 0.5)
		(connect_pads
			(clearance 0)
		)
		(min_thickness 0.25)
		(keepout
			(tracks allowed)
			(vias allowed)
			(pads allowed)
			(copperpour allowed)
			(footprints allowed)
		)
		(placement
			(enabled no)
			(sheetname "")
		)
		(fill
			(thermal_gap 0.5)
			(thermal_bridge_width 0.5)
			(island_removal_mode 0)
		)
		(polygon
			(pts
				(xy 172.521118 -272.16862) (xy 172.521118 -271.89303) (xy 173.079918 -271.89303) (xy 173.079918 -272.16862)
			)
		)
	)
	(zone
		(layer "In11.Cu")
		(hatch none 0.5)
		(connect_pads
			(clearance 0)
		)
		(min_thickness 0.25)
		(keepout
			(tracks allowed)
			(vias allowed)
			(pads allowed)
			(copperpour allowed)
			(footprints allowed)
		)
		(placement
			(enabled no)
			(sheetname "")
		)
		(fill
			(thermal_gap 0.5)
			(thermal_bridge_width 0.5)
			(island_removal_mode 0)
		)
		(polygon
			(pts
				(xy 161.533586 -224.568512) (xy 161.533586 -224.292922) (xy 162.092386 -224.292922) (xy 162.092386 -224.568512)
			)
		)
	)
	(zone
		(layer "In11.Cu")
		(hatch none 0.5)
		(connect_pads
			(clearance 0)
		)
		(min_thickness 0.25)
		(keepout
			(tracks allowed)
			(vias allowed)
			(pads allowed)
			(copperpour allowed)
			(footprints allowed)
		)
		(placement
			(enabled no)
			(sheetname "")
		)
		(fill
			(thermal_gap 0.5)
			(thermal_bridge_width 0.5)
			(island_removal_mode 0)
		)
		(polygon
			(pts
				(xy 172.521118 -238.168434) (xy 172.521118 -237.892844) (xy 173.079918 -237.892844) (xy 173.079918 -238.168434)
			)
		)
	)
	(zone
		(layer "In11.Cu")
		(hatch none 0.5)
		(connect_pads
			(clearance 0)
		)
		(min_thickness 0.25)
		(keepout
			(tracks allowed)
			(vias allowed)
			(pads allowed)
			(copperpour allowed)
			(footprints allowed)
		)
		(placement
			(enabled no)
			(sheetname "")
		)
		(fill
			(thermal_gap 0.5)
			(thermal_bridge_width 0.5)
			(island_removal_mode 0)
		)
		(polygon
			(pts
				(xy 20.570952 -200.14692) (xy 20.570952 -199.597264) (xy 21.200872 -199.597264) (xy 21.200872 -200.14692)
			)
		)
	)
	(zone
		(layer "In11.Cu")
		(hatch none 0.5)
		(connect_pads
			(clearance 0)
		)
		(min_thickness 0.25)
		(keepout
			(tracks allowed)
			(vias allowed)
			(pads allowed)
			(copperpour allowed)
			(footprints allowed)
		)
		(placement
			(enabled no)
			(sheetname "")
		)
		(fill
			(thermal_gap 0.5)
			(thermal_bridge_width 0.5)
			(island_removal_mode 0)
		)
		(polygon
			(pts
				(xy 202.696318 -283.218382) (xy 202.696318 -282.942792) (xy 203.255118 -282.942792) (xy 203.255118 -283.218382)
			)
		)
	)
	(zone
		(layer "In11.Cu")
		(hatch none 0.5)
		(connect_pads
			(clearance 0)
		)
		(min_thickness 0.25)
		(keepout
			(tracks allowed)
			(vias allowed)
			(pads allowed)
			(copperpour allowed)
			(footprints allowed)
		)
		(placement
			(enabled no)
			(sheetname "")
		)
		(fill
			(thermal_gap 0.5)
			(thermal_bridge_width 0.5)
			(island_removal_mode 0)
		)
		(polygon
			(pts
				(xy 50.746152 -214.596726) (xy 50.746152 -214.04707) (xy 51.376072 -214.04707) (xy 51.376072 -214.596726)
			)
		)
	)
	(zone
		(layer "In11.Cu")
		(hatch none 0.5)
		(connect_pads
			(clearance 0)
		)
		(min_thickness 0.25)
		(keepout
			(tracks allowed)
			(vias allowed)
			(pads allowed)
			(copperpour allowed)
			(footprints allowed)
		)
		(placement
			(enabled no)
			(sheetname "")
		)
		(fill
			(thermal_gap 0.5)
			(thermal_bridge_width 0.5)
			(island_removal_mode 0)
		)
		(polygon
			(pts
				(xy 421.010842 -258.464812) (xy 421.010842 -258.740402) (xy 420.452042 -258.740402) (xy 420.452042 -258.464812)
			)
		)
	)
	(zone
		(layer "In11.Cu")
		(hatch none 0.5)
		(connect_pads
			(clearance 0)
		)
		(min_thickness 0.25)
		(keepout
			(tracks allowed)
			(vias allowed)
			(pads allowed)
			(copperpour allowed)
			(footprints allowed)
		)
		(placement
			(enabled no)
			(sheetname "")
		)
		(fill
			(thermal_gap 0.5)
			(thermal_bridge_width 0.5)
			(island_removal_mode 0)
		)
		(polygon
			(pts
				(xy 420.461186 -296.818558) (xy 420.461186 -296.542968) (xy 421.019986 -296.542968) (xy 421.019986 -296.818558)
			)
		)
	)
	(zone
		(layer "In11.Cu")
		(hatch none 0.5)
		(connect_pads
			(clearance 0)
		)
		(min_thickness 0.25)
		(keepout
			(tracks allowed)
			(vias allowed)
			(pads allowed)
			(copperpour allowed)
			(footprints allowed)
		)
		(placement
			(enabled no)
			(sheetname "")
		)
		(fill
			(thermal_gap 0.5)
			(thermal_bridge_width 0.5)
			(island_removal_mode 0)
		)
		(polygon
			(pts
				(xy 294.586152 -240.096802) (xy 294.586152 -239.547146) (xy 295.216072 -239.547146) (xy 295.216072 -240.096802)
			)
		)
	)
	(zone
		(layer "In11.Cu")
		(hatch none 0.5)
		(connect_pads
			(clearance 0)
		)
		(min_thickness 0.25)
		(keepout
			(tracks allowed)
			(vias allowed)
			(pads allowed)
			(copperpour allowed)
			(footprints allowed)
		)
		(placement
			(enabled no)
			(sheetname "")
		)
		(fill
			(thermal_gap 0.5)
			(thermal_bridge_width 0.5)
			(island_removal_mode 0)
		)
		(polygon
			(pts
				(xy 50.771552 -260.496812) (xy 50.771552 -259.947156) (xy 51.401472 -259.947156) (xy 51.401472 -260.496812)
			)
		)
	)
	(zone
		(layer "In11.Cu")
		(hatch none 0.5)
		(connect_pads
			(clearance 0)
		)
		(min_thickness 0.25)
		(keepout
			(tracks allowed)
			(vias allowed)
			(pads allowed)
			(copperpour allowed)
			(footprints allowed)
		)
		(placement
			(enabled no)
			(sheetname "")
		)
		(fill
			(thermal_gap 0.5)
			(thermal_bridge_width 0.5)
			(island_removal_mode 0)
		)
		(polygon
			(pts
				(xy 35.48126 -267.642848) (xy 35.48126 -266.083288) (xy 36.7538 -266.083288) (xy 36.7538 -267.642848)
			)
		)
	)
	(zone
		(layer "In11.Cu")
		(hatch none 0.5)
		(connect_pads
			(clearance 0)
		)
		(min_thickness 0.25)
		(keepout
			(tracks allowed)
			(vias allowed)
			(pads allowed)
			(copperpour allowed)
			(footprints allowed)
		)
		(placement
			(enabled no)
			(sheetname "")
		)
		(fill
			(thermal_gap 0.5)
			(thermal_bridge_width 0.5)
			(island_removal_mode 0)
		)
		(polygon
			(pts
				(xy 298.71162 -302.997108) (xy 298.71162 -302.447452) (xy 299.34154 -302.447452) (xy 299.34154 -302.997108)
			)
		)
	)
	(zone
		(layer "In11.Cu")
		(hatch none 0.5)
		(connect_pads
			(clearance 0)
		)
		(min_thickness 0.25)
		(keepout
			(tracks allowed)
			(vias allowed)
			(pads allowed)
			(copperpour allowed)
			(footprints allowed)
		)
		(placement
			(enabled no)
			(sheetname "")
		)
		(fill
			(thermal_gap 0.5)
			(thermal_bridge_width 0.5)
			(island_removal_mode 0)
		)
		(polygon
			(pts
				(xy 372.98122 -341.539068) (xy 372.98122 -339.844888) (xy 377.84532 -339.844888) (xy 377.84532 -341.539068)
			)
		)
	)
	(zone
		(layer "In11.Cu")
		(hatch none 0.5)
		(connect_pads
			(clearance 0)
		)
		(min_thickness 0.25)
		(keepout
			(tracks allowed)
			(vias allowed)
			(pads allowed)
			(copperpour allowed)
			(footprints allowed)
		)
		(placement
			(enabled no)
			(sheetname "")
		)
		(fill
			(thermal_gap 0.5)
			(thermal_bridge_width 0.5)
			(island_removal_mode 0)
		)
		(polygon
			(pts
				(xy 294.586152 -264.74674) (xy 294.586152 -264.197084) (xy 295.216072 -264.197084) (xy 295.216072 -264.74674)
			)
		)
	)
	(zone
		(layer "In11.Cu")
		(hatch none 0.5)
		(connect_pads
			(clearance 0)
		)
		(min_thickness 0.25)
		(keepout
			(tracks allowed)
			(vias allowed)
			(pads allowed)
			(copperpour allowed)
			(footprints allowed)
		)
		(placement
			(enabled no)
			(sheetname "")
		)
		(fill
			(thermal_gap 0.5)
			(thermal_bridge_width 0.5)
			(island_removal_mode 0)
		)
		(polygon
			(pts
				(xy 321.80276 -348.925388) (xy 321.80276 -347.170248) (xy 322.84416 -347.170248) (xy 322.84416 -348.925388)
			)
		)
	)
	(zone
		(layer "In11.Cu")
		(hatch none 0.5)
		(connect_pads
			(clearance 0)
		)
		(min_thickness 0.25)
		(keepout
			(tracks allowed)
			(vias allowed)
			(pads allowed)
			(copperpour allowed)
			(footprints allowed)
		)
		(placement
			(enabled no)
			(sheetname "")
		)
		(fill
			(thermal_gap 0.5)
			(thermal_bridge_width 0.5)
			(island_removal_mode 0)
		)
		(polygon
			(pts
				(xy 20.570952 -237.546896) (xy 20.570952 -236.99724) (xy 21.200872 -236.99724) (xy 21.200872 -237.546896)
			)
		)
	)
	(zone
		(layer "In11.Cu")
		(hatch none 0.5)
		(connect_pads
			(clearance 0)
		)
		(min_thickness 0.25)
		(keepout
			(tracks allowed)
			(vias allowed)
			(pads allowed)
			(copperpour allowed)
			(footprints allowed)
		)
		(placement
			(enabled no)
			(sheetname "")
		)
		(fill
			(thermal_gap 0.5)
			(thermal_bridge_width 0.5)
			(island_removal_mode 0)
		)
		(polygon
			(pts
				(xy 435.548786 -227.968556) (xy 435.548786 -227.692966) (xy 436.107586 -227.692966) (xy 436.107586 -227.968556)
			)
		)
	)
	(zone
		(layer "In11.Cu")
		(hatch none 0.5)
		(connect_pads
			(clearance 0)
		)
		(min_thickness 0.25)
		(keepout
			(tracks allowed)
			(vias allowed)
			(pads allowed)
			(copperpour allowed)
			(footprints allowed)
		)
		(placement
			(enabled no)
			(sheetname "")
		)
		(fill
			(thermal_gap 0.5)
			(thermal_bridge_width 0.5)
			(island_removal_mode 0)
		)
		(polygon
			(pts
				(xy 203.245974 -276.314662) (xy 203.245974 -276.590252) (xy 202.687174 -276.590252) (xy 202.687174 -276.314662)
			)
		)
	)
	(zone
		(layer "In11.Cu")
		(hatch none 0.5)
		(connect_pads
			(clearance 0)
		)
		(min_thickness 0.25)
		(keepout
			(tracks allowed)
			(vias allowed)
			(pads allowed)
			(copperpour allowed)
			(footprints allowed)
		)
		(placement
			(enabled no)
			(sheetname "")
		)
		(fill
			(thermal_gap 0.5)
			(thermal_bridge_width 0.5)
			(island_removal_mode 0)
		)
		(polygon
			(pts
				(xy 421.010842 -266.114784) (xy 421.010842 -266.390374) (xy 420.452042 -266.390374) (xy 420.452042 -266.114784)
			)
		)
	)
	(zone
		(layer "In11.Cu")
		(hatch none 0.5)
		(connect_pads
			(clearance 0)
		)
		(min_thickness 0.25)
		(keepout
			(tracks allowed)
			(vias allowed)
			(pads allowed)
			(copperpour allowed)
			(footprints allowed)
		)
		(placement
			(enabled no)
			(sheetname "")
		)
		(fill
			(thermal_gap 0.5)
			(thermal_bridge_width 0.5)
			(island_removal_mode 0)
		)
		(polygon
			(pts
				(xy 436.098442 -211.714842) (xy 436.098442 -211.990432) (xy 435.539642 -211.990432) (xy 435.539642 -211.714842)
			)
		)
	)
	(zone
		(layer "In11.Cu")
		(hatch none 0.5)
		(connect_pads
			(clearance 0)
		)
		(min_thickness 0.25)
		(keepout
			(tracks allowed)
			(vias allowed)
			(pads allowed)
			(copperpour allowed)
			(footprints allowed)
		)
		(placement
			(enabled no)
			(sheetname "")
		)
		(fill
			(thermal_gap 0.5)
			(thermal_bridge_width 0.5)
			(island_removal_mode 0)
		)
		(polygon
			(pts
				(xy 294.586152 -307.246782) (xy 294.586152 -306.697126) (xy 295.216072 -306.697126) (xy 295.216072 -307.246782)
			)
		)
	)
	(zone
		(layer "In11.Cu")
		(hatch none 0.5)
		(connect_pads
			(clearance 0)
		)
		(min_thickness 0.25)
		(keepout
			(tracks allowed)
			(vias allowed)
			(pads allowed)
			(copperpour allowed)
			(footprints allowed)
		)
		(placement
			(enabled no)
			(sheetname "")
		)
		(fill
			(thermal_gap 0.5)
			(thermal_bridge_width 0.5)
			(island_removal_mode 0)
		)
		(polygon
			(pts
				(xy 173.070774 -204.064616) (xy 173.070774 -204.340206) (xy 172.511974 -204.340206) (xy 172.511974 -204.064616)
			)
		)
	)
	(zone
		(layer "In11.Cu")
		(hatch none 0.5)
		(connect_pads
			(clearance 0)
		)
		(min_thickness 0.25)
		(keepout
			(tracks allowed)
			(vias allowed)
			(pads allowed)
			(copperpour allowed)
			(footprints allowed)
		)
		(placement
			(enabled no)
			(sheetname "")
		)
		(fill
			(thermal_gap 0.5)
			(thermal_bridge_width 0.5)
			(island_removal_mode 0)
		)
		(polygon
			(pts
				(xy 173.070774 -207.46466) (xy 173.070774 -207.74025) (xy 172.511974 -207.74025) (xy 172.511974 -207.46466)
			)
		)
	)
	(zone
		(layer "In11.Cu")
		(hatch none 0.5)
		(connect_pads
			(clearance 0)
		)
		(min_thickness 0.25)
		(keepout
			(tracks allowed)
			(vias allowed)
			(pads allowed)
			(copperpour allowed)
			(footprints allowed)
		)
		(placement
			(enabled no)
			(sheetname "")
		)
		(fill
			(thermal_gap 0.5)
			(thermal_bridge_width 0.5)
			(island_removal_mode 0)
		)
		(polygon
			(pts
				(xy 191.632586 -268.768576) (xy 191.632586 -268.492986) (xy 192.191386 -268.492986) (xy 192.191386 -268.768576)
			)
		)
	)
	(zone
		(layer "In11.Cu")
		(hatch none 0.5)
		(connect_pads
			(clearance 0)
		)
		(min_thickness 0.25)
		(keepout
			(tracks allowed)
			(vias allowed)
			(pads allowed)
			(copperpour allowed)
			(footprints allowed)
		)
		(placement
			(enabled no)
			(sheetname "")
		)
		(fill
			(thermal_gap 0.5)
			(thermal_bridge_width 0.5)
			(island_removal_mode 0)
		)
		(polygon
			(pts
				(xy 432.65471 -258.464812) (xy 432.65471 -258.740402) (xy 432.09591 -258.740402) (xy 432.09591 -258.464812)
			)
		)
	)
	(zone
		(layer "In11.Cu")
		(hatch none 0.5)
		(connect_pads
			(clearance 0)
		)
		(min_thickness 0.25)
		(keepout
			(tracks allowed)
			(vias allowed)
			(pads allowed)
			(copperpour allowed)
			(footprints allowed)
		)
		(placement
			(enabled no)
			(sheetname "")
		)
		(fill
			(thermal_gap 0.5)
			(thermal_bridge_width 0.5)
			(island_removal_mode 0)
		)
		(polygon
			(pts
				(xy 173.070774 -267.814806) (xy 173.070774 -268.090396) (xy 172.511974 -268.090396) (xy 172.511974 -267.814806)
			)
		)
	)
	(zone
		(layer "In11.Cu")
		(hatch none 0.5)
		(connect_pads
			(clearance 0)
		)
		(min_thickness 0.25)
		(keepout
			(tracks allowed)
			(vias allowed)
			(pads allowed)
			(copperpour allowed)
			(footprints allowed)
		)
		(placement
			(enabled no)
			(sheetname "")
		)
		(fill
			(thermal_gap 0.5)
			(thermal_bridge_width 0.5)
			(island_removal_mode 0)
		)
		(polygon
			(pts
				(xy 173.070774 -240.614708) (xy 173.070774 -240.890298) (xy 172.511974 -240.890298) (xy 172.511974 -240.614708)
			)
		)
	)
	(zone
		(layer "In11.Cu")
		(hatch none 0.5)
		(connect_pads
			(clearance 0)
		)
		(min_thickness 0.25)
		(keepout
			(tracks allowed)
			(vias allowed)
			(pads allowed)
			(copperpour allowed)
			(footprints allowed)
		)
		(placement
			(enabled no)
			(sheetname "")
		)
		(fill
			(thermal_gap 0.5)
			(thermal_bridge_width 0.5)
			(island_removal_mode 0)
		)
		(polygon
			(pts
				(xy 177.170842 -199.814688) (xy 177.170842 -200.090278) (xy 176.612042 -200.090278) (xy 176.612042 -199.814688)
			)
		)
	)
	(zone
		(layer "In11.Cu")
		(hatch none 0.5)
		(connect_pads
			(clearance 0)
		)
		(min_thickness 0.25)
		(keepout
			(tracks allowed)
			(vias allowed)
			(pads allowed)
			(copperpour allowed)
			(footprints allowed)
		)
		(placement
			(enabled no)
			(sheetname "")
		)
		(fill
			(thermal_gap 0.5)
			(thermal_bridge_width 0.5)
			(island_removal_mode 0)
		)
		(polygon
			(pts
				(xy 276.05482 -242.646962) (xy 276.05482 -242.097306) (xy 276.68474 -242.097306) (xy 276.68474 -242.646962)
			)
		)
	)
	(zone
		(layer "In11.Cu")
		(hatch none 0.5)
		(connect_pads
			(clearance 0)
		)
		(min_thickness 0.25)
		(keepout
			(tracks allowed)
			(vias allowed)
			(pads allowed)
			(copperpour allowed)
			(footprints allowed)
		)
		(placement
			(enabled no)
			(sheetname "")
		)
		(fill
			(thermal_gap 0.5)
			(thermal_bridge_width 0.5)
			(island_removal_mode 0)
		)
		(polygon
			(pts
				(xy 435.548786 -278.11857) (xy 435.548786 -277.84298) (xy 436.107586 -277.84298) (xy 436.107586 -278.11857)
			)
		)
	)
	(zone
		(layer "In11.Cu")
		(hatch none 0.5)
		(connect_pads
			(clearance 0)
		)
		(min_thickness 0.25)
		(keepout
			(tracks allowed)
			(vias allowed)
			(pads allowed)
			(copperpour allowed)
			(footprints allowed)
		)
		(placement
			(enabled no)
			(sheetname "")
		)
		(fill
			(thermal_gap 0.5)
			(thermal_bridge_width 0.5)
			(island_removal_mode 0)
		)
		(polygon
			(pts
				(xy 46.646084 -293.64686) (xy 46.646084 -293.097204) (xy 47.276004 -293.097204) (xy 47.276004 -293.64686)
			)
		)
	)
	(zone
		(layer "In11.Cu")
		(hatch none 0.5)
		(connect_pads
			(clearance 0)
		)
		(min_thickness 0.25)
		(keepout
			(tracks allowed)
			(vias allowed)
			(pads allowed)
			(copperpour allowed)
			(footprints allowed)
		)
		(placement
			(enabled no)
			(sheetname "")
		)
		(fill
			(thermal_gap 0.5)
			(thermal_bridge_width 0.5)
			(island_removal_mode 0)
		)
		(polygon
			(pts
				(xy 425.11091 -302.664622) (xy 425.11091 -302.940212) (xy 424.55211 -302.940212) (xy 424.55211 -302.664622)
			)
		)
	)
	(zone
		(layer "In11.Cu")
		(hatch none 0.5)
		(connect_pads
			(clearance 0)
		)
		(min_thickness 0.25)
		(keepout
			(tracks allowed)
			(vias allowed)
			(pads allowed)
			(copperpour allowed)
			(footprints allowed)
		)
		(placement
			(enabled no)
			(sheetname "")
		)
		(fill
			(thermal_gap 0.5)
			(thermal_bridge_width 0.5)
			(island_removal_mode 0)
		)
		(polygon
			(pts
				(xy 50.771552 -293.647114) (xy 50.771552 -293.097458) (xy 51.401472 -293.097458) (xy 51.401472 -293.647114)
			)
		)
	)
	(zone
		(layer "In11.Cu")
		(hatch none 0.5)
		(connect_pads
			(clearance 0)
		)
		(min_thickness 0.25)
		(keepout
			(tracks allowed)
			(vias allowed)
			(pads allowed)
			(copperpour allowed)
			(footprints allowed)
		)
		(placement
			(enabled no)
			(sheetname "")
		)
		(fill
			(thermal_gap 0.5)
			(thermal_bridge_width 0.5)
			(island_removal_mode 0)
		)
		(polygon
			(pts
				(xy 177.170842 -294.164766) (xy 177.170842 -294.440356) (xy 176.612042 -294.440356) (xy 176.612042 -294.164766)
			)
		)
	)
	(zone
		(layer "In11.Cu")
		(hatch none 0.5)
		(connect_pads
			(clearance 0)
		)
		(min_thickness 0.25)
		(keepout
			(tracks allowed)
			(vias allowed)
			(pads allowed)
			(copperpour allowed)
			(footprints allowed)
		)
		(placement
			(enabled no)
			(sheetname "")
		)
		(fill
			(thermal_gap 0.5)
			(thermal_bridge_width 0.5)
			(island_removal_mode 0)
		)
		(polygon
			(pts
				(xy 414.9852 -366.865408) (xy 414.9852 -365.669068) (xy 416.33648 -365.669068) (xy 416.33648 -366.865408)
			)
		)
	)
	(zone
		(layer "In11.Cu")
		(hatch none 0.5)
		(connect_pads
			(clearance 0)
		)
		(min_thickness 0.25)
		(keepout
			(tracks allowed)
			(vias allowed)
			(pads allowed)
			(copperpour allowed)
			(footprints allowed)
		)
		(placement
			(enabled no)
			(sheetname "")
		)
		(fill
			(thermal_gap 0.5)
			(thermal_bridge_width 0.5)
			(island_removal_mode 0)
		)
		(polygon
			(pts
				(xy 99.41052 -338.869528) (xy 99.41052 -334.399128) (xy 114.22126 -334.399128) (xy 114.22126 -338.869528)
			)
		)
	)
	(zone
		(layer "In11.Cu")
		(hatch none 0.5)
		(connect_pads
			(clearance 0)
		)
		(min_thickness 0.25)
		(keepout
			(tracks allowed)
			(vias allowed)
			(pads allowed)
			(copperpour allowed)
			(footprints allowed)
		)
		(placement
			(enabled no)
			(sheetname "")
		)
		(fill
			(thermal_gap 0.5)
			(thermal_bridge_width 0.5)
			(island_removal_mode 0)
		)
		(polygon
			(pts
				(xy 451.186042 -300.114716) (xy 451.186042 -300.390306) (xy 450.697092 -300.390306) (xy 450.697092 -300.787562)
				(xy 451.164452 -300.787562) (xy 451.164452 -301.289212) (xy 449.672456 -301.289212) (xy 449.672456 -300.114716)
				(xy 450.627242 -300.114716)
			)
		)
	)
	(zone
		(layer "In11.Cu")
		(hatch none 0.5)
		(connect_pads
			(clearance 0)
		)
		(min_thickness 0.25)
		(keepout
			(tracks allowed)
			(vias allowed)
			(pads allowed)
			(copperpour allowed)
			(footprints allowed)
		)
		(placement
			(enabled no)
			(sheetname "")
		)
		(fill
			(thermal_gap 0.5)
			(thermal_bridge_width 0.5)
			(island_removal_mode 0)
		)
		(polygon
			(pts
				(xy 450.636386 -263.66851) (xy 450.636386 -263.39292) (xy 451.195186 -263.39292) (xy 451.195186 -263.66851)
			)
		)
	)
	(zone
		(layer "In11.Cu")
		(hatch none 0.5)
		(connect_pads
			(clearance 0)
		)
		(min_thickness 0.25)
		(keepout
			(tracks allowed)
			(vias allowed)
			(pads allowed)
			(copperpour allowed)
			(footprints allowed)
		)
		(placement
			(enabled no)
			(sheetname "")
		)
		(fill
			(thermal_gap 0.5)
			(thermal_bridge_width 0.5)
			(island_removal_mode 0)
		)
		(polygon
			(pts
				(xy 202.696318 -272.742914) (xy 203.255118 -272.742914) (xy 203.255118 -273.018504) (xy 203.255118 -273.215608)
				(xy 202.286108 -273.215608) (xy 202.286108 -273.571462) (xy 201.925936 -273.571462) (xy 201.925936 -272.742914)
			)
		)
	)
	(zone
		(layer "In11.Cu")
		(hatch none 0.5)
		(connect_pads
			(clearance 0)
		)
		(min_thickness 0.25)
		(keepout
			(tracks allowed)
			(vias allowed)
			(pads allowed)
			(copperpour allowed)
			(footprints allowed)
		)
		(placement
			(enabled no)
			(sheetname "")
		)
		(fill
			(thermal_gap 0.5)
			(thermal_bridge_width 0.5)
			(island_removal_mode 0)
		)
		(polygon
			(pts
				(xy 20.624292 -309.800752) (xy 20.624292 -309.250334) (xy 21.183092 -309.250334) (xy 21.183092 -309.800752)
			)
		)
	)
	(zone
		(layer "In11.Cu")
		(hatch none 0.5)
		(connect_pads
			(clearance 0)
		)
		(min_thickness 0.25)
		(keepout
			(tracks allowed)
			(vias allowed)
			(pads allowed)
			(copperpour allowed)
			(footprints allowed)
		)
		(placement
			(enabled no)
			(sheetname "")
		)
		(fill
			(thermal_gap 0.5)
			(thermal_bridge_width 0.5)
			(island_removal_mode 0)
		)
		(polygon
			(pts
				(xy 202.012042 -269.514828) (xy 202.012042 -269.790418) (xy 201.453242 -269.790418) (xy 201.453242 -269.514828)
			)
		)
	)
	(zone
		(layer "In11.Cu")
		(hatch none 0.5)
		(connect_pads
			(clearance 0)
		)
		(min_thickness 0.25)
		(keepout
			(tracks allowed)
			(vias allowed)
			(pads allowed)
			(copperpour allowed)
			(footprints allowed)
		)
		(placement
			(enabled no)
			(sheetname "")
		)
		(fill
			(thermal_gap 0.5)
			(thermal_bridge_width 0.5)
			(island_removal_mode 0)
		)
		(polygon
			(pts
				(xy 451.186042 -220.214698) (xy 451.186042 -220.490288) (xy 450.627242 -220.490288) (xy 450.627242 -220.214698)
			)
		)
	)
	(zone
		(layer "In11.Cu")
		(hatch none 0.5)
		(connect_pads
			(clearance 0)
		)
		(min_thickness 0.25)
		(keepout
			(tracks allowed)
			(vias allowed)
			(pads allowed)
			(copperpour allowed)
			(footprints allowed)
		)
		(placement
			(enabled no)
			(sheetname "")
		)
		(fill
			(thermal_gap 0.5)
			(thermal_bridge_width 0.5)
			(island_removal_mode 0)
		)
		(polygon
			(pts
				(xy 348.1324 -297.934888) (xy 348.1324 -292.885368) (xy 350.23806 -292.885368) (xy 350.23806 -297.934888)
			)
		)
	)
	(zone
		(layer "In11.Cu")
		(hatch none 0.5)
		(connect_pads
			(clearance 0)
		)
		(min_thickness 0.25)
		(keepout
			(tracks allowed)
			(vias allowed)
			(pads allowed)
			(copperpour allowed)
			(footprints allowed)
		)
		(placement
			(enabled no)
			(sheetname "")
		)
		(fill
			(thermal_gap 0.5)
			(thermal_bridge_width 0.5)
			(island_removal_mode 0)
		)
		(polygon
			(pts
				(xy 268.56436 -302.15078) (xy 268.56436 -301.600362) (xy 269.12316 -301.600362) (xy 269.12316 -302.15078)
			)
		)
	)
	(zone
		(layer "In11.Cu")
		(hatch none 0.5)
		(connect_pads
			(clearance 0)
		)
		(min_thickness 0.25)
		(keepout
			(tracks allowed)
			(vias allowed)
			(pads allowed)
			(copperpour allowed)
			(footprints allowed)
		)
		(placement
			(enabled no)
			(sheetname "")
		)
		(fill
			(thermal_gap 0.5)
			(thermal_bridge_width 0.5)
			(island_removal_mode 0)
		)
		(polygon
			(pts
				(xy 46.646084 -259.646928) (xy 46.646084 -259.097272) (xy 47.276004 -259.097272) (xy 47.276004 -259.646928)
			)
		)
	)
	(zone
		(layer "In11.Cu")
		(hatch none 0.5)
		(connect_pads
			(clearance 0)
		)
		(min_thickness 0.25)
		(keepout
			(tracks allowed)
			(vias allowed)
			(pads allowed)
			(copperpour allowed)
			(footprints allowed)
		)
		(placement
			(enabled no)
			(sheetname "")
		)
		(fill
			(thermal_gap 0.5)
			(thermal_bridge_width 0.5)
			(island_removal_mode 0)
		)
		(polygon
			(pts
				(xy 203.245974 -200.664826) (xy 203.245974 -200.940416) (xy 202.687174 -200.940416) (xy 202.467718 -200.940416)
				(xy 202.467718 -200.36409) (xy 203.245974 -200.36409)
			)
		)
	)
	(zone
		(layer "In11.Cu")
		(hatch none 0.5)
		(connect_pads
			(clearance 0)
		)
		(min_thickness 0.25)
		(keepout
			(tracks allowed)
			(vias allowed)
			(pads allowed)
			(copperpour allowed)
			(footprints allowed)
		)
		(placement
			(enabled no)
			(sheetname "")
		)
		(fill
			(thermal_gap 0.5)
			(thermal_bridge_width 0.5)
			(island_removal_mode 0)
		)
		(polygon
			(pts
				(xy 28.114752 -242.646962) (xy 28.114752 -242.097306) (xy 28.744672 -242.097306) (xy 28.744672 -242.646962)
			)
		)
	)
	(zone
		(layer "In11.Cu")
		(hatch none 0.5)
		(connect_pads
			(clearance 0)
		)
		(min_thickness 0.25)
		(keepout
			(tracks allowed)
			(vias allowed)
			(pads allowed)
			(copperpour allowed)
			(footprints allowed)
		)
		(placement
			(enabled no)
			(sheetname "")
		)
		(fill
			(thermal_gap 0.5)
			(thermal_bridge_width 0.5)
			(island_removal_mode 0)
		)
		(polygon
			(pts
				(xy 203.245974 -203.214732) (xy 203.245974 -203.490322) (xy 202.687174 -203.490322) (xy 202.687174 -203.214732)
			)
		)
	)
	(zone
		(layer "In11.Cu")
		(hatch none 0.5)
		(connect_pads
			(clearance 0)
		)
		(min_thickness 0.25)
		(keepout
			(tracks allowed)
			(vias allowed)
			(pads allowed)
			(copperpour allowed)
			(footprints allowed)
		)
		(placement
			(enabled no)
			(sheetname "")
		)
		(fill
			(thermal_gap 0.5)
			(thermal_bridge_width 0.5)
			(island_removal_mode 0)
		)
		(polygon
			(pts
				(xy 450.636386 -223.718374) (xy 450.636386 -223.442784) (xy 451.195186 -223.442784) (xy 451.195186 -223.718374)
			)
		)
	)
	(zone
		(layer "In11.Cu")
		(hatch none 0.5)
		(connect_pads
			(clearance 0)
		)
		(min_thickness 0.25)
		(keepout
			(tracks allowed)
			(vias allowed)
			(pads allowed)
			(copperpour allowed)
			(footprints allowed)
		)
		(placement
			(enabled no)
			(sheetname "")
		)
		(fill
			(thermal_gap 0.5)
			(thermal_bridge_width 0.5)
			(island_removal_mode 0)
		)
		(polygon
			(pts
				(xy 294.586152 -238.39678) (xy 294.586152 -237.847124) (xy 295.216072 -237.847124) (xy 295.216072 -238.39678)
			)
		)
	)
	(zone
		(layer "In11.Cu")
		(hatch none 0.5)
		(connect_pads
			(clearance 0)
		)
		(min_thickness 0.25)
		(keepout
			(tracks allowed)
			(vias allowed)
			(pads allowed)
			(copperpour allowed)
			(footprints allowed)
		)
		(placement
			(enabled no)
			(sheetname "")
		)
		(fill
			(thermal_gap 0.5)
			(thermal_bridge_width 0.5)
			(island_removal_mode 0)
		)
		(polygon
			(pts
				(xy 424.561254 -271.318482) (xy 424.561254 -271.042892) (xy 425.120054 -271.042892) (xy 425.120054 -271.318482)
			)
		)
	)
	(zone
		(layer "In11.Cu")
		(hatch none 0.5)
		(connect_pads
			(clearance 0)
		)
		(min_thickness 0.25)
		(keepout
			(tracks allowed)
			(vias allowed)
			(pads allowed)
			(copperpour allowed)
			(footprints allowed)
		)
		(placement
			(enabled no)
			(sheetname "")
		)
		(fill
			(thermal_gap 0.5)
			(thermal_bridge_width 0.5)
			(island_removal_mode 0)
		)
		(polygon
			(pts
				(xy 421.010842 -231.264714) (xy 421.010842 -231.540304) (xy 420.452042 -231.540304) (xy 420.452042 -231.264714)
			)
		)
	)
	(zone
		(layer "In11.Cu")
		(hatch none 0.5)
		(connect_pads
			(clearance 0)
		)
		(min_thickness 0.25)
		(keepout
			(tracks allowed)
			(vias allowed)
			(pads allowed)
			(copperpour allowed)
			(footprints allowed)
		)
		(placement
			(enabled no)
			(sheetname "")
		)
		(fill
			(thermal_gap 0.5)
			(thermal_bridge_width 0.5)
			(island_removal_mode 0)
		)
		(polygon
			(pts
				(xy 50.746152 -239.246918) (xy 50.746152 -238.697262) (xy 51.376072 -238.697262) (xy 51.376072 -239.246918)
			)
		)
	)
	(zone
		(layer "In11.Cu")
		(hatch none 0.5)
		(connect_pads
			(clearance 0)
		)
		(min_thickness 0.25)
		(keepout
			(tracks allowed)
			(vias allowed)
			(pads allowed)
			(copperpour allowed)
			(footprints allowed)
		)
		(placement
			(enabled no)
			(sheetname "")
		)
		(fill
			(thermal_gap 0.5)
			(thermal_bridge_width 0.5)
			(island_removal_mode 0)
		)
		(polygon
			(pts
				(xy 172.521118 -312.968386) (xy 172.521118 -312.692796) (xy 173.079918 -312.692796) (xy 173.079918 -312.968386)
			)
		)
	)
	(zone
		(layer "In11.Cu")
		(hatch none 0.5)
		(connect_pads
			(clearance 0)
		)
		(min_thickness 0.25)
		(keepout
			(tracks allowed)
			(vias allowed)
			(pads allowed)
			(copperpour allowed)
			(footprints allowed)
		)
		(placement
			(enabled no)
			(sheetname "")
		)
		(fill
			(thermal_gap 0.5)
			(thermal_bridge_width 0.5)
			(island_removal_mode 0)
		)
		(polygon
			(pts
				(xy 424.561254 -233.068622) (xy 424.561254 -232.793032) (xy 425.120054 -232.793032) (xy 425.120054 -233.068622)
			)
		)
	)
	(zone
		(layer "In11.Cu")
		(hatch none 0.5)
		(connect_pads
			(clearance 0)
		)
		(min_thickness 0.25)
		(keepout
			(tracks allowed)
			(vias allowed)
			(pads allowed)
			(copperpour allowed)
			(footprints allowed)
		)
		(placement
			(enabled no)
			(sheetname "")
		)
		(fill
			(thermal_gap 0.5)
			(thermal_bridge_width 0.5)
			(island_removal_mode 0)
		)
		(polygon
			(pts
				(xy 50.746152 -205.246732) (xy 50.746152 -204.697076) (xy 51.376072 -204.697076) (xy 51.376072 -205.246732)
			)
		)
	)
	(zone
		(layer "In11.Cu")
		(hatch none 0.5)
		(connect_pads
			(clearance 0)
		)
		(min_thickness 0.25)
		(keepout
			(tracks allowed)
			(vias allowed)
			(pads allowed)
			(copperpour allowed)
			(footprints allowed)
		)
		(placement
			(enabled no)
			(sheetname "")
		)
		(fill
			(thermal_gap 0.5)
			(thermal_bridge_width 0.5)
			(island_removal_mode 0)
		)
		(polygon
			(pts
				(xy 421.010842 -286.514794) (xy 421.010842 -286.790384) (xy 420.452042 -286.790384) (xy 420.452042 -286.514794)
			)
		)
	)
	(zone
		(layer "In11.Cu")
		(hatch none 0.5)
		(connect_pads
			(clearance 0)
		)
		(min_thickness 0.25)
		(keepout
			(tracks allowed)
			(vias allowed)
			(pads allowed)
			(copperpour allowed)
			(footprints allowed)
		)
		(placement
			(enabled no)
			(sheetname "")
		)
		(fill
			(thermal_gap 0.5)
			(thermal_bridge_width 0.5)
			(island_removal_mode 0)
		)
		(polygon
			(pts
				(xy 172.521118 -226.268534) (xy 172.521118 -225.992944) (xy 173.079918 -225.992944) (xy 173.079918 -226.268534)
			)
		)
	)
	(zone
		(layer "In11.Cu")
		(hatch none 0.5)
		(connect_pads
			(clearance 0)
		)
		(min_thickness 0.25)
		(keepout
			(tracks allowed)
			(vias allowed)
			(pads allowed)
			(copperpour allowed)
			(footprints allowed)
		)
		(placement
			(enabled no)
			(sheetname "")
		)
		(fill
			(thermal_gap 0.5)
			(thermal_bridge_width 0.5)
			(island_removal_mode 0)
		)
		(polygon
			(pts
				(xy 177.170842 -285.664656) (xy 177.170842 -285.940246) (xy 176.612042 -285.940246) (xy 176.612042 -285.664656)
			)
		)
	)
	(zone
		(layer "In11.Cu")
		(hatch none 0.5)
		(connect_pads
			(clearance 0)
		)
		(min_thickness 0.25)
		(keepout
			(tracks allowed)
			(vias allowed)
			(pads allowed)
			(copperpour allowed)
			(footprints allowed)
		)
		(placement
			(enabled no)
			(sheetname "")
		)
		(fill
			(thermal_gap 0.5)
			(thermal_bridge_width 0.5)
			(island_removal_mode 0)
		)
		(polygon
			(pts
				(xy 172.521118 -267.068554) (xy 172.521118 -266.792964) (xy 173.079918 -266.792964) (xy 173.079918 -267.068554)
			)
		)
	)
	(zone
		(layer "In11.Cu")
		(hatch none 0.5)
		(connect_pads
			(clearance 0)
		)
		(min_thickness 0.25)
		(keepout
			(tracks allowed)
			(vias allowed)
			(pads allowed)
			(copperpour allowed)
			(footprints allowed)
		)
		(placement
			(enabled no)
			(sheetname "")
		)
		(fill
			(thermal_gap 0.5)
			(thermal_bridge_width 0.5)
			(island_removal_mode 0)
		)
		(polygon
			(pts
				(xy 180.36794 -358.183688) (xy 180.36794 -356.880668) (xy 182.12562 -356.880668) (xy 182.12562 -358.183688)
			)
		)
	)
	(zone
		(layer "In11.Cu")
		(hatch none 0.5)
		(connect_pads
			(clearance 0)
		)
		(min_thickness 0.25)
		(keepout
			(tracks allowed)
			(vias allowed)
			(pads allowed)
			(copperpour allowed)
			(footprints allowed)
		)
		(placement
			(enabled no)
			(sheetname "")
		)
		(fill
			(thermal_gap 0.5)
			(thermal_bridge_width 0.5)
			(island_removal_mode 0)
		)
		(polygon
			(pts
				(xy 435.548786 -281.518614) (xy 435.548786 -281.243024) (xy 436.107586 -281.243024) (xy 436.107586 -281.518614)
			)
		)
	)
	(zone
		(layer "In11.Cu")
		(hatch none 0.5)
		(connect_pads
			(clearance 0)
		)
		(min_thickness 0.25)
		(keepout
			(tracks allowed)
			(vias allowed)
			(pads allowed)
			(copperpour allowed)
			(footprints allowed)
		)
		(placement
			(enabled no)
			(sheetname "")
		)
		(fill
			(thermal_gap 0.5)
			(thermal_bridge_width 0.5)
			(island_removal_mode 0)
		)
		(polygon
			(pts
				(xy 46.646084 -226.49688) (xy 46.646084 -225.947224) (xy 47.276004 -225.947224) (xy 47.276004 -226.49688)
			)
		)
	)
	(zone
		(layer "In11.Cu")
		(hatch none 0.5)
		(connect_pads
			(clearance 0)
		)
		(min_thickness 0.25)
		(keepout
			(tracks allowed)
			(vias allowed)
			(pads allowed)
			(copperpour allowed)
			(footprints allowed)
		)
		(placement
			(enabled no)
			(sheetname "")
		)
		(fill
			(thermal_gap 0.5)
			(thermal_bridge_width 0.5)
			(island_removal_mode 0)
		)
		(polygon
			(pts
				(xy 405.373586 -268.66596) (xy 405.932386 -268.66596) (xy 405.932386 -269.61846) (xy 405.373586 -269.61846)
				(xy 404.863046 -269.61846) (xy 404.863046 -268.66596)
			)
		)
	)
	(zone
		(layer "In11.Cu")
		(hatch none 0.5)
		(connect_pads
			(clearance 0)
		)
		(min_thickness 0.25)
		(keepout
			(tracks allowed)
			(vias allowed)
			(pads allowed)
			(copperpour allowed)
			(footprints allowed)
		)
		(placement
			(enabled no)
			(sheetname "")
		)
		(fill
			(thermal_gap 0.5)
			(thermal_bridge_width 0.5)
			(island_removal_mode 0)
		)
		(polygon
			(pts
				(xy 50.771552 -314.04687) (xy 50.771552 -313.497214) (xy 51.401472 -313.497214) (xy 51.401472 -314.04687)
			)
		)
	)
	(zone
		(layer "In11.Cu")
		(hatch none 0.5)
		(connect_pads
			(clearance 0)
		)
		(min_thickness 0.25)
		(keepout
			(tracks allowed)
			(vias allowed)
			(pads allowed)
			(copperpour allowed)
			(footprints allowed)
		)
		(placement
			(enabled no)
			(sheetname "")
		)
		(fill
			(thermal_gap 0.5)
			(thermal_bridge_width 0.5)
			(island_removal_mode 0)
		)
		(polygon
			(pts
				(xy 203.245974 -215.114632) (xy 203.245974 -215.390222) (xy 202.687174 -215.390222) (xy 202.687174 -215.114632)
			)
		)
	)
	(zone
		(layer "In11.Cu")
		(hatch none 0.5)
		(connect_pads
			(clearance 0)
		)
		(min_thickness 0.25)
		(keepout
			(tracks allowed)
			(vias allowed)
			(pads allowed)
			(copperpour allowed)
			(footprints allowed)
		)
		(placement
			(enabled no)
			(sheetname "")
		)
		(fill
			(thermal_gap 0.5)
			(thermal_bridge_width 0.5)
			(island_removal_mode 0)
		)
		(polygon
			(pts
				(xy 203.245974 -292.464744) (xy 203.245974 -292.740334) (xy 202.687174 -292.740334) (xy 202.687174 -292.464744)
			)
		)
	)
	(zone
		(layer "In11.Cu")
		(hatch none 0.5)
		(connect_pads
			(clearance 0)
		)
		(min_thickness 0.25)
		(keepout
			(tracks allowed)
			(vias allowed)
			(pads allowed)
			(copperpour allowed)
			(footprints allowed)
		)
		(placement
			(enabled no)
			(sheetname "")
		)
		(fill
			(thermal_gap 0.5)
			(thermal_bridge_width 0.5)
			(island_removal_mode 0)
		)
		(polygon
			(pts
				(xy 202.021186 -271.318482) (xy 201.462386 -271.318482) (xy 201.059542 -271.318482) (xy 201.059542 -270.536162)
				(xy 202.362816 -270.536162) (xy 202.362816 -271.318482)
			)
		)
	)
	(zone
		(layer "In11.Cu")
		(hatch none 0.5)
		(connect_pads
			(clearance 0)
		)
		(min_thickness 0.25)
		(keepout
			(tracks allowed)
			(vias allowed)
			(pads allowed)
			(copperpour allowed)
			(footprints allowed)
		)
		(placement
			(enabled no)
			(sheetname "")
		)
		(fill
			(thermal_gap 0.5)
			(thermal_bridge_width 0.5)
			(island_removal_mode 0)
		)
		(polygon
			(pts
				(xy 435.548786 -213.518496) (xy 435.548786 -213.242906) (xy 436.107586 -213.242906) (xy 436.107586 -213.518496)
			)
		)
	)
	(zone
		(layer "In11.Cu")
		(hatch none 0.5)
		(connect_pads
			(clearance 0)
		)
		(min_thickness 0.25)
		(keepout
			(tracks allowed)
			(vias allowed)
			(pads allowed)
			(copperpour allowed)
			(footprints allowed)
		)
		(placement
			(enabled no)
			(sheetname "")
		)
		(fill
			(thermal_gap 0.5)
			(thermal_bridge_width 0.5)
			(island_removal_mode 0)
		)
		(polygon
			(pts
				(xy 420.461186 -222.86849) (xy 420.461186 -222.5929) (xy 421.019986 -222.5929) (xy 421.019986 -222.86849)
			)
		)
	)
	(zone
		(layer "In11.Cu")
		(hatch none 0.5)
		(connect_pads
			(clearance 0)
		)
		(min_thickness 0.25)
		(keepout
			(tracks allowed)
			(vias allowed)
			(pads allowed)
			(copperpour allowed)
			(footprints allowed)
		)
		(placement
			(enabled no)
			(sheetname "")
		)
		(fill
			(thermal_gap 0.5)
			(thermal_bridge_width 0.5)
			(island_removal_mode 0)
		)
		(polygon
			(pts
				(xy 172.521118 -277.268432) (xy 172.521118 -276.992842) (xy 173.079918 -276.992842) (xy 173.079918 -277.268432)
			)
		)
	)
	(zone
		(layer "In11.Cu")
		(hatch none 0.5)
		(connect_pads
			(clearance 0)
		)
		(min_thickness 0.25)
		(keepout
			(tracks allowed)
			(vias allowed)
			(pads allowed)
			(copperpour allowed)
			(footprints allowed)
		)
		(placement
			(enabled no)
			(sheetname "")
		)
		(fill
			(thermal_gap 0.5)
			(thermal_bridge_width 0.5)
			(island_removal_mode 0)
		)
		(polygon
			(pts
				(xy 268.558518 -278.342344) (xy 268.558518 -277.802086) (xy 269.126462 -277.802086) (xy 269.426944 -277.802086)
				(xy 269.531084 -277.906226) (xy 269.531084 -278.171656) (xy 269.360396 -278.342344) (xy 269.117318 -278.342344)
			)
		)
	)
	(zone
		(layer "In11.Cu")
		(hatch none 0.5)
		(connect_pads
			(clearance 0)
		)
		(min_thickness 0.25)
		(keepout
			(tracks allowed)
			(vias allowed)
			(pads allowed)
			(copperpour allowed)
			(footprints allowed)
		)
		(placement
			(enabled no)
			(sheetname "")
		)
		(fill
			(thermal_gap 0.5)
			(thermal_bridge_width 0.5)
			(island_removal_mode 0)
		)
		(polygon
			(pts
				(xy 202.696318 -268.768576) (xy 202.696318 -268.492986) (xy 203.255118 -268.492986) (xy 203.255118 -268.768576)
			)
		)
	)
	(zone
		(layer "In11.Cu")
		(hatch none 0.5)
		(connect_pads
			(clearance 0)
		)
		(min_thickness 0.25)
		(keepout
			(tracks allowed)
			(vias allowed)
			(pads allowed)
			(copperpour allowed)
			(footprints allowed)
		)
		(placement
			(enabled no)
			(sheetname "")
		)
		(fill
			(thermal_gap 0.5)
			(thermal_bridge_width 0.5)
			(island_removal_mode 0)
		)
		(polygon
			(pts
				(xy 173.070774 -217.664792) (xy 173.070774 -217.940382) (xy 172.511974 -217.940382) (xy 172.511974 -217.664792)
			)
		)
	)
	(zone
		(layer "In11.Cu")
		(hatch none 0.5)
		(connect_pads
			(clearance 0)
		)
		(min_thickness 0.25)
		(keepout
			(tracks allowed)
			(vias allowed)
			(pads allowed)
			(copperpour allowed)
			(footprints allowed)
		)
		(placement
			(enabled no)
			(sheetname "")
		)
		(fill
			(thermal_gap 0.5)
			(thermal_bridge_width 0.5)
			(island_removal_mode 0)
		)
		(polygon
			(pts
				(xy 20.629118 -246.907812) (xy 20.629118 -246.359172) (xy 21.154898 -246.359172) (xy 21.154898 -246.907812)
			)
		)
	)
	(zone
		(layer "In11.Cu")
		(hatch none 0.5)
		(connect_pads
			(clearance 0)
		)
		(min_thickness 0.25)
		(keepout
			(tracks allowed)
			(vias allowed)
			(pads allowed)
			(copperpour allowed)
			(footprints allowed)
		)
		(placement
			(enabled no)
			(sheetname "")
		)
		(fill
			(thermal_gap 0.5)
			(thermal_bridge_width 0.5)
			(island_removal_mode 0)
		)
		(polygon
			(pts
				(xy 425.11091 -292.464744) (xy 425.11091 -292.740334) (xy 424.55211 -292.740334) (xy 424.55211 -292.464744)
			)
		)
	)
	(zone
		(layer "In11.Cu")
		(hatch none 0.5)
		(connect_pads
			(clearance 0)
		)
		(min_thickness 0.25)
		(keepout
			(tracks allowed)
			(vias allowed)
			(pads allowed)
			(copperpour allowed)
			(footprints allowed)
		)
		(placement
			(enabled no)
			(sheetname "")
		)
		(fill
			(thermal_gap 0.5)
			(thermal_bridge_width 0.5)
			(island_removal_mode 0)
		)
		(polygon
			(pts
				(xy 202.696318 -250.918472) (xy 202.696318 -250.642882) (xy 203.255118 -250.642882) (xy 203.255118 -250.918472)
			)
		)
	)
	(zone
		(layer "In11.Cu")
		(hatch none 0.5)
		(connect_pads
			(clearance 0)
		)
		(min_thickness 0.25)
		(keepout
			(tracks allowed)
			(vias allowed)
			(pads allowed)
			(copperpour allowed)
			(footprints allowed)
		)
		(placement
			(enabled no)
			(sheetname "")
		)
		(fill
			(thermal_gap 0.5)
			(thermal_bridge_width 0.5)
			(island_removal_mode 0)
		)
		(polygon
			(pts
				(xy 421.010842 -225.314764) (xy 421.010842 -225.590354) (xy 420.452042 -225.590354) (xy 420.452042 -225.314764)
			)
		)
	)
	(zone
		(layer "In11.Cu")
		(hatch none 0.5)
		(connect_pads
			(clearance 0)
		)
		(min_thickness 0.25)
		(keepout
			(tracks allowed)
			(vias allowed)
			(pads allowed)
			(copperpour allowed)
			(footprints allowed)
		)
		(placement
			(enabled no)
			(sheetname "")
		)
		(fill
			(thermal_gap 0.5)
			(thermal_bridge_width 0.5)
			(island_removal_mode 0)
		)
		(polygon
			(pts
				(xy 451.186042 -198.964804) (xy 451.186042 -199.240394) (xy 450.627242 -199.240394) (xy 450.627242 -198.964804)
			)
		)
	)
	(zone
		(layer "In11.Cu")
		(hatch none 0.5)
		(connect_pads
			(clearance 0)
		)
		(min_thickness 0.25)
		(keepout
			(tracks allowed)
			(vias allowed)
			(pads allowed)
			(copperpour allowed)
			(footprints allowed)
		)
		(placement
			(enabled no)
			(sheetname "")
		)
		(fill
			(thermal_gap 0.5)
			(thermal_bridge_width 0.5)
			(island_removal_mode 0)
		)
		(polygon
			(pts
				(xy 20.570952 -239.246918) (xy 20.570952 -238.697262) (xy 21.200872 -238.697262) (xy 21.200872 -239.246918)
			)
		)
	)
	(zone
		(layer "In11.Cu")
		(hatch none 0.5)
		(connect_pads
			(clearance 0)
		)
		(min_thickness 0.25)
		(keepout
			(tracks allowed)
			(vias allowed)
			(pads allowed)
			(copperpour allowed)
			(footprints allowed)
		)
		(placement
			(enabled no)
			(sheetname "")
		)
		(fill
			(thermal_gap 0.5)
			(thermal_bridge_width 0.5)
			(island_removal_mode 0)
		)
		(polygon
			(pts
				(xy 294.586152 -277.496778) (xy 294.586152 -276.947122) (xy 295.216072 -276.947122) (xy 295.216072 -277.496778)
			)
		)
	)
	(zone
		(layer "In11.Cu")
		(hatch none 0.5)
		(connect_pads
			(clearance 0)
		)
		(min_thickness 0.25)
		(keepout
			(tracks allowed)
			(vias allowed)
			(pads allowed)
			(copperpour allowed)
			(footprints allowed)
		)
		(placement
			(enabled no)
			(sheetname "")
		)
		(fill
			(thermal_gap 0.5)
			(thermal_bridge_width 0.5)
			(island_removal_mode 0)
		)
		(polygon
			(pts
				(xy 268.51102 -214.596726) (xy 268.51102 -214.04707) (xy 269.14094 -214.04707) (xy 269.14094 -214.596726)
			)
		)
	)
	(zone
		(layer "In11.Cu")
		(hatch none 0.5)
		(connect_pads
			(clearance 0)
		)
		(min_thickness 0.25)
		(keepout
			(tracks allowed)
			(vias allowed)
			(pads allowed)
			(copperpour allowed)
			(footprints allowed)
		)
		(placement
			(enabled no)
			(sheetname "")
		)
		(fill
			(thermal_gap 0.5)
			(thermal_bridge_width 0.5)
			(island_removal_mode 0)
		)
		(polygon
			(pts
				(xy 330.0984 -41.938448) (xy 330.0984 -39.449248) (xy 335.53146 -39.449248) (xy 335.53146 -41.938448)
			)
		)
	)
	(zone
		(layer "In11.Cu")
		(hatch none 0.5)
		(connect_pads
			(clearance 0)
		)
		(min_thickness 0.25)
		(keepout
			(tracks allowed)
			(vias allowed)
			(pads allowed)
			(copperpour allowed)
			(footprints allowed)
		)
		(placement
			(enabled no)
			(sheetname "")
		)
		(fill
			(thermal_gap 0.5)
			(thermal_bridge_width 0.5)
			(island_removal_mode 0)
		)
		(polygon
			(pts
				(xy 176.621186 -220.318584) (xy 176.621186 -220.042994) (xy 177.179986 -220.042994) (xy 177.179986 -220.318584)
			)
		)
	)
	(zone
		(layer "In11.Cu")
		(hatch none 0.5)
		(connect_pads
			(clearance 0)
		)
		(min_thickness 0.25)
		(keepout
			(tracks allowed)
			(vias allowed)
			(pads allowed)
			(copperpour allowed)
			(footprints allowed)
		)
		(placement
			(enabled no)
			(sheetname "")
		)
		(fill
			(thermal_gap 0.5)
			(thermal_bridge_width 0.5)
			(island_removal_mode 0)
		)
		(polygon
			(pts
				(xy 172.521118 -316.36843) (xy 172.521118 -316.09284) (xy 173.079918 -316.09284) (xy 173.079918 -316.36843)
			)
		)
	)
	(zone
		(layer "In11.Cu")
		(hatch none 0.5)
		(connect_pads
			(clearance 0)
		)
		(min_thickness 0.25)
		(keepout
			(tracks allowed)
			(vias allowed)
			(pads allowed)
			(copperpour allowed)
			(footprints allowed)
		)
		(placement
			(enabled no)
			(sheetname "")
		)
		(fill
			(thermal_gap 0.5)
			(thermal_bridge_width 0.5)
			(island_removal_mode 0)
		)
		(polygon
			(pts
				(xy 298.68622 -205.246732) (xy 298.68622 -204.697076) (xy 299.31614 -204.697076) (xy 299.31614 -205.246732)
			)
		)
	)
	(zone
		(layer "In11.Cu")
		(hatch none 0.5)
		(connect_pads
			(clearance 0)
		)
		(min_thickness 0.25)
		(keepout
			(tracks allowed)
			(vias allowed)
			(pads allowed)
			(copperpour allowed)
			(footprints allowed)
		)
		(placement
			(enabled no)
			(sheetname "")
		)
		(fill
			(thermal_gap 0.5)
			(thermal_bridge_width 0.5)
			(island_removal_mode 0)
		)
		(polygon
			(pts
				(xy 420.461186 -283.218382) (xy 420.461186 -282.942792) (xy 421.019986 -282.942792) (xy 421.019986 -283.218382)
			)
		)
	)
	(zone
		(layer "In11.Cu")
		(hatch none 0.5)
		(connect_pads
			(clearance 0)
		)
		(min_thickness 0.25)
		(keepout
			(tracks allowed)
			(vias allowed)
			(pads allowed)
			(copperpour allowed)
			(footprints allowed)
		)
		(placement
			(enabled no)
			(sheetname "")
		)
		(fill
			(thermal_gap 0.5)
			(thermal_bridge_width 0.5)
			(island_removal_mode 0)
		)
		(polygon
			(pts
				(xy 202.696318 -263.66851) (xy 202.696318 -263.39292) (xy 203.255118 -263.39292) (xy 203.255118 -263.66851)
			)
		)
	)
	(zone
		(layer "In11.Cu")
		(hatch none 0.5)
		(connect_pads
			(clearance 0)
		)
		(min_thickness 0.25)
		(keepout
			(tracks allowed)
			(vias allowed)
			(pads allowed)
			(copperpour allowed)
			(footprints allowed)
		)
		(placement
			(enabled no)
			(sheetname "")
		)
		(fill
			(thermal_gap 0.5)
			(thermal_bridge_width 0.5)
			(island_removal_mode 0)
		)
		(polygon
			(pts
				(xy 143.212058 -243.80825) (xy 149.216618 -243.80825) (xy 149.777958 -244.36959) (xy 149.777958 -245.61927)
				(xy 149.711918 -245.68531) (xy 143.179038 -245.68531) (xy 142.892018 -245.39829) (xy 142.892018 -244.12829)
			)
		)
	)
	(zone
		(layer "In11.Cu")
		(hatch none 0.5)
		(connect_pads
			(clearance 0)
		)
		(min_thickness 0.25)
		(keepout
			(tracks allowed)
			(vias allowed)
			(pads allowed)
			(copperpour allowed)
			(footprints allowed)
		)
		(placement
			(enabled no)
			(sheetname "")
		)
		(fill
			(thermal_gap 0.5)
			(thermal_bridge_width 0.5)
			(island_removal_mode 0)
		)
		(polygon
			(pts
				(xy 172.521118 -268.768576) (xy 172.521118 -268.492986) (xy 173.079918 -268.492986) (xy 173.079918 -268.768576)
			)
		)
	)
	(zone
		(layer "In11.Cu")
		(hatch none 0.5)
		(connect_pads
			(clearance 0)
		)
		(min_thickness 0.25)
		(keepout
			(tracks allowed)
			(vias allowed)
			(pads allowed)
			(copperpour allowed)
			(footprints allowed)
		)
		(placement
			(enabled no)
			(sheetname "")
		)
		(fill
			(thermal_gap 0.5)
			(thermal_bridge_width 0.5)
			(island_removal_mode 0)
		)
		(polygon
			(pts
				(xy 176.621186 -250.918472) (xy 176.621186 -250.642882) (xy 177.179986 -250.642882) (xy 177.179986 -250.918472)
			)
		)
	)
	(zone
		(layer "In11.Cu")
		(hatch none 0.5)
		(connect_pads
			(clearance 0)
		)
		(min_thickness 0.25)
		(keepout
			(tracks allowed)
			(vias allowed)
			(pads allowed)
			(copperpour allowed)
			(footprints allowed)
		)
		(placement
			(enabled no)
			(sheetname "")
		)
		(fill
			(thermal_gap 0.5)
			(thermal_bridge_width 0.5)
			(island_removal_mode 0)
		)
		(polygon
			(pts
				(xy 424.561254 -301.91837) (xy 424.561254 -301.64278) (xy 425.120054 -301.64278) (xy 425.120054 -301.91837)
			)
		)
	)
	(zone
		(layer "In11.Cu")
		(hatch none 0.5)
		(connect_pads
			(clearance 0)
		)
		(min_thickness 0.25)
		(keepout
			(tracks allowed)
			(vias allowed)
			(pads allowed)
			(copperpour allowed)
			(footprints allowed)
		)
		(placement
			(enabled no)
			(sheetname "")
		)
		(fill
			(thermal_gap 0.5)
			(thermal_bridge_width 0.5)
			(island_removal_mode 0)
		)
		(polygon
			(pts
				(xy 268.56436 -300.450758) (xy 268.56436 -299.90034) (xy 269.12316 -299.90034) (xy 269.12316 -300.450758)
			)
		)
	)
	(zone
		(layer "In11.Cu")
		(hatch none 0.5)
		(connect_pads
			(clearance 0)
		)
		(min_thickness 0.25)
		(keepout
			(tracks allowed)
			(vias allowed)
			(pads allowed)
			(copperpour allowed)
			(footprints allowed)
		)
		(placement
			(enabled no)
			(sheetname "")
		)
		(fill
			(thermal_gap 0.5)
			(thermal_bridge_width 0.5)
			(island_removal_mode 0)
		)
		(polygon
			(pts
				(xy 291.180012 -267.319506) (xy 291.180012 -266.737846) (xy 291.738812 -266.737846) (xy 291.738812 -267.319506)
			)
		)
	)
	(zone
		(layer "In11.Cu")
		(hatch none 0.5)
		(connect_pads
			(clearance 0)
		)
		(min_thickness 0.25)
		(keepout
			(tracks allowed)
			(vias allowed)
			(pads allowed)
			(copperpour allowed)
			(footprints allowed)
		)
		(placement
			(enabled no)
			(sheetname "")
		)
		(fill
			(thermal_gap 0.5)
			(thermal_bridge_width 0.5)
			(island_removal_mode 0)
		)
		(polygon
			(pts
				(xy 202.696318 -225.418396) (xy 202.696318 -225.142806) (xy 203.255118 -225.142806) (xy 203.255118 -225.418396)
			)
		)
	)
	(zone
		(layer "In11.Cu")
		(hatch none 0.5)
		(connect_pads
			(clearance 0)
		)
		(min_thickness 0.25)
		(keepout
			(tracks allowed)
			(vias allowed)
			(pads allowed)
			(copperpour allowed)
			(footprints allowed)
		)
		(placement
			(enabled no)
			(sheetname "")
		)
		(fill
			(thermal_gap 0.5)
			(thermal_bridge_width 0.5)
			(island_removal_mode 0)
		)
		(polygon
			(pts
				(xy 50.746152 -251.996956) (xy 50.746152 -251.4473) (xy 51.376072 -251.4473) (xy 51.376072 -251.996956)
			)
		)
	)
	(zone
		(layer "In11.Cu")
		(hatch none 0.5)
		(connect_pads
			(clearance 0)
		)
		(min_thickness 0.25)
		(keepout
			(tracks allowed)
			(vias allowed)
			(pads allowed)
			(copperpour allowed)
			(footprints allowed)
		)
		(placement
			(enabled no)
			(sheetname "")
		)
		(fill
			(thermal_gap 0.5)
			(thermal_bridge_width 0.5)
			(island_removal_mode 0)
		)
		(polygon
			(pts
				(xy 420.461186 -311.268618) (xy 420.461186 -310.993028) (xy 421.019986 -310.993028) (xy 421.019986 -311.268618)
			)
		)
	)
	(zone
		(layer "In11.Cu")
		(hatch none 0.5)
		(connect_pads
			(clearance 0)
		)
		(min_thickness 0.25)
		(keepout
			(tracks allowed)
			(vias allowed)
			(pads allowed)
			(copperpour allowed)
			(footprints allowed)
		)
		(placement
			(enabled no)
			(sheetname "")
		)
		(fill
			(thermal_gap 0.5)
			(thermal_bridge_width 0.5)
			(island_removal_mode 0)
		)
		(polygon
			(pts
				(xy 173.070774 -238.914686) (xy 173.070774 -239.190276) (xy 172.511974 -239.190276) (xy 172.511974 -238.914686)
			)
		)
	)
	(zone
		(layer "In11.Cu")
		(hatch none 0.5)
		(connect_pads
			(clearance 0)
		)
		(min_thickness 0.25)
		(keepout
			(tracks allowed)
			(vias allowed)
			(pads allowed)
			(copperpour allowed)
			(footprints allowed)
		)
		(placement
			(enabled no)
			(sheetname "")
		)
		(fill
			(thermal_gap 0.5)
			(thermal_bridge_width 0.5)
			(island_removal_mode 0)
		)
		(polygon
			(pts
				(xy 176.621186 -300.218348) (xy 176.621186 -299.942758) (xy 177.179986 -299.942758) (xy 177.179986 -300.218348)
			)
		)
	)
	(zone
		(layer "In11.Cu")
		(hatch none 0.5)
		(connect_pads
			(clearance 0)
		)
		(min_thickness 0.25)
		(keepout
			(tracks allowed)
			(vias allowed)
			(pads allowed)
			(copperpour allowed)
			(footprints allowed)
		)
		(placement
			(enabled no)
			(sheetname "")
		)
		(fill
			(thermal_gap 0.5)
			(thermal_bridge_width 0.5)
			(island_removal_mode 0)
		)
		(polygon
			(pts
				(xy 450.636386 -272.742914) (xy 451.195186 -272.742914) (xy 451.195186 -273.018504) (xy 451.195186 -273.215608)
				(xy 450.226176 -273.215608) (xy 450.226176 -273.571462) (xy 449.866004 -273.571462) (xy 449.866004 -272.742914)
			)
		)
	)
	(zone
		(layer "In11.Cu")
		(hatch none 0.5)
		(connect_pads
			(clearance 0)
		)
		(min_thickness 0.25)
		(keepout
			(tracks allowed)
			(vias allowed)
			(pads allowed)
			(copperpour allowed)
			(footprints allowed)
		)
		(placement
			(enabled no)
			(sheetname "")
		)
		(fill
			(thermal_gap 0.5)
			(thermal_bridge_width 0.5)
			(island_removal_mode 0)
		)
		(polygon
			(pts
				(xy 424.561254 -217.768424) (xy 424.561254 -217.492834) (xy 425.120054 -217.492834) (xy 425.120054 -217.768424)
			)
		)
	)
	(zone
		(layer "In11.Cu")
		(hatch none 0.5)
		(connect_pads
			(clearance 0)
		)
		(min_thickness 0.25)
		(keepout
			(tracks allowed)
			(vias allowed)
			(pads allowed)
			(copperpour allowed)
			(footprints allowed)
		)
		(placement
			(enabled no)
			(sheetname "")
		)
		(fill
			(thermal_gap 0.5)
			(thermal_bridge_width 0.5)
			(island_removal_mode 0)
		)
		(polygon
			(pts
				(xy 187.608718 -234.76839) (xy 187.608718 -234.4928) (xy 188.167518 -234.4928) (xy 188.167518 -234.76839)
			)
		)
	)
	(zone
		(layer "In11.Cu")
		(hatch none 0.5)
		(connect_pads
			(clearance 0)
		)
		(min_thickness 0.25)
		(keepout
			(tracks allowed)
			(vias allowed)
			(pads allowed)
			(copperpour allowed)
			(footprints allowed)
		)
		(placement
			(enabled no)
			(sheetname "")
		)
		(fill
			(thermal_gap 0.5)
			(thermal_bridge_width 0.5)
			(island_removal_mode 0)
		)
		(polygon
			(pts
				(xy 176.621186 -212.668612) (xy 176.621186 -212.393022) (xy 177.179986 -212.393022) (xy 177.179986 -212.668612)
			)
		)
	)
	(zone
		(layer "In11.Cu")
		(hatch none 0.5)
		(connect_pads
			(clearance 0)
		)
		(min_thickness 0.25)
		(keepout
			(tracks allowed)
			(vias allowed)
			(pads allowed)
			(copperpour allowed)
			(footprints allowed)
		)
		(placement
			(enabled no)
			(sheetname "")
		)
		(fill
			(thermal_gap 0.5)
			(thermal_bridge_width 0.5)
			(island_removal_mode 0)
		)
		(polygon
			(pts
				(xy 322.291202 -247.32615) (xy 322.360036 -247.394984) (xy 324.271386 -249.306334) (xy 324.271386 -249.819922)
				(xy 324.271386 -254.22606) (xy 323.426582 -255.070864) (xy 322.581524 -255.915668) (xy 322.581524 -256.25171)
				(xy 322.440808 -256.392426) (xy 319.38087 -256.392426) (xy 319.346326 -256.42697) (xy 319.346326 -260.764782)
				(xy 319.82791 -261.246366) (xy 319.82791 -261.755636) (xy 320.1289 -261.755636) (xy 321.963542 -259.920994)
				(xy 322.217542 -259.920994) (xy 324.7136 -259.920994) (xy 330.77277 -259.920994) (xy 330.799186 -259.894578)
				(xy 330.799186 -254.735076) (xy 330.795376 -254.731266) (xy 330.21397 -254.73152) (xy 330.192888 -254.710438)
				(xy 330.192888 -254.212598) (xy 330.18476 -254.20447) (xy 330.18476 -253.087124) (xy 330.18476 -252.375416)
				(xy 329.646026 -251.836682) (xy 329.646026 -251.214128) (xy 330.49591 -250.36399) (xy 332.542642 -250.36399)
				(xy 332.543912 -250.36272) (xy 332.543912 -248.966736) (xy 331.584808 -248.966736) (xy 331.5462 -248.928128)
				(xy 331.5462 -246.43969) (xy 322.013326 -246.43969) (xy 322.013326 -247.048274)
			)
		)
	)
	(zone
		(layer "In11.Cu")
		(hatch none 0.5)
		(connect_pads
			(clearance 0)
		)
		(min_thickness 0.25)
		(keepout
			(tracks allowed)
			(vias allowed)
			(pads allowed)
			(copperpour allowed)
			(footprints allowed)
		)
		(placement
			(enabled no)
			(sheetname "")
		)
		(fill
			(thermal_gap 0.5)
			(thermal_bridge_width 0.5)
			(island_removal_mode 0)
		)
		(polygon
			(pts
				(xy 420.461186 -238.168434) (xy 420.461186 -237.892844) (xy 421.019986 -237.892844) (xy 421.019986 -238.168434)
			)
		)
	)
	(zone
		(layer "In11.Cu")
		(hatch none 0.5)
		(connect_pads
			(clearance 0)
		)
		(min_thickness 0.25)
		(keepout
			(tracks allowed)
			(vias allowed)
			(pads allowed)
			(copperpour allowed)
			(footprints allowed)
		)
		(placement
			(enabled no)
			(sheetname "")
		)
		(fill
			(thermal_gap 0.5)
			(thermal_bridge_width 0.5)
			(island_removal_mode 0)
		)
		(polygon
			(pts
				(xy 20.624292 -291.100764) (xy 20.624292 -290.550346) (xy 21.183092 -290.550346) (xy 21.183092 -291.100764)
			)
		)
	)
	(zone
		(layer "In11.Cu")
		(hatch none 0.5)
		(connect_pads
			(clearance 0)
		)
		(min_thickness 0.25)
		(keepout
			(tracks allowed)
			(vias allowed)
			(pads allowed)
			(copperpour allowed)
			(footprints allowed)
		)
		(placement
			(enabled no)
			(sheetname "")
		)
		(fill
			(thermal_gap 0.5)
			(thermal_bridge_width 0.5)
			(island_removal_mode 0)
		)
		(polygon
			(pts
				(xy 425.11091 -290.764722) (xy 425.11091 -291.040312) (xy 424.55211 -291.040312) (xy 424.55211 -290.764722)
			)
		)
	)
	(zone
		(layer "In11.Cu")
		(hatch none 0.5)
		(connect_pads
			(clearance 0)
		)
		(min_thickness 0.25)
		(keepout
			(tracks allowed)
			(vias allowed)
			(pads allowed)
			(copperpour allowed)
			(footprints allowed)
		)
		(placement
			(enabled no)
			(sheetname "")
		)
		(fill
			(thermal_gap 0.5)
			(thermal_bridge_width 0.5)
			(island_removal_mode 0)
		)
		(polygon
			(pts
				(xy 294.586152 -206.09687) (xy 294.586152 -205.547214) (xy 295.216072 -205.547214) (xy 295.216072 -206.09687)
			)
		)
	)
	(zone
		(layer "In11.Cu")
		(hatch none 0.5)
		(connect_pads
			(clearance 0)
		)
		(min_thickness 0.25)
		(keepout
			(tracks allowed)
			(vias allowed)
			(pads allowed)
			(copperpour allowed)
			(footprints allowed)
		)
		(placement
			(enabled no)
			(sheetname "")
		)
		(fill
			(thermal_gap 0.5)
			(thermal_bridge_width 0.5)
			(island_removal_mode 0)
		)
		(polygon
			(pts
				(xy 177.170842 -278.864822) (xy 177.170842 -279.140412) (xy 176.612042 -279.140412) (xy 176.612042 -278.864822)
			)
		)
	)
	(zone
		(layer "In11.Cu")
		(hatch none 0.5)
		(connect_pads
			(clearance 0)
		)
		(min_thickness 0.25)
		(keepout
			(tracks allowed)
			(vias allowed)
			(pads allowed)
			(copperpour allowed)
			(footprints allowed)
		)
		(placement
			(enabled no)
			(sheetname "")
		)
		(fill
			(thermal_gap 0.5)
			(thermal_bridge_width 0.5)
			(island_removal_mode 0)
		)
		(polygon
			(pts
				(xy 50.771552 -292.796976) (xy 50.771552 -292.24732) (xy 51.401472 -292.24732) (xy 51.401472 -292.796976)
			)
		)
	)
	(zone
		(layer "In11.Cu")
		(hatch none 0.5)
		(connect_pads
			(clearance 0)
		)
		(min_thickness 0.25)
		(keepout
			(tracks allowed)
			(vias allowed)
			(pads allowed)
			(copperpour allowed)
			(footprints allowed)
		)
		(placement
			(enabled no)
			(sheetname "")
		)
		(fill
			(thermal_gap 0.5)
			(thermal_bridge_width 0.5)
			(island_removal_mode 0)
		)
		(polygon
			(pts
				(xy 298.68622 -234.996736) (xy 298.68622 -234.44708) (xy 299.31614 -234.44708) (xy 299.31614 -234.996736)
			)
		)
	)
	(zone
		(layer "In11.Cu")
		(hatch none 0.5)
		(connect_pads
			(clearance 0)
		)
		(min_thickness 0.25)
		(keepout
			(tracks allowed)
			(vias allowed)
			(pads allowed)
			(copperpour allowed)
			(footprints allowed)
		)
		(placement
			(enabled no)
			(sheetname "")
		)
		(fill
			(thermal_gap 0.5)
			(thermal_bridge_width 0.5)
			(island_removal_mode 0)
		)
		(polygon
			(pts
				(xy 20.570952 -234.996736) (xy 20.570952 -234.44708) (xy 21.200872 -234.44708) (xy 21.200872 -234.996736)
			)
		)
	)
	(zone
		(layer "In11.Cu")
		(hatch none 0.5)
		(connect_pads
			(clearance 0)
		)
		(min_thickness 0.25)
		(keepout
			(tracks allowed)
			(vias allowed)
			(pads allowed)
			(copperpour allowed)
			(footprints allowed)
		)
		(placement
			(enabled no)
			(sheetname "")
		)
		(fill
			(thermal_gap 0.5)
			(thermal_bridge_width 0.5)
			(island_removal_mode 0)
		)
		(polygon
			(pts
				(xy 173.070774 -250.81484) (xy 173.070774 -251.09043) (xy 172.511974 -251.09043) (xy 172.511974 -250.81484)
			)
		)
	)
	(zone
		(layer "In11.Cu")
		(hatch none 0.5)
		(connect_pads
			(clearance 0)
		)
		(min_thickness 0.25)
		(keepout
			(tracks allowed)
			(vias allowed)
			(pads allowed)
			(copperpour allowed)
			(footprints allowed)
		)
		(placement
			(enabled no)
			(sheetname "")
		)
		(fill
			(thermal_gap 0.5)
			(thermal_bridge_width 0.5)
			(island_removal_mode 0)
		)
		(polygon
			(pts
				(xy 140.065252 -259.01269) (xy 140.514578 -259.01269) (xy 141.896338 -260.39445) (xy 147.044918 -260.39445)
				(xy 147.436078 -260.78561) (xy 147.918678 -261.26821) (xy 147.918678 -261.55269) (xy 147.316698 -262.15467)
				(xy 146.498818 -262.15467) (xy 141.126718 -262.15467) (xy 140.476478 -262.15467) (xy 140.016738 -261.69493)
				(xy 140.016738 -261.505954) (xy 140.175996 -261.346696) (xy 140.203936 -261.346696) (xy 140.215366 -261.335266)
				(xy 140.215366 -261.132828) (xy 140.019532 -260.936994) (xy 140.016738 -260.936994) (xy 140.016738 -260.719316)
				(xy 140.13942 -260.596634) (xy 140.13942 -260.13029) (xy 140.065252 -260.056122)
			)
		)
	)
	(zone
		(layer "In11.Cu")
		(hatch none 0.5)
		(connect_pads
			(clearance 0)
		)
		(min_thickness 0.25)
		(keepout
			(tracks allowed)
			(vias allowed)
			(pads allowed)
			(copperpour allowed)
			(footprints allowed)
		)
		(placement
			(enabled no)
			(sheetname "")
		)
		(fill
			(thermal_gap 0.5)
			(thermal_bridge_width 0.5)
			(island_removal_mode 0)
		)
		(polygon
			(pts
				(xy 20.624292 -298.750736) (xy 20.624292 -298.200318) (xy 21.183092 -298.200318) (xy 21.183092 -298.750736)
			)
		)
	)
	(zone
		(layer "In11.Cu")
		(hatch none 0.5)
		(connect_pads
			(clearance 0)
		)
		(min_thickness 0.25)
		(keepout
			(tracks allowed)
			(vias allowed)
			(pads allowed)
			(copperpour allowed)
			(footprints allowed)
		)
		(placement
			(enabled no)
			(sheetname "")
		)
		(fill
			(thermal_gap 0.5)
			(thermal_bridge_width 0.5)
			(island_removal_mode 0)
		)
		(polygon
			(pts
				(xy 188.158374 -227.014786) (xy 188.158374 -227.290376) (xy 187.599574 -227.290376) (xy 187.599574 -227.014786)
			)
		)
	)
	(zone
		(layer "In11.Cu")
		(hatch none 0.5)
		(connect_pads
			(clearance 0)
		)
		(min_thickness 0.25)
		(keepout
			(tracks allowed)
			(vias allowed)
			(pads allowed)
			(copperpour allowed)
			(footprints allowed)
		)
		(placement
			(enabled no)
			(sheetname "")
		)
		(fill
			(thermal_gap 0.5)
			(thermal_bridge_width 0.5)
			(island_removal_mode 0)
		)
		(polygon
			(pts
				(xy 50.771552 -298.746926) (xy 50.771552 -298.19727) (xy 51.401472 -298.19727) (xy 51.401472 -298.746926)
			)
		)
	)
	(zone
		(layer "In11.Cu")
		(hatch none 0.5)
		(connect_pads
			(clearance 0)
		)
		(min_thickness 0.25)
		(keepout
			(tracks allowed)
			(vias allowed)
			(pads allowed)
			(copperpour allowed)
			(footprints allowed)
		)
		(placement
			(enabled no)
			(sheetname "")
		)
		(fill
			(thermal_gap 0.5)
			(thermal_bridge_width 0.5)
			(island_removal_mode 0)
		)
		(polygon
			(pts
				(xy 172.521118 -301.068486) (xy 172.521118 -300.792896) (xy 173.079918 -300.792896) (xy 173.079918 -301.068486)
			)
		)
	)
	(zone
		(layer "In11.Cu")
		(hatch none 0.5)
		(connect_pads
			(clearance 0)
		)
		(min_thickness 0.25)
		(keepout
			(tracks allowed)
			(vias allowed)
			(pads allowed)
			(copperpour allowed)
			(footprints allowed)
		)
		(placement
			(enabled no)
			(sheetname "")
		)
		(fill
			(thermal_gap 0.5)
			(thermal_bridge_width 0.5)
			(island_removal_mode 0)
		)
		(polygon
			(pts
				(xy 436.098442 -282.264612) (xy 436.098442 -282.540202) (xy 435.539642 -282.540202) (xy 435.539642 -282.264612)
			)
		)
	)
	(zone
		(layer "In11.Cu")
		(hatch none 0.5)
		(connect_pads
			(clearance 0)
		)
		(min_thickness 0.25)
		(keepout
			(tracks allowed)
			(vias allowed)
			(pads allowed)
			(copperpour allowed)
			(footprints allowed)
		)
		(placement
			(enabled no)
			(sheetname "")
		)
		(fill
			(thermal_gap 0.5)
			(thermal_bridge_width 0.5)
			(island_removal_mode 0)
		)
		(polygon
			(pts
				(xy 176.621186 -200.768458) (xy 176.621186 -200.492868) (xy 177.179986 -200.492868) (xy 177.179986 -200.768458)
			)
		)
	)
	(zone
		(layer "In11.Cu")
		(hatch none 0.5)
		(connect_pads
			(clearance 0)
		)
		(min_thickness 0.25)
		(keepout
			(tracks allowed)
			(vias allowed)
			(pads allowed)
			(copperpour allowed)
			(footprints allowed)
		)
		(placement
			(enabled no)
			(sheetname "")
		)
		(fill
			(thermal_gap 0.5)
			(thermal_bridge_width 0.5)
			(island_removal_mode 0)
		)
		(polygon
			(pts
				(xy 173.070774 -315.41466) (xy 173.070774 -315.69025) (xy 172.511974 -315.69025) (xy 172.511974 -315.41466)
			)
		)
	)
	(zone
		(layer "In11.Cu")
		(hatch none 0.5)
		(connect_pads
			(clearance 0)
		)
		(min_thickness 0.25)
		(keepout
			(tracks allowed)
			(vias allowed)
			(pads allowed)
			(copperpour allowed)
			(footprints allowed)
		)
		(placement
			(enabled no)
			(sheetname "")
		)
		(fill
			(thermal_gap 0.5)
			(thermal_bridge_width 0.5)
			(island_removal_mode 0)
		)
		(polygon
			(pts
				(xy 50.771552 -259.646928) (xy 50.771552 -259.097272) (xy 51.401472 -259.097272) (xy 51.401472 -259.646928)
			)
		)
	)
	(zone
		(layer "In11.Cu")
		(hatch none 0.5)
		(connect_pads
			(clearance 0)
		)
		(min_thickness 0.25)
		(keepout
			(tracks allowed)
			(vias allowed)
			(pads allowed)
			(copperpour allowed)
			(footprints allowed)
		)
		(placement
			(enabled no)
			(sheetname "")
		)
		(fill
			(thermal_gap 0.5)
			(thermal_bridge_width 0.5)
			(island_removal_mode 0)
		)
		(polygon
			(pts
				(xy 420.461186 -239.868456) (xy 420.461186 -239.592866) (xy 421.019986 -239.592866) (xy 421.019986 -239.868456)
			)
		)
	)
	(zone
		(layer "In11.Cu")
		(hatch none 0.5)
		(connect_pads
			(clearance 0)
		)
		(min_thickness 0.25)
		(keepout
			(tracks allowed)
			(vias allowed)
			(pads allowed)
			(copperpour allowed)
			(footprints allowed)
		)
		(placement
			(enabled no)
			(sheetname "")
		)
		(fill
			(thermal_gap 0.5)
			(thermal_bridge_width 0.5)
			(island_removal_mode 0)
		)
		(polygon
			(pts
				(xy 420.461186 -298.51858) (xy 420.461186 -298.24299) (xy 421.019986 -298.24299) (xy 421.019986 -298.51858)
			)
		)
	)
	(zone
		(layer "In11.Cu")
		(hatch none 0.5)
		(connect_pads
			(clearance 0)
		)
		(min_thickness 0.25)
		(keepout
			(tracks allowed)
			(vias allowed)
			(pads allowed)
			(copperpour allowed)
			(footprints allowed)
		)
		(placement
			(enabled no)
			(sheetname "")
		)
		(fill
			(thermal_gap 0.5)
			(thermal_bridge_width 0.5)
			(island_removal_mode 0)
		)
		(polygon
			(pts
				(xy 425.11091 -306.064666) (xy 425.11091 -306.340256) (xy 424.55211 -306.340256) (xy 424.55211 -306.064666)
			)
		)
	)
	(zone
		(layer "In11.Cu")
		(hatch none 0.5)
		(connect_pads
			(clearance 0)
		)
		(min_thickness 0.25)
		(keepout
			(tracks allowed)
			(vias allowed)
			(pads allowed)
			(copperpour allowed)
			(footprints allowed)
		)
		(placement
			(enabled no)
			(sheetname "")
		)
		(fill
			(thermal_gap 0.5)
			(thermal_bridge_width 0.5)
			(island_removal_mode 0)
		)
		(polygon
			(pts
				(xy 50.746152 -236.696758) (xy 50.746152 -236.147102) (xy 51.376072 -236.147102) (xy 51.376072 -236.696758)
			)
		)
	)
	(zone
		(layer "In11.Cu")
		(hatch none 0.5)
		(connect_pads
			(clearance 0)
		)
		(min_thickness 0.25)
		(keepout
			(tracks not_allowed)
			(vias allowed)
			(pads allowed)
			(copperpour not_allowed)
			(footprints allowed)
		)
		(placement
			(enabled no)
			(sheetname "")
		)
		(fill
			(thermal_gap 0.5)
			(thermal_bridge_width 0.5)
			(island_removal_mode 0)
		)
		(polygon
			(pts
				(arc
					(start 404.242016 -428.960788)
					(mid 404.264334 -429.01467)
					(end 404.318216 -429.036988)
				)
				(arc
					(start 405.258016 -429.036988)
					(mid 405.311898 -429.01467)
					(end 405.334216 -428.960788)
				)
				(arc
					(start 405.334216 -426.419264)
					(mid 405.311898 -426.365382)
					(end 405.258016 -426.343064)
				)
				(arc
					(start 404.318216 -426.343064)
					(mid 404.264334 -426.365382)
					(end 404.242016 -426.419264)
				)
			)
		)
	)
	(zone
		(layer "In11.Cu")
		(hatch none 0.5)
		(connect_pads
			(clearance 0)
		)
		(min_thickness 0.25)
		(keepout
			(tracks allowed)
			(vias allowed)
			(pads allowed)
			(copperpour allowed)
			(footprints allowed)
		)
		(placement
			(enabled no)
			(sheetname "")
		)
		(fill
			(thermal_gap 0.5)
			(thermal_bridge_width 0.5)
			(island_removal_mode 0)
		)
		(polygon
			(pts
				(xy 202.696318 -287.468564) (xy 202.696318 -287.192974) (xy 203.255118 -287.192974) (xy 203.255118 -287.468564)
			)
		)
	)
	(zone
		(layer "In11.Cu")
		(hatch none 0.5)
		(connect_pads
			(clearance 0)
		)
		(min_thickness 0.25)
		(keepout
			(tracks allowed)
			(vias allowed)
			(pads allowed)
			(copperpour allowed)
			(footprints allowed)
		)
		(placement
			(enabled no)
			(sheetname "")
		)
		(fill
			(thermal_gap 0.5)
			(thermal_bridge_width 0.5)
			(island_removal_mode 0)
		)
		(polygon
			(pts
				(xy 50.771552 -281.74696) (xy 50.771552 -281.197304) (xy 51.401472 -281.197304) (xy 51.401472 -281.74696)
			)
		)
	)
	(zone
		(layer "In11.Cu")
		(hatch none 0.5)
		(connect_pads
			(clearance 0)
		)
		(min_thickness 0.25)
		(keepout
			(tracks allowed)
			(vias allowed)
			(pads allowed)
			(copperpour allowed)
			(footprints allowed)
		)
		(placement
			(enabled no)
			(sheetname "")
		)
		(fill
			(thermal_gap 0.5)
			(thermal_bridge_width 0.5)
			(island_removal_mode 0)
		)
		(polygon
			(pts
				(xy 268.51102 -237.546896) (xy 268.51102 -236.99724) (xy 269.14094 -236.99724) (xy 269.14094 -237.546896)
			)
		)
	)
	(zone
		(layer "In11.Cu")
		(hatch none 0.5)
		(connect_pads
			(clearance 0)
		)
		(min_thickness 0.25)
		(keepout
			(tracks allowed)
			(vias allowed)
			(pads allowed)
			(copperpour allowed)
			(footprints allowed)
		)
		(placement
			(enabled no)
			(sheetname "")
		)
		(fill
			(thermal_gap 0.5)
			(thermal_bridge_width 0.5)
			(island_removal_mode 0)
		)
		(polygon
			(pts
				(xy 298.71162 -293.647114) (xy 298.71162 -293.097458) (xy 299.34154 -293.097458) (xy 299.34154 -293.647114)
			)
		)
	)
	(zone
		(layer "In11.Cu")
		(hatch none 0.5)
		(connect_pads
			(clearance 0)
		)
		(min_thickness 0.25)
		(keepout
			(tracks allowed)
			(vias allowed)
			(pads allowed)
			(copperpour allowed)
			(footprints allowed)
		)
		(placement
			(enabled no)
			(sheetname "")
		)
		(fill
			(thermal_gap 0.5)
			(thermal_bridge_width 0.5)
			(island_removal_mode 0)
		)
		(polygon
			(pts
				(xy 425.11091 -233.81462) (xy 425.11091 -234.09021) (xy 424.55211 -234.09021) (xy 424.55211 -233.81462)
			)
		)
	)
	(zone
		(layer "In11.Cu")
		(hatch none 0.5)
		(connect_pads
			(clearance 0)
		)
		(min_thickness 0.25)
		(keepout
			(tracks allowed)
			(vias allowed)
			(pads allowed)
			(copperpour allowed)
			(footprints allowed)
		)
		(placement
			(enabled no)
			(sheetname "")
		)
		(fill
			(thermal_gap 0.5)
			(thermal_bridge_width 0.5)
			(island_removal_mode 0)
		)
		(polygon
			(pts
				(xy 436.098442 -233.81462) (xy 436.098442 -234.09021) (xy 435.539642 -234.09021) (xy 435.539642 -233.81462)
			)
		)
	)
	(zone
		(layer "In11.Cu")
		(hatch none 0.5)
		(connect_pads
			(clearance 0)
		)
		(min_thickness 0.25)
		(keepout
			(tracks allowed)
			(vias allowed)
			(pads allowed)
			(copperpour allowed)
			(footprints allowed)
		)
		(placement
			(enabled no)
			(sheetname "")
		)
		(fill
			(thermal_gap 0.5)
			(thermal_bridge_width 0.5)
			(island_removal_mode 0)
		)
		(polygon
			(pts
				(xy 173.070774 -289.914838) (xy 173.070774 -290.190428) (xy 172.511974 -290.190428) (xy 172.511974 -289.914838)
			)
		)
	)
	(zone
		(layer "In11.Cu")
		(hatch none 0.5)
		(connect_pads
			(clearance 0)
		)
		(min_thickness 0.25)
		(keepout
			(tracks allowed)
			(vias allowed)
			(pads allowed)
			(copperpour allowed)
			(footprints allowed)
		)
		(placement
			(enabled no)
			(sheetname "")
		)
		(fill
			(thermal_gap 0.5)
			(thermal_bridge_width 0.5)
			(island_removal_mode 0)
		)
		(polygon
			(pts
				(xy 20.570952 -216.296748) (xy 20.570952 -215.747092) (xy 21.200872 -215.747092) (xy 21.200872 -216.296748)
			)
		)
	)
	(zone
		(layer "In11.Cu")
		(hatch none 0.5)
		(connect_pads
			(clearance 0)
		)
		(min_thickness 0.25)
		(keepout
			(tracks allowed)
			(vias allowed)
			(pads allowed)
			(copperpour allowed)
			(footprints allowed)
		)
		(placement
			(enabled no)
			(sheetname "")
		)
		(fill
			(thermal_gap 0.5)
			(thermal_bridge_width 0.5)
			(island_removal_mode 0)
		)
		(polygon
			(pts
				(xy 172.521118 -307.868574) (xy 172.521118 -307.592984) (xy 173.079918 -307.592984) (xy 173.079918 -307.868574)
			)
		)
	)
	(zone
		(layer "In11.Cu")
		(hatch none 0.5)
		(connect_pads
			(clearance 0)
		)
		(min_thickness 0.25)
		(keepout
			(tracks allowed)
			(vias allowed)
			(pads allowed)
			(copperpour allowed)
			(footprints allowed)
		)
		(placement
			(enabled no)
			(sheetname "")
		)
		(fill
			(thermal_gap 0.5)
			(thermal_bridge_width 0.5)
			(island_removal_mode 0)
		)
		(polygon
			(pts
				(xy 421.010842 -310.314848) (xy 421.010842 -310.590438) (xy 420.452042 -310.590438) (xy 420.452042 -310.314848)
			)
		)
	)
	(zone
		(layer "In11.Cu")
		(hatch none 0.5)
		(connect_pads
			(clearance 0)
		)
		(min_thickness 0.25)
		(keepout
			(tracks allowed)
			(vias allowed)
			(pads allowed)
			(copperpour allowed)
			(footprints allowed)
		)
		(placement
			(enabled no)
			(sheetname "")
		)
		(fill
			(thermal_gap 0.5)
			(thermal_bridge_width 0.5)
			(island_removal_mode 0)
		)
		(polygon
			(pts
				(xy 298.71162 -267.2969) (xy 298.71162 -266.747244) (xy 299.34154 -266.747244) (xy 299.34154 -267.2969)
			)
		)
	)
	(zone
		(layer "In11.Cu")
		(hatch none 0.5)
		(connect_pads
			(clearance 0)
		)
		(min_thickness 0.25)
		(keepout
			(tracks allowed)
			(vias allowed)
			(pads allowed)
			(copperpour allowed)
			(footprints allowed)
		)
		(placement
			(enabled no)
			(sheetname "")
		)
		(fill
			(thermal_gap 0.5)
			(thermal_bridge_width 0.5)
			(island_removal_mode 0)
		)
		(polygon
			(pts
				(xy 425.11091 -309.46471) (xy 425.11091 -309.7403) (xy 424.55211 -309.7403) (xy 424.55211 -309.46471)
			)
		)
	)
	(zone
		(layer "In11.Cu")
		(hatch none 0.5)
		(connect_pads
			(clearance 0)
		)
		(min_thickness 0.25)
		(keepout
			(tracks allowed)
			(vias allowed)
			(pads allowed)
			(copperpour allowed)
			(footprints allowed)
		)
		(placement
			(enabled no)
			(sheetname "")
		)
		(fill
			(thermal_gap 0.5)
			(thermal_bridge_width 0.5)
			(island_removal_mode 0)
		)
		(polygon
			(pts
				(xy 450.636386 -242.418616) (xy 450.636386 -242.143026) (xy 451.195186 -242.143026) (xy 451.195186 -242.418616)
			)
		)
	)
	(zone
		(layer "In11.Cu")
		(hatch none 0.5)
		(connect_pads
			(clearance 0)
		)
		(min_thickness 0.25)
		(keepout
			(tracks allowed)
			(vias allowed)
			(pads allowed)
			(copperpour allowed)
			(footprints allowed)
		)
		(placement
			(enabled no)
			(sheetname "")
		)
		(fill
			(thermal_gap 0.5)
			(thermal_bridge_width 0.5)
			(island_removal_mode 0)
		)
		(polygon
			(pts
				(xy 50.771552 -274.096734) (xy 50.771552 -273.547078) (xy 51.401472 -273.547078) (xy 51.401472 -274.096734)
			)
		)
	)
	(zone
		(layer "In11.Cu")
		(hatch none 0.5)
		(connect_pads
			(clearance 0)
		)
		(min_thickness 0.25)
		(keepout
			(tracks allowed)
			(vias allowed)
			(pads allowed)
			(copperpour allowed)
			(footprints allowed)
		)
		(placement
			(enabled no)
			(sheetname "")
		)
		(fill
			(thermal_gap 0.5)
			(thermal_bridge_width 0.5)
			(island_removal_mode 0)
		)
		(polygon
			(pts
				(xy 76.89596 -348.145608) (xy 76.89596 -343.599008) (xy 81.22412 -343.599008) (xy 81.22412 -348.145608)
			)
		)
	)
	(zone
		(layer "In11.Cu")
		(hatch none 0.5)
		(connect_pads
			(clearance 0)
		)
		(min_thickness 0.25)
		(keepout
			(tracks allowed)
			(vias allowed)
			(pads allowed)
			(copperpour allowed)
			(footprints allowed)
		)
		(placement
			(enabled no)
			(sheetname "")
		)
		(fill
			(thermal_gap 0.5)
			(thermal_bridge_width 0.5)
			(island_removal_mode 0)
		)
		(polygon
			(pts
				(xy 298.68622 -203.546964) (xy 298.68622 -202.997308) (xy 299.31614 -202.997308) (xy 299.31614 -203.546964)
			)
		)
	)
	(zone
		(layer "In11.Cu")
		(hatch none 0.5)
		(connect_pads
			(clearance 0)
		)
		(min_thickness 0.25)
		(keepout
			(tracks allowed)
			(vias allowed)
			(pads allowed)
			(copperpour allowed)
			(footprints allowed)
		)
		(placement
			(enabled no)
			(sheetname "")
		)
		(fill
			(thermal_gap 0.5)
			(thermal_bridge_width 0.5)
			(island_removal_mode 0)
		)
		(polygon
			(pts
				(xy 451.186042 -239.764824) (xy 451.186042 -240.040414) (xy 450.627242 -240.040414) (xy 450.627242 -239.764824)
			)
		)
	)
	(zone
		(layer "In11.Cu")
		(hatch none 0.5)
		(connect_pads
			(clearance 0)
		)
		(min_thickness 0.25)
		(keepout
			(tracks allowed)
			(vias allowed)
			(pads allowed)
			(copperpour allowed)
			(footprints allowed)
		)
		(placement
			(enabled no)
			(sheetname "")
		)
		(fill
			(thermal_gap 0.5)
			(thermal_bridge_width 0.5)
			(island_removal_mode 0)
		)
		(polygon
			(pts
				(xy 425.11091 -261.864856) (xy 425.11091 -262.140446) (xy 424.55211 -262.140446) (xy 424.55211 -261.864856)
			)
		)
	)
	(zone
		(layer "In11.Cu")
		(hatch none 0.5)
		(connect_pads
			(clearance 0)
		)
		(min_thickness 0.25)
		(keepout
			(tracks allowed)
			(vias allowed)
			(pads allowed)
			(copperpour allowed)
			(footprints allowed)
		)
		(placement
			(enabled no)
			(sheetname "")
		)
		(fill
			(thermal_gap 0.5)
			(thermal_bridge_width 0.5)
			(island_removal_mode 0)
		)
		(polygon
			(pts
				(xy 203.245974 -291.614606) (xy 203.245974 -291.890196) (xy 203.245974 -291.929058) (xy 202.736196 -291.929058)
				(xy 202.736196 -292.18636) (xy 202.204574 -292.18636) (xy 202.204574 -291.27323) (xy 202.783186 -291.27323)
				(xy 202.783186 -291.614606)
			)
		)
	)
	(zone
		(layer "In11.Cu")
		(hatch none 0.5)
		(connect_pads
			(clearance 0)
		)
		(min_thickness 0.25)
		(keepout
			(tracks allowed)
			(vias allowed)
			(pads allowed)
			(copperpour allowed)
			(footprints allowed)
		)
		(placement
			(enabled no)
			(sheetname "")
		)
		(fill
			(thermal_gap 0.5)
			(thermal_bridge_width 0.5)
			(island_removal_mode 0)
		)
		(polygon
			(pts
				(xy 425.11091 -210.01482) (xy 425.11091 -210.29041) (xy 424.55211 -210.29041) (xy 424.55211 -210.01482)
			)
		)
	)
	(zone
		(layer "In11.Cu")
		(hatch none 0.5)
		(connect_pads
			(clearance 0)
		)
		(min_thickness 0.25)
		(keepout
			(tracks allowed)
			(vias allowed)
			(pads allowed)
			(copperpour allowed)
			(footprints allowed)
		)
		(placement
			(enabled no)
			(sheetname "")
		)
		(fill
			(thermal_gap 0.5)
			(thermal_bridge_width 0.5)
			(island_removal_mode 0)
		)
		(polygon
			(pts
				(xy 20.61845 -263.892284) (xy 20.61845 -263.352026) (xy 21.17725 -263.352026) (xy 21.17725 -263.892284)
			)
		)
	)
	(zone
		(layer "In11.Cu")
		(hatch none 0.5)
		(connect_pads
			(clearance 0)
		)
		(min_thickness 0.25)
		(keepout
			(tracks allowed)
			(vias allowed)
			(pads allowed)
			(copperpour allowed)
			(footprints allowed)
		)
		(placement
			(enabled no)
			(sheetname "")
		)
		(fill
			(thermal_gap 0.5)
			(thermal_bridge_width 0.5)
			(island_removal_mode 0)
		)
		(polygon
			(pts
				(xy 46.646084 -299.59681) (xy 46.646084 -299.047154) (xy 47.276004 -299.047154) (xy 47.276004 -299.59681)
			)
		)
	)
	(zone
		(layer "In11.Cu")
		(hatch none 0.5)
		(connect_pads
			(clearance 0)
		)
		(min_thickness 0.25)
		(keepout
			(tracks allowed)
			(vias allowed)
			(pads allowed)
			(copperpour allowed)
			(footprints allowed)
		)
		(placement
			(enabled no)
			(sheetname "")
		)
		(fill
			(thermal_gap 0.5)
			(thermal_bridge_width 0.5)
			(island_removal_mode 0)
		)
		(polygon
			(pts
				(xy 46.646084 -223.096836) (xy 46.646084 -222.54718) (xy 47.276004 -222.54718) (xy 47.276004 -223.096836)
			)
		)
	)
	(zone
		(layer "In11.Cu")
		(hatch none 0.5)
		(connect_pads
			(clearance 0)
		)
		(min_thickness 0.25)
		(keepout
			(tracks allowed)
			(vias allowed)
			(pads allowed)
			(copperpour allowed)
			(footprints allowed)
		)
		(placement
			(enabled no)
			(sheetname "")
		)
		(fill
			(thermal_gap 0.5)
			(thermal_bridge_width 0.5)
			(island_removal_mode 0)
		)
		(polygon
			(pts
				(xy 451.186042 -222.764604) (xy 451.186042 -223.040194) (xy 450.627242 -223.040194) (xy 450.627242 -222.764604)
				(xy 450.627242 -222.323406) (xy 451.186042 -222.323406)
			)
		)
	)
	(zone
		(layer "In11.Cu")
		(hatch none 0.5)
		(connect_pads
			(clearance 0)
		)
		(min_thickness 0.25)
		(keepout
			(tracks allowed)
			(vias allowed)
			(pads allowed)
			(copperpour allowed)
			(footprints allowed)
		)
		(placement
			(enabled no)
			(sheetname "")
		)
		(fill
			(thermal_gap 0.5)
			(thermal_bridge_width 0.5)
			(island_removal_mode 0)
		)
		(polygon
			(pts
				(xy 50.746152 -231.596946) (xy 50.746152 -231.04729) (xy 51.376072 -231.04729) (xy 51.376072 -231.596946)
			)
		)
	)
	(zone
		(layer "In11.Cu")
		(hatch none 0.5)
		(connect_pads
			(clearance 0)
		)
		(min_thickness 0.25)
		(keepout
			(tracks allowed)
			(vias allowed)
			(pads allowed)
			(copperpour allowed)
			(footprints allowed)
		)
		(placement
			(enabled no)
			(sheetname "")
		)
		(fill
			(thermal_gap 0.5)
			(thermal_bridge_width 0.5)
			(island_removal_mode 0)
		)
		(polygon
			(pts
				(xy 298.71162 -308.09692) (xy 298.71162 -307.547264) (xy 299.34154 -307.547264) (xy 299.34154 -308.09692)
			)
		)
	)
	(zone
		(layer "In11.Cu")
		(hatch none 0.5)
		(connect_pads
			(clearance 0)
		)
		(min_thickness 0.25)
		(keepout
			(tracks allowed)
			(vias allowed)
			(pads allowed)
			(copperpour allowed)
			(footprints allowed)
		)
		(placement
			(enabled no)
			(sheetname "")
		)
		(fill
			(thermal_gap 0.5)
			(thermal_bridge_width 0.5)
			(island_removal_mode 0)
		)
		(polygon
			(pts
				(xy 46.646084 -277.496778) (xy 46.646084 -276.947122) (xy 47.276004 -276.947122) (xy 47.276004 -277.496778)
			)
		)
	)
	(zone
		(layer "In11.Cu")
		(hatch none 0.5)
		(connect_pads
			(clearance 0)
		)
		(min_thickness 0.25)
		(keepout
			(tracks allowed)
			(vias allowed)
			(pads allowed)
			(copperpour allowed)
			(footprints allowed)
		)
		(placement
			(enabled no)
			(sheetname "")
		)
		(fill
			(thermal_gap 0.5)
			(thermal_bridge_width 0.5)
			(island_removal_mode 0)
		)
		(polygon
			(pts
				(xy 420.461186 -241.568478) (xy 420.461186 -241.292888) (xy 421.019986 -241.292888) (xy 421.019986 -241.568478)
			)
		)
	)
	(zone
		(layer "In11.Cu")
		(hatch none 0.5)
		(connect_pads
			(clearance 0)
		)
		(min_thickness 0.25)
		(keepout
			(tracks allowed)
			(vias allowed)
			(pads allowed)
			(copperpour allowed)
			(footprints allowed)
		)
		(placement
			(enabled no)
			(sheetname "")
		)
		(fill
			(thermal_gap 0.5)
			(thermal_bridge_width 0.5)
			(island_removal_mode 0)
		)
		(polygon
			(pts
				(xy 450.636386 -283.218382) (xy 450.636386 -282.942792) (xy 451.195186 -282.942792) (xy 451.195186 -283.218382)
			)
		)
	)
	(zone
		(layer "In11.Cu")
		(hatch none 0.5)
		(connect_pads
			(clearance 0)
		)
		(min_thickness 0.25)
		(keepout
			(tracks allowed)
			(vias allowed)
			(pads allowed)
			(copperpour allowed)
			(footprints allowed)
		)
		(placement
			(enabled no)
			(sheetname "")
		)
		(fill
			(thermal_gap 0.5)
			(thermal_bridge_width 0.5)
			(island_removal_mode 0)
		)
		(polygon
			(pts
				(xy 420.461186 -291.718492) (xy 420.461186 -291.442902) (xy 421.019986 -291.442902) (xy 421.019986 -291.718492)
			)
		)
	)
	(zone
		(layer "In11.Cu")
		(hatch none 0.5)
		(connect_pads
			(clearance 0)
		)
		(min_thickness 0.25)
		(keepout
			(tracks allowed)
			(vias allowed)
			(pads allowed)
			(copperpour allowed)
			(footprints allowed)
		)
		(placement
			(enabled no)
			(sheetname "")
		)
		(fill
			(thermal_gap 0.5)
			(thermal_bridge_width 0.5)
			(island_removal_mode 0)
		)
		(polygon
			(pts
				(xy 268.56436 -281.75077) (xy 268.56436 -281.200352) (xy 269.12316 -281.200352) (xy 269.12316 -281.75077)
			)
		)
	)
	(zone
		(layer "In11.Cu")
		(hatch none 0.5)
		(connect_pads
			(clearance 0)
		)
		(min_thickness 0.25)
		(keepout
			(tracks allowed)
			(vias allowed)
			(pads allowed)
			(copperpour allowed)
			(footprints allowed)
		)
		(placement
			(enabled no)
			(sheetname "")
		)
		(fill
			(thermal_gap 0.5)
			(thermal_bridge_width 0.5)
			(island_removal_mode 0)
		)
		(polygon
			(pts
				(xy 424.561254 -207.568546) (xy 424.561254 -207.292956) (xy 425.120054 -207.292956) (xy 425.120054 -207.568546)
			)
		)
	)
	(zone
		(layer "In11.Cu")
		(hatch none 0.5)
		(connect_pads
			(clearance 0)
		)
		(min_thickness 0.25)
		(keepout
			(tracks allowed)
			(vias allowed)
			(pads allowed)
			(copperpour allowed)
			(footprints allowed)
		)
		(placement
			(enabled no)
			(sheetname "")
		)
		(fill
			(thermal_gap 0.5)
			(thermal_bridge_width 0.5)
			(island_removal_mode 0)
		)
		(polygon
			(pts
				(xy 420.461186 -230.518462) (xy 420.461186 -230.242872) (xy 421.019986 -230.242872) (xy 421.019986 -230.518462)
			)
		)
	)
	(zone
		(layer "In11.Cu")
		(hatch none 0.5)
		(connect_pads
			(clearance 0)
		)
		(min_thickness 0.25)
		(keepout
			(tracks allowed)
			(vias allowed)
			(pads allowed)
			(copperpour allowed)
			(footprints allowed)
		)
		(placement
			(enabled no)
			(sheetname "")
		)
		(fill
			(thermal_gap 0.5)
			(thermal_bridge_width 0.5)
			(island_removal_mode 0)
		)
		(polygon
			(pts
				(xy 425.11091 -258.464812) (xy 425.11091 -258.740402) (xy 424.55211 -258.740402) (xy 424.55211 -258.464812)
			)
		)
	)
	(zone
		(layer "In11.Cu")
		(hatch none 0.5)
		(connect_pads
			(clearance 0)
		)
		(min_thickness 0.25)
		(keepout
			(tracks allowed)
			(vias allowed)
			(pads allowed)
			(copperpour allowed)
			(footprints allowed)
		)
		(placement
			(enabled no)
			(sheetname "")
		)
		(fill
			(thermal_gap 0.5)
			(thermal_bridge_width 0.5)
			(island_removal_mode 0)
		)
		(polygon
			(pts
				(xy 381.55626 -347.696028) (xy 381.55626 -343.825068) (xy 386.79628 -343.825068) (xy 386.79628 -347.696028)
			)
		)
	)
	(zone
		(layer "In11.Cu")
		(hatch none 0.5)
		(connect_pads
			(clearance 0)
		)
		(min_thickness 0.25)
		(keepout
			(tracks allowed)
			(vias allowed)
			(pads allowed)
			(copperpour allowed)
			(footprints allowed)
		)
		(placement
			(enabled no)
			(sheetname "")
		)
		(fill
			(thermal_gap 0.5)
			(thermal_bridge_width 0.5)
			(island_removal_mode 0)
		)
		(polygon
			(pts
				(xy 424.561254 -313.818524) (xy 424.561254 -313.542934) (xy 425.120054 -313.542934) (xy 425.120054 -313.818524)
			)
		)
	)
	(zone
		(layer "In11.Cu")
		(hatch none 0.5)
		(connect_pads
			(clearance 0)
		)
		(min_thickness 0.25)
		(keepout
			(tracks allowed)
			(vias allowed)
			(pads allowed)
			(copperpour allowed)
			(footprints allowed)
		)
		(placement
			(enabled no)
			(sheetname "")
		)
		(fill
			(thermal_gap 0.5)
			(thermal_bridge_width 0.5)
			(island_removal_mode 0)
		)
		(polygon
			(pts
				(xy 188.158374 -307.764688) (xy 188.158374 -308.040278) (xy 187.599574 -308.040278) (xy 187.599574 -307.764688)
			)
		)
	)
	(zone
		(layer "In11.Cu")
		(hatch none 0.5)
		(connect_pads
			(clearance 0)
		)
		(min_thickness 0.25)
		(keepout
			(tracks allowed)
			(vias allowed)
			(pads allowed)
			(copperpour allowed)
			(footprints allowed)
		)
		(placement
			(enabled no)
			(sheetname "")
		)
		(fill
			(thermal_gap 0.5)
			(thermal_bridge_width 0.5)
			(island_removal_mode 0)
		)
		(polygon
			(pts
				(xy 420.461186 -277.268432) (xy 420.461186 -276.992842) (xy 421.019986 -276.992842) (xy 421.019986 -277.268432)
			)
		)
	)
	(zone
		(layer "In11.Cu")
		(hatch none 0.5)
		(connect_pads
			(clearance 0)
		)
		(min_thickness 0.25)
		(keepout
			(tracks allowed)
			(vias allowed)
			(pads allowed)
			(copperpour allowed)
			(footprints allowed)
		)
		(placement
			(enabled no)
			(sheetname "")
		)
		(fill
			(thermal_gap 0.5)
			(thermal_bridge_width 0.5)
			(island_removal_mode 0)
		)
		(polygon
			(pts
				(xy 177.170842 -201.51471) (xy 177.170842 -201.7903) (xy 176.612042 -201.7903) (xy 176.612042 -201.51471)
			)
		)
	)
	(zone
		(layer "In11.Cu")
		(hatch none 0.5)
		(connect_pads
			(clearance 0)
		)
		(min_thickness 0.25)
		(keepout
			(tracks allowed)
			(vias allowed)
			(pads allowed)
			(copperpour allowed)
			(footprints allowed)
		)
		(placement
			(enabled no)
			(sheetname "")
		)
		(fill
			(thermal_gap 0.5)
			(thermal_bridge_width 0.5)
			(island_removal_mode 0)
		)
		(polygon
			(pts
				(xy 172.521118 -314.668408) (xy 172.521118 -314.392818) (xy 173.079918 -314.392818) (xy 173.079918 -314.668408)
			)
		)
	)
	(zone
		(layer "In11.Cu")
		(hatch none 0.5)
		(connect_pads
			(clearance 0)
		)
		(min_thickness 0.25)
		(keepout
			(tracks allowed)
			(vias allowed)
			(pads allowed)
			(copperpour allowed)
			(footprints allowed)
		)
		(placement
			(enabled no)
			(sheetname "")
		)
		(fill
			(thermal_gap 0.5)
			(thermal_bridge_width 0.5)
			(island_removal_mode 0)
		)
		(polygon
			(pts
				(xy 425.11091 -251.664724) (xy 425.11091 -251.940314) (xy 424.55211 -251.940314) (xy 424.55211 -251.664724)
			)
		)
	)
	(zone
		(layer "In11.Cu")
		(hatch none 0.5)
		(connect_pads
			(clearance 0)
		)
		(min_thickness 0.25)
		(keepout
			(tracks allowed)
			(vias allowed)
			(pads allowed)
			(copperpour allowed)
			(footprints allowed)
		)
		(placement
			(enabled no)
			(sheetname "")
		)
		(fill
			(thermal_gap 0.5)
			(thermal_bridge_width 0.5)
			(island_removal_mode 0)
		)
		(polygon
			(pts
				(xy 424.561254 -298.51858) (xy 424.561254 -298.24299) (xy 425.120054 -298.24299) (xy 425.120054 -298.51858)
			)
		)
	)
	(zone
		(layer "In11.Cu")
		(hatch none 0.5)
		(connect_pads
			(clearance 0)
		)
		(min_thickness 0.25)
		(keepout
			(tracks allowed)
			(vias allowed)
			(pads allowed)
			(copperpour allowed)
			(footprints allowed)
		)
		(placement
			(enabled no)
			(sheetname "")
		)
		(fill
			(thermal_gap 0.5)
			(thermal_bridge_width 0.5)
			(island_removal_mode 0)
		)
		(polygon
			(pts
				(xy 450.636386 -280.668476) (xy 450.636386 -280.392886) (xy 451.195186 -280.392886) (xy 451.195186 -280.668476)
			)
		)
	)
	(zone
		(layer "In11.Cu")
		(hatch none 0.5)
		(connect_pads
			(clearance 0)
		)
		(min_thickness 0.25)
		(keepout
			(tracks allowed)
			(vias allowed)
			(pads allowed)
			(copperpour allowed)
			(footprints allowed)
		)
		(placement
			(enabled no)
			(sheetname "")
		)
		(fill
			(thermal_gap 0.5)
			(thermal_bridge_width 0.5)
			(island_removal_mode 0)
		)
		(polygon
			(pts
				(xy 420.461186 -275.56841) (xy 420.461186 -275.29282) (xy 421.019986 -275.29282) (xy 421.019986 -275.56841)
			)
		)
	)
	(zone
		(layer "In11.Cu")
		(hatch none 0.5)
		(connect_pads
			(clearance 0)
		)
		(min_thickness 0.25)
		(keepout
			(tracks allowed)
			(vias allowed)
			(pads allowed)
			(copperpour allowed)
			(footprints allowed)
		)
		(placement
			(enabled no)
			(sheetname "")
		)
		(fill
			(thermal_gap 0.5)
			(thermal_bridge_width 0.5)
			(island_removal_mode 0)
		)
		(polygon
			(pts
				(xy 184.714642 -266.114784) (xy 184.714642 -266.390374) (xy 184.155842 -266.390374) (xy 184.155842 -266.114784)
			)
		)
	)
	(zone
		(layer "In11.Cu")
		(hatch none 0.5)
		(connect_pads
			(clearance 0)
		)
		(min_thickness 0.25)
		(keepout
			(tracks allowed)
			(vias allowed)
			(pads allowed)
			(copperpour allowed)
			(footprints allowed)
		)
		(placement
			(enabled no)
			(sheetname "")
		)
		(fill
			(thermal_gap 0.5)
			(thermal_bridge_width 0.5)
			(island_removal_mode 0)
		)
		(polygon
			(pts
				(xy 424.561254 -286.618426) (xy 424.561254 -286.342836) (xy 425.120054 -286.342836) (xy 425.120054 -286.618426)
			)
		)
	)
	(zone
		(layer "In11.Cu")
		(hatch none 0.5)
		(connect_pads
			(clearance 0)
		)
		(min_thickness 0.25)
		(keepout
			(tracks allowed)
			(vias allowed)
			(pads allowed)
			(copperpour allowed)
			(footprints allowed)
		)
		(placement
			(enabled no)
			(sheetname "")
		)
		(fill
			(thermal_gap 0.5)
			(thermal_bridge_width 0.5)
			(island_removal_mode 0)
		)
		(polygon
			(pts
				(xy 20.624292 -293.65067) (xy 20.624292 -293.100252) (xy 21.183092 -293.100252) (xy 21.183092 -293.65067)
			)
		)
	)
	(zone
		(layer "In11.Cu")
		(hatch none 0.5)
		(connect_pads
			(clearance 0)
		)
		(min_thickness 0.25)
		(keepout
			(tracks allowed)
			(vias allowed)
			(pads allowed)
			(copperpour allowed)
			(footprints allowed)
		)
		(placement
			(enabled no)
			(sheetname "")
		)
		(fill
			(thermal_gap 0.5)
			(thermal_bridge_width 0.5)
			(island_removal_mode 0)
		)
		(polygon
			(pts
				(xy 202.696318 -199.642984) (xy 203.255118 -199.642984) (xy 203.255118 -199.918574) (xy 203.255118 -200.05675)
				(xy 202.505818 -200.05675) (xy 202.505818 -199.642984)
			)
		)
	)
	(zone
		(layer "In11.Cu")
		(hatch none 0.5)
		(connect_pads
			(clearance 0)
		)
		(min_thickness 0.25)
		(keepout
			(tracks allowed)
			(vias allowed)
			(pads allowed)
			(copperpour allowed)
			(footprints allowed)
		)
		(placement
			(enabled no)
			(sheetname "")
		)
		(fill
			(thermal_gap 0.5)
			(thermal_bridge_width 0.5)
			(island_removal_mode 0)
		)
		(polygon
			(pts
				(xy 424.561254 -225.418396) (xy 424.561254 -225.142806) (xy 425.120054 -225.142806) (xy 425.120054 -225.418396)
			)
		)
	)
	(zone
		(layer "In11.Cu")
		(hatch none 0.5)
		(connect_pads
			(clearance 0)
		)
		(min_thickness 0.25)
		(keepout
			(tracks allowed)
			(vias allowed)
			(pads allowed)
			(copperpour allowed)
			(footprints allowed)
		)
		(placement
			(enabled no)
			(sheetname "")
		)
		(fill
			(thermal_gap 0.5)
			(thermal_bridge_width 0.5)
			(island_removal_mode 0)
		)
		(polygon
			(pts
				(xy 458.180186 -267.918438) (xy 458.180186 -267.642848) (xy 458.738986 -267.642848) (xy 458.738986 -267.918438)
			)
		)
	)
	(zone
		(layer "In11.Cu")
		(hatch none 0.5)
		(connect_pads
			(clearance 0)
		)
		(min_thickness 0.25)
		(keepout
			(tracks allowed)
			(vias allowed)
			(pads allowed)
			(copperpour allowed)
			(footprints allowed)
		)
		(placement
			(enabled no)
			(sheetname "")
		)
		(fill
			(thermal_gap 0.5)
			(thermal_bridge_width 0.5)
			(island_removal_mode 0)
		)
		(polygon
			(pts
				(xy 203.245974 -266.114784) (xy 203.245974 -266.390374) (xy 202.687174 -266.390374) (xy 202.630532 -266.390374)
				(xy 202.630532 -266.779248) (xy 202.055984 -266.779248) (xy 202.055984 -265.887454) (xy 203.245974 -265.887454)
			)
		)
	)
	(zone
		(layer "In11.Cu")
		(hatch none 0.5)
		(connect_pads
			(clearance 0)
		)
		(min_thickness 0.25)
		(keepout
			(tracks allowed)
			(vias allowed)
			(pads allowed)
			(copperpour allowed)
			(footprints allowed)
		)
		(placement
			(enabled no)
			(sheetname "")
		)
		(fill
			(thermal_gap 0.5)
			(thermal_bridge_width 0.5)
			(island_removal_mode 0)
		)
		(polygon
			(pts
				(xy 409.473654 -224.568512) (xy 409.473654 -224.292922) (xy 410.032454 -224.292922) (xy 410.032454 -224.568512)
			)
		)
	)
	(zone
		(layer "In11.Cu")
		(hatch none 0.5)
		(connect_pads
			(clearance 0)
		)
		(min_thickness 0.25)
		(keepout
			(tracks allowed)
			(vias allowed)
			(pads allowed)
			(copperpour allowed)
			(footprints allowed)
		)
		(placement
			(enabled no)
			(sheetname "")
		)
		(fill
			(thermal_gap 0.5)
			(thermal_bridge_width 0.5)
			(island_removal_mode 0)
		)
		(polygon
			(pts
				(xy 74.351134 -247.32615) (xy 74.419968 -247.394984) (xy 76.331318 -249.306334) (xy 76.331318 -249.819922)
				(xy 76.331318 -254.22606) (xy 75.486514 -255.070864) (xy 74.641456 -255.915668) (xy 74.641456 -256.25171)
				(xy 74.50074 -256.392426) (xy 71.440802 -256.392426) (xy 71.406258 -256.42697) (xy 71.406258 -260.764782)
				(xy 71.887842 -261.246366) (xy 71.887842 -261.755636) (xy 72.188832 -261.755636) (xy 74.023474 -259.920994)
				(xy 74.277474 -259.920994) (xy 76.773532 -259.920994) (xy 82.832702 -259.920994) (xy 82.859118 -259.894578)
				(xy 82.859118 -254.735076) (xy 82.855308 -254.731266) (xy 82.273902 -254.73152) (xy 82.25282 -254.710438)
				(xy 82.25282 -254.212598) (xy 82.244692 -254.20447) (xy 82.244692 -253.087124) (xy 82.244692 -252.375416)
				(xy 81.705958 -251.836682) (xy 81.705958 -251.214128) (xy 82.555842 -250.36399) (xy 84.602574 -250.36399)
				(xy 84.603844 -250.36272) (xy 84.603844 -248.966736) (xy 83.642708 -248.966736) (xy 83.59648 -248.920508)
				(xy 83.59648 -246.43969) (xy 74.073258 -246.43969) (xy 74.073258 -247.048274)
			)
		)
	)
	(zone
		(layer "In11.Cu")
		(hatch none 0.5)
		(connect_pads
			(clearance 0)
		)
		(min_thickness 0.25)
		(keepout
			(tracks allowed)
			(vias allowed)
			(pads allowed)
			(copperpour allowed)
			(footprints allowed)
		)
		(placement
			(enabled no)
			(sheetname "")
		)
		(fill
			(thermal_gap 0.5)
			(thermal_bridge_width 0.5)
			(island_removal_mode 0)
		)
		(polygon
			(pts
				(xy 177.170842 -280.56459) (xy 177.170842 -280.84018) (xy 176.612042 -280.84018) (xy 176.612042 -280.56459)
			)
		)
	)
	(zone
		(layer "In11.Cu")
		(hatch none 0.5)
		(connect_pads
			(clearance 0)
		)
		(min_thickness 0.25)
		(keepout
			(tracks allowed)
			(vias allowed)
			(pads allowed)
			(copperpour allowed)
			(footprints allowed)
		)
		(placement
			(enabled no)
			(sheetname "")
		)
		(fill
			(thermal_gap 0.5)
			(thermal_bridge_width 0.5)
			(island_removal_mode 0)
		)
		(polygon
			(pts
				(xy 172.521118 -239.868456) (xy 172.521118 -239.592866) (xy 173.079918 -239.592866) (xy 173.079918 -239.868456)
			)
		)
	)
	(zone
		(layer "In11.Cu")
		(hatch none 0.5)
		(connect_pads
			(clearance 0)
		)
		(min_thickness 0.25)
		(keepout
			(tracks allowed)
			(vias allowed)
			(pads allowed)
			(copperpour allowed)
			(footprints allowed)
		)
		(placement
			(enabled no)
			(sheetname "")
		)
		(fill
			(thermal_gap 0.5)
			(thermal_bridge_width 0.5)
			(island_removal_mode 0)
		)
		(polygon
			(pts
				(xy 420.461186 -216.91854) (xy 420.461186 -216.64295) (xy 421.019986 -216.64295) (xy 421.019986 -216.91854)
			)
		)
	)
	(zone
		(layer "In11.Cu")
		(hatch none 0.5)
		(connect_pads
			(clearance 0)
		)
		(min_thickness 0.25)
		(keepout
			(tracks allowed)
			(vias allowed)
			(pads allowed)
			(copperpour allowed)
			(footprints allowed)
		)
		(placement
			(enabled no)
			(sheetname "")
		)
		(fill
			(thermal_gap 0.5)
			(thermal_bridge_width 0.5)
			(island_removal_mode 0)
		)
		(polygon
			(pts
				(xy 177.170842 -273.764756) (xy 177.170842 -274.040346) (xy 176.612042 -274.040346) (xy 176.612042 -273.764756)
			)
		)
	)
	(zone
		(layer "In11.Cu")
		(hatch none 0.5)
		(connect_pads
			(clearance 0)
		)
		(min_thickness 0.25)
		(keepout
			(tracks allowed)
			(vias allowed)
			(pads allowed)
			(copperpour allowed)
			(footprints allowed)
		)
		(placement
			(enabled no)
			(sheetname "")
		)
		(fill
			(thermal_gap 0.5)
			(thermal_bridge_width 0.5)
			(island_removal_mode 0)
		)
		(polygon
			(pts
				(xy 46.646084 -230.746808) (xy 46.646084 -230.197152) (xy 47.276004 -230.197152) (xy 47.276004 -230.746808)
			)
		)
	)
	(zone
		(layer "In11.Cu")
		(hatch none 0.5)
		(connect_pads
			(clearance 0)
		)
		(min_thickness 0.25)
		(keepout
			(tracks allowed)
			(vias allowed)
			(pads allowed)
			(copperpour allowed)
			(footprints allowed)
		)
		(placement
			(enabled no)
			(sheetname "")
		)
		(fill
			(thermal_gap 0.5)
			(thermal_bridge_width 0.5)
			(island_removal_mode 0)
		)
		(polygon
			(pts
				(xy 172.521118 -280.668476) (xy 172.521118 -280.392886) (xy 173.079918 -280.392886) (xy 173.079918 -280.668476)
			)
		)
	)
	(zone
		(layer "In11.Cu")
		(hatch none 0.5)
		(connect_pads
			(clearance 0)
		)
		(min_thickness 0.25)
		(keepout
			(tracks allowed)
			(vias allowed)
			(pads allowed)
			(copperpour allowed)
			(footprints allowed)
		)
		(placement
			(enabled no)
			(sheetname "")
		)
		(fill
			(thermal_gap 0.5)
			(thermal_bridge_width 0.5)
			(island_removal_mode 0)
		)
		(polygon
			(pts
				(xy 202.696318 -252.618494) (xy 202.696318 -252.342904) (xy 203.255118 -252.342904) (xy 203.255118 -252.618494)
			)
		)
	)
	(zone
		(layer "In11.Cu")
		(hatch none 0.5)
		(connect_pads
			(clearance 0)
		)
		(min_thickness 0.25)
		(keepout
			(tracks allowed)
			(vias allowed)
			(pads allowed)
			(copperpour allowed)
			(footprints allowed)
		)
		(placement
			(enabled no)
			(sheetname "")
		)
		(fill
			(thermal_gap 0.5)
			(thermal_bridge_width 0.5)
			(island_removal_mode 0)
		)
		(polygon
			(pts
				(xy 424.561254 -267.918438) (xy 424.561254 -267.642848) (xy 425.120054 -267.642848) (xy 425.120054 -267.918438)
			)
		)
	)
	(zone
		(layer "In11.Cu")
		(hatch none 0.5)
		(connect_pads
			(clearance 0)
		)
		(min_thickness 0.25)
		(keepout
			(tracks allowed)
			(vias allowed)
			(pads allowed)
			(copperpour allowed)
			(footprints allowed)
		)
		(placement
			(enabled no)
			(sheetname "")
		)
		(fill
			(thermal_gap 0.5)
			(thermal_bridge_width 0.5)
			(island_removal_mode 0)
		)
		(polygon
			(pts
				(xy 176.621186 -267.918438) (xy 176.621186 -267.642848) (xy 177.179986 -267.642848) (xy 177.179986 -267.918438)
			)
		)
	)
	(zone
		(layer "In11.Cu")
		(hatch none 0.5)
		(connect_pads
			(clearance 0)
		)
		(min_thickness 0.25)
		(keepout
			(tracks allowed)
			(vias allowed)
			(pads allowed)
			(copperpour allowed)
			(footprints allowed)
		)
		(placement
			(enabled no)
			(sheetname "")
		)
		(fill
			(thermal_gap 0.5)
			(thermal_bridge_width 0.5)
			(island_removal_mode 0)
		)
		(polygon
			(pts
				(xy 420.934642 -263.564624) (xy 420.934642 -263.840214) (xy 420.375842 -263.840214) (xy 420.375842 -263.564624)
			)
		)
	)
	(zone
		(layer "In11.Cu")
		(hatch none 0.5)
		(connect_pads
			(clearance 0)
		)
		(min_thickness 0.25)
		(keepout
			(tracks allowed)
			(vias allowed)
			(pads allowed)
			(copperpour allowed)
			(footprints allowed)
		)
		(placement
			(enabled no)
			(sheetname "")
		)
		(fill
			(thermal_gap 0.5)
			(thermal_bridge_width 0.5)
			(island_removal_mode 0)
		)
		(polygon
			(pts
				(xy 157.983174 -224.464626) (xy 157.983174 -224.740216) (xy 157.424374 -224.740216) (xy 157.424374 -224.464626)
			)
		)
	)
	(zone
		(layer "In11.Cu")
		(hatch none 0.5)
		(connect_pads
			(clearance 0)
		)
		(min_thickness 0.25)
		(keepout
			(tracks allowed)
			(vias allowed)
			(pads allowed)
			(copperpour allowed)
			(footprints allowed)
		)
		(placement
			(enabled no)
			(sheetname "")
		)
		(fill
			(thermal_gap 0.5)
			(thermal_bridge_width 0.5)
			(island_removal_mode 0)
		)
		(polygon
			(pts
				(xy 268.56436 -293.65067) (xy 268.56436 -293.100252) (xy 269.12316 -293.100252) (xy 269.12316 -293.65067)
			)
		)
	)
	(zone
		(layer "In11.Cu")
		(hatch none 0.5)
		(connect_pads
			(clearance 0)
		)
		(min_thickness 0.25)
		(keepout
			(tracks allowed)
			(vias allowed)
			(pads allowed)
			(copperpour allowed)
			(footprints allowed)
		)
		(placement
			(enabled no)
			(sheetname "")
		)
		(fill
			(thermal_gap 0.5)
			(thermal_bridge_width 0.5)
			(island_removal_mode 0)
		)
		(polygon
			(pts
				(xy 420.461186 -289.168586) (xy 420.461186 -288.892996) (xy 421.019986 -288.892996) (xy 421.019986 -289.168586)
			)
		)
	)
	(zone
		(layer "In11.Cu")
		(hatch none 0.5)
		(connect_pads
			(clearance 0)
		)
		(min_thickness 0.25)
		(keepout
			(tracks allowed)
			(vias allowed)
			(pads allowed)
			(copperpour allowed)
			(footprints allowed)
		)
		(placement
			(enabled no)
			(sheetname "")
		)
		(fill
			(thermal_gap 0.5)
			(thermal_bridge_width 0.5)
			(island_removal_mode 0)
		)
		(polygon
			(pts
				(xy 268.558518 -231.592374) (xy 268.558518 -231.052116) (xy 269.126462 -231.052116) (xy 269.426944 -231.052116)
				(xy 269.531084 -231.156256) (xy 269.531084 -231.421686) (xy 269.360396 -231.592374) (xy 269.117318 -231.592374)
			)
		)
	)
	(zone
		(layer "In11.Cu")
		(hatch none 0.5)
		(connect_pads
			(clearance 0)
		)
		(min_thickness 0.25)
		(keepout
			(tracks allowed)
			(vias allowed)
			(pads allowed)
			(copperpour allowed)
			(footprints allowed)
		)
		(placement
			(enabled no)
			(sheetname "")
		)
		(fill
			(thermal_gap 0.5)
			(thermal_bridge_width 0.5)
			(island_removal_mode 0)
		)
		(polygon
			(pts
				(xy 294.586152 -228.196902) (xy 294.586152 -227.647246) (xy 295.216072 -227.647246) (xy 295.216072 -228.196902)
			)
		)
	)
	(zone
		(layer "In11.Cu")
		(hatch none 0.5)
		(connect_pads
			(clearance 0)
		)
		(min_thickness 0.25)
		(keepout
			(tracks allowed)
			(vias allowed)
			(pads allowed)
			(copperpour allowed)
			(footprints allowed)
		)
		(placement
			(enabled no)
			(sheetname "")
		)
		(fill
			(thermal_gap 0.5)
			(thermal_bridge_width 0.5)
			(island_removal_mode 0)
		)
		(polygon
			(pts
				(xy 424.561254 -305.318414) (xy 424.561254 -305.042824) (xy 425.120054 -305.042824) (xy 425.120054 -305.318414)
			)
		)
	)
	(zone
		(layer "In11.Cu")
		(hatch none 0.5)
		(connect_pads
			(clearance 0)
		)
		(min_thickness 0.25)
		(keepout
			(tracks allowed)
			(vias allowed)
			(pads allowed)
			(copperpour allowed)
			(footprints allowed)
		)
		(placement
			(enabled no)
			(sheetname "")
		)
		(fill
			(thermal_gap 0.5)
			(thermal_bridge_width 0.5)
			(island_removal_mode 0)
		)
		(polygon
			(pts
				(xy 298.71162 -263.896856) (xy 298.71162 -263.3472) (xy 299.34154 -263.3472) (xy 299.34154 -263.896856)
			)
		)
	)
	(zone
		(layer "In11.Cu")
		(hatch none 0.5)
		(connect_pads
			(clearance 0)
		)
		(min_thickness 0.25)
		(keepout
			(tracks allowed)
			(vias allowed)
			(pads allowed)
			(copperpour allowed)
			(footprints allowed)
		)
		(placement
			(enabled no)
			(sheetname "")
		)
		(fill
			(thermal_gap 0.5)
			(thermal_bridge_width 0.5)
			(island_removal_mode 0)
		)
		(polygon
			(pts
				(xy 425.11091 -245.714774) (xy 425.11091 -245.990364) (xy 424.55211 -245.990364) (xy 424.55211 -245.714774)
			)
		)
	)
	(zone
		(layer "In11.Cu")
		(hatch none 0.5)
		(connect_pads
			(clearance 0)
		)
		(min_thickness 0.25)
		(keepout
			(tracks allowed)
			(vias allowed)
			(pads allowed)
			(copperpour allowed)
			(footprints allowed)
		)
		(placement
			(enabled no)
			(sheetname "")
		)
		(fill
			(thermal_gap 0.5)
			(thermal_bridge_width 0.5)
			(island_removal_mode 0)
		)
		(polygon
			(pts
				(xy 425.11091 -273.764756) (xy 425.11091 -274.040346) (xy 424.55211 -274.040346) (xy 424.55211 -273.764756)
			)
		)
	)
	(zone
		(layer "In11.Cu")
		(hatch none 0.5)
		(connect_pads
			(clearance 0)
		)
		(min_thickness 0.25)
		(keepout
			(tracks allowed)
			(vias allowed)
			(pads allowed)
			(copperpour allowed)
			(footprints allowed)
		)
		(placement
			(enabled no)
			(sheetname "")
		)
		(fill
			(thermal_gap 0.5)
			(thermal_bridge_width 0.5)
			(island_removal_mode 0)
		)
		(polygon
			(pts
				(xy 187.608718 -261.968488) (xy 187.608718 -261.692898) (xy 188.167518 -261.692898) (xy 188.167518 -261.968488)
			)
		)
	)
	(zone
		(layer "In11.Cu")
		(hatch none 0.5)
		(connect_pads
			(clearance 0)
		)
		(min_thickness 0.25)
		(keepout
			(tracks allowed)
			(vias allowed)
			(pads allowed)
			(copperpour allowed)
			(footprints allowed)
		)
		(placement
			(enabled no)
			(sheetname "")
		)
		(fill
			(thermal_gap 0.5)
			(thermal_bridge_width 0.5)
			(island_removal_mode 0)
		)
		(polygon
			(pts
				(xy 172.521118 -300.218602) (xy 172.521118 -299.943012) (xy 173.079918 -299.943012) (xy 173.079918 -300.218602)
			)
		)
	)
	(zone
		(layer "In11.Cu")
		(hatch none 0.5)
		(connect_pads
			(clearance 0)
		)
		(min_thickness 0.25)
		(keepout
			(tracks allowed)
			(vias allowed)
			(pads allowed)
			(copperpour allowed)
			(footprints allowed)
		)
		(placement
			(enabled no)
			(sheetname "")
		)
		(fill
			(thermal_gap 0.5)
			(thermal_bridge_width 0.5)
			(island_removal_mode 0)
		)
		(polygon
			(pts
				(xy 294.586152 -209.496914) (xy 294.586152 -208.947258) (xy 295.216072 -208.947258) (xy 295.216072 -209.496914)
			)
		)
	)
	(zone
		(layer "In11.Cu")
		(hatch none 0.5)
		(connect_pads
			(clearance 0)
		)
		(min_thickness 0.25)
		(keepout
			(tracks allowed)
			(vias allowed)
			(pads allowed)
			(copperpour allowed)
			(footprints allowed)
		)
		(placement
			(enabled no)
			(sheetname "")
		)
		(fill
			(thermal_gap 0.5)
			(thermal_bridge_width 0.5)
			(island_removal_mode 0)
		)
		(polygon
			(pts
				(xy 294.586152 -274.946872) (xy 294.586152 -274.397216) (xy 295.216072 -274.397216) (xy 295.216072 -274.946872)
			)
		)
	)
	(zone
		(layer "In11.Cu")
		(hatch none 0.5)
		(connect_pads
			(clearance 0)
		)
		(min_thickness 0.25)
		(keepout
			(tracks not_allowed)
			(vias allowed)
			(pads allowed)
			(copperpour not_allowed)
			(footprints allowed)
		)
		(placement
			(enabled no)
			(sheetname "")
		)
		(fill
			(thermal_gap 0.5)
			(thermal_bridge_width 0.5)
			(island_removal_mode 0)
		)
		(polygon
			(pts
				(arc
					(start 320.142108 -428.960788)
					(mid 320.164426 -429.01467)
					(end 320.218308 -429.036988)
				)
				(arc
					(start 321.158108 -429.036988)
					(mid 321.21199 -429.01467)
					(end 321.234308 -428.960788)
				)
				(arc
					(start 321.234308 -426.419264)
					(mid 321.21199 -426.365382)
					(end 321.158108 -426.343064)
				)
				(arc
					(start 320.218308 -426.343064)
					(mid 320.164426 -426.365382)
					(end 320.142108 -426.419264)
				)
			)
		)
	)
	(zone
		(layer "In11.Cu")
		(hatch none 0.5)
		(connect_pads
			(clearance 0)
		)
		(min_thickness 0.25)
		(keepout
			(tracks allowed)
			(vias allowed)
			(pads allowed)
			(copperpour allowed)
			(footprints allowed)
		)
		(placement
			(enabled no)
			(sheetname "")
		)
		(fill
			(thermal_gap 0.5)
			(thermal_bridge_width 0.5)
			(island_removal_mode 0)
		)
		(polygon
			(pts
				(xy 424.561254 -295.118536) (xy 424.561254 -294.842946) (xy 425.120054 -294.842946) (xy 425.120054 -295.118536)
			)
		)
	)
	(zone
		(layer "In11.Cu")
		(hatch none 0.5)
		(connect_pads
			(clearance 0)
		)
		(min_thickness 0.25)
		(keepout
			(tracks allowed)
			(vias allowed)
			(pads allowed)
			(copperpour allowed)
			(footprints allowed)
		)
		(placement
			(enabled no)
			(sheetname "")
		)
		(fill
			(thermal_gap 0.5)
			(thermal_bridge_width 0.5)
			(island_removal_mode 0)
		)
		(polygon
			(pts
				(xy 298.71162 -283.446982) (xy 298.71162 -282.897326) (xy 299.34154 -282.897326) (xy 299.34154 -283.446982)
			)
		)
	)
	(zone
		(layer "In11.Cu")
		(hatch none 0.5)
		(connect_pads
			(clearance 0)
		)
		(min_thickness 0.25)
		(keepout
			(tracks allowed)
			(vias allowed)
			(pads allowed)
			(copperpour allowed)
			(footprints allowed)
		)
		(placement
			(enabled no)
			(sheetname "")
		)
		(fill
			(thermal_gap 0.5)
			(thermal_bridge_width 0.5)
			(island_removal_mode 0)
		)
		(polygon
			(pts
				(xy 356.14102 -338.333588) (xy 356.14102 -335.257648) (xy 369.84178 -335.257648) (xy 369.84178 -338.333588)
			)
		)
	)
	(zone
		(layer "In11.Cu")
		(hatch none 0.5)
		(connect_pads
			(clearance 0)
		)
		(min_thickness 0.25)
		(keepout
			(tracks allowed)
			(vias allowed)
			(pads allowed)
			(copperpour allowed)
			(footprints allowed)
		)
		(placement
			(enabled no)
			(sheetname "")
		)
		(fill
			(thermal_gap 0.5)
			(thermal_bridge_width 0.5)
			(island_removal_mode 0)
		)
		(polygon
			(pts
				(xy 436.098442 -277.1648) (xy 436.098442 -277.44039) (xy 435.539642 -277.44039) (xy 435.539642 -277.1648)
			)
		)
	)
	(zone
		(layer "In11.Cu")
		(hatch none 0.5)
		(connect_pads
			(clearance 0)
		)
		(min_thickness 0.25)
		(keepout
			(tracks allowed)
			(vias allowed)
			(pads allowed)
			(copperpour allowed)
			(footprints allowed)
		)
		(placement
			(enabled no)
			(sheetname "")
		)
		(fill
			(thermal_gap 0.5)
			(thermal_bridge_width 0.5)
			(island_removal_mode 0)
		)
		(polygon
			(pts
				(xy 298.68622 -250.296934) (xy 298.68622 -249.747278) (xy 299.31614 -249.747278) (xy 299.31614 -250.296934)
			)
		)
	)
	(zone
		(layer "In11.Cu")
		(hatch none 0.5)
		(connect_pads
			(clearance 0)
		)
		(min_thickness 0.25)
		(keepout
			(tracks allowed)
			(vias allowed)
			(pads allowed)
			(copperpour allowed)
			(footprints allowed)
		)
		(placement
			(enabled no)
			(sheetname "")
		)
		(fill
			(thermal_gap 0.5)
			(thermal_bridge_width 0.5)
			(island_removal_mode 0)
		)
		(polygon
			(pts
				(xy 421.010842 -221.064836) (xy 421.010842 -221.340426) (xy 420.452042 -221.340426) (xy 420.452042 -221.064836)
			)
		)
	)
	(zone
		(layer "In11.Cu")
		(hatch none 0.5)
		(connect_pads
			(clearance 0)
		)
		(min_thickness 0.25)
		(keepout
			(tracks allowed)
			(vias allowed)
			(pads allowed)
			(copperpour allowed)
			(footprints allowed)
		)
		(placement
			(enabled no)
			(sheetname "")
		)
		(fill
			(thermal_gap 0.5)
			(thermal_bridge_width 0.5)
			(island_removal_mode 0)
		)
		(polygon
			(pts
				(xy 425.11091 -283.964634) (xy 425.11091 -284.240224) (xy 424.55211 -284.240224) (xy 424.55211 -283.964634)
			)
		)
	)
	(zone
		(layer "In11.Cu")
		(hatch none 0.5)
		(connect_pads
			(clearance 0)
		)
		(min_thickness 0.25)
		(keepout
			(tracks allowed)
			(vias allowed)
			(pads allowed)
			(copperpour allowed)
			(footprints allowed)
		)
		(placement
			(enabled no)
			(sheetname "")
		)
		(fill
			(thermal_gap 0.5)
			(thermal_bridge_width 0.5)
			(island_removal_mode 0)
		)
		(polygon
			(pts
				(xy 46.646084 -200.996804) (xy 46.646084 -200.447148) (xy 47.276004 -200.447148) (xy 47.276004 -200.996804)
			)
		)
	)
	(zone
		(layer "In11.Cu")
		(hatch none 0.5)
		(connect_pads
			(clearance 0)
		)
		(min_thickness 0.25)
		(keepout
			(tracks allowed)
			(vias allowed)
			(pads allowed)
			(copperpour allowed)
			(footprints allowed)
		)
		(placement
			(enabled no)
			(sheetname "")
		)
		(fill
			(thermal_gap 0.5)
			(thermal_bridge_width 0.5)
			(island_removal_mode 0)
		)
		(polygon
			(pts
				(xy 268.56436 -304.700686) (xy 268.56436 -304.150268) (xy 269.12316 -304.150268) (xy 269.12316 -304.700686)
			)
		)
	)
	(zone
		(layer "In11.Cu")
		(hatch none 0.5)
		(connect_pads
			(clearance 0)
		)
		(min_thickness 0.25)
		(keepout
			(tracks allowed)
			(vias allowed)
			(pads allowed)
			(copperpour allowed)
			(footprints allowed)
		)
		(placement
			(enabled no)
			(sheetname "")
		)
		(fill
			(thermal_gap 0.5)
			(thermal_bridge_width 0.5)
			(island_removal_mode 0)
		)
		(polygon
			(pts
				(xy 188.158374 -280.564844) (xy 188.158374 -280.840434) (xy 187.599574 -280.840434) (xy 187.599574 -280.564844)
			)
		)
	)
	(zone
		(layer "In11.Cu")
		(hatch none 0.5)
		(connect_pads
			(clearance 0)
		)
		(min_thickness 0.25)
		(keepout
			(tracks allowed)
			(vias allowed)
			(pads allowed)
			(copperpour allowed)
			(footprints allowed)
		)
		(placement
			(enabled no)
			(sheetname "")
		)
		(fill
			(thermal_gap 0.5)
			(thermal_bridge_width 0.5)
			(island_removal_mode 0)
		)
		(polygon
			(pts
				(xy 20.624292 -302.15078) (xy 20.624292 -301.600362) (xy 21.183092 -301.600362) (xy 21.183092 -302.15078)
			)
		)
	)
	(zone
		(layer "In11.Cu")
		(hatch none 0.5)
		(connect_pads
			(clearance 0)
		)
		(min_thickness 0.25)
		(keepout
			(tracks allowed)
			(vias allowed)
			(pads allowed)
			(copperpour allowed)
			(footprints allowed)
		)
		(placement
			(enabled no)
			(sheetname "")
		)
		(fill
			(thermal_gap 0.5)
			(thermal_bridge_width 0.5)
			(island_removal_mode 0)
		)
		(polygon
			(pts
				(xy 176.621186 -295.118536) (xy 176.621186 -294.842946) (xy 177.179986 -294.842946) (xy 177.179986 -295.118536)
			)
		)
	)
	(zone
		(layer "In11.Cu")
		(hatch none 0.5)
		(connect_pads
			(clearance 0)
		)
		(min_thickness 0.25)
		(keepout
			(tracks allowed)
			(vias allowed)
			(pads allowed)
			(copperpour allowed)
			(footprints allowed)
		)
		(placement
			(enabled no)
			(sheetname "")
		)
		(fill
			(thermal_gap 0.5)
			(thermal_bridge_width 0.5)
			(island_removal_mode 0)
		)
		(polygon
			(pts
				(xy 294.586152 -219.696792) (xy 294.586152 -219.147136) (xy 295.216072 -219.147136) (xy 295.216072 -219.696792)
			)
		)
	)
	(zone
		(layer "In11.Cu")
		(hatch none 0.5)
		(connect_pads
			(clearance 0)
		)
		(min_thickness 0.25)
		(keepout
			(tracks allowed)
			(vias allowed)
			(pads allowed)
			(copperpour allowed)
			(footprints allowed)
		)
		(placement
			(enabled no)
			(sheetname "")
		)
		(fill
			(thermal_gap 0.5)
			(thermal_bridge_width 0.5)
			(island_removal_mode 0)
		)
		(polygon
			(pts
				(xy 450.636386 -221.168468) (xy 450.636386 -220.892878) (xy 451.195186 -220.892878) (xy 451.195186 -221.168468)
			)
		)
	)
	(zone
		(layer "In11.Cu")
		(hatch none 0.5)
		(connect_pads
			(clearance 0)
		)
		(min_thickness 0.25)
		(keepout
			(tracks allowed)
			(vias allowed)
			(pads allowed)
			(copperpour allowed)
			(footprints allowed)
		)
		(placement
			(enabled no)
			(sheetname "")
		)
		(fill
			(thermal_gap 0.5)
			(thermal_bridge_width 0.5)
			(island_removal_mode 0)
		)
		(polygon
			(pts
				(xy 50.746152 -199.296782) (xy 50.746152 -198.747126) (xy 51.376072 -198.747126) (xy 51.376072 -199.296782)
			)
		)
	)
	(zone
		(layer "In11.Cu")
		(hatch none 0.5)
		(connect_pads
			(clearance 0)
		)
		(min_thickness 0.25)
		(keepout
			(tracks allowed)
			(vias allowed)
			(pads allowed)
			(copperpour allowed)
			(footprints allowed)
		)
		(placement
			(enabled no)
			(sheetname "")
		)
		(fill
			(thermal_gap 0.5)
			(thermal_bridge_width 0.5)
			(island_removal_mode 0)
		)
		(polygon
			(pts
				(xy 84.87664 -341.823548) (xy 84.87664 -338.856828) (xy 89.1921 -338.856828) (xy 89.1921 -341.823548)
			)
		)
	)
	(zone
		(layer "In11.Cu")
		(hatch none 0.5)
		(connect_pads
			(clearance 0)
		)
		(min_thickness 0.25)
		(keepout
			(tracks not_allowed)
			(vias allowed)
			(pads allowed)
			(copperpour not_allowed)
			(footprints allowed)
		)
		(placement
			(enabled no)
			(sheetname "")
		)
		(fill
			(thermal_gap 0.5)
			(thermal_bridge_width 0.5)
			(island_removal_mode 0)
		)
		(polygon
			(pts
				(arc
					(start 387.24205 -428.960788)
					(mid 387.264368 -429.01467)
					(end 387.31825 -429.036988)
				)
				(arc
					(start 388.25805 -429.036988)
					(mid 388.311932 -429.01467)
					(end 388.33425 -428.960788)
				)
				(arc
					(start 388.33425 -426.419264)
					(mid 388.311932 -426.365382)
					(end 388.25805 -426.343064)
				)
				(arc
					(start 387.31825 -426.343064)
					(mid 387.264368 -426.365382)
					(end 387.24205 -426.419264)
				)
			)
		)
	)
	(zone
		(layer "In11.Cu")
		(hatch none 0.5)
		(connect_pads
			(clearance 0)
		)
		(min_thickness 0.25)
		(keepout
			(tracks allowed)
			(vias allowed)
			(pads allowed)
			(copperpour allowed)
			(footprints allowed)
		)
		(placement
			(enabled no)
			(sheetname "")
		)
		(fill
			(thermal_gap 0.5)
			(thermal_bridge_width 0.5)
			(island_removal_mode 0)
		)
		(polygon
			(pts
				(xy 172.521118 -210.118452) (xy 172.521118 -209.842862) (xy 173.079918 -209.842862) (xy 173.079918 -210.118452)
			)
		)
	)
	(zone
		(layer "In11.Cu")
		(hatch none 0.5)
		(connect_pads
			(clearance 0)
		)
		(min_thickness 0.25)
		(keepout
			(tracks allowed)
			(vias allowed)
			(pads allowed)
			(copperpour allowed)
			(footprints allowed)
		)
		(placement
			(enabled no)
			(sheetname "")
		)
		(fill
			(thermal_gap 0.5)
			(thermal_bridge_width 0.5)
			(island_removal_mode 0)
		)
		(polygon
			(pts
				(xy 46.646084 -279.1968) (xy 46.646084 -278.647144) (xy 47.276004 -278.647144) (xy 47.276004 -279.1968)
			)
		)
	)
	(zone
		(layer "In11.Cu")
		(hatch none 0.5)
		(connect_pads
			(clearance 0)
		)
		(min_thickness 0.25)
		(keepout
			(tracks allowed)
			(vias allowed)
			(pads allowed)
			(copperpour allowed)
			(footprints allowed)
		)
		(placement
			(enabled no)
			(sheetname "")
		)
		(fill
			(thermal_gap 0.5)
			(thermal_bridge_width 0.5)
			(island_removal_mode 0)
		)
		(polygon
			(pts
				(xy 439.648854 -308.718458) (xy 439.648854 -308.442868) (xy 440.207654 -308.442868) (xy 440.207654 -308.718458)
			)
		)
	)
	(zone
		(layer "In11.Cu")
		(hatch none 0.5)
		(connect_pads
			(clearance 0)
		)
		(min_thickness 0.25)
		(keepout
			(tracks allowed)
			(vias allowed)
			(pads allowed)
			(copperpour allowed)
			(footprints allowed)
		)
		(placement
			(enabled no)
			(sheetname "")
		)
		(fill
			(thermal_gap 0.5)
			(thermal_bridge_width 0.5)
			(island_removal_mode 0)
		)
		(polygon
			(pts
				(xy 50.771552 -304.696876) (xy 50.771552 -304.14722) (xy 51.401472 -304.14722) (xy 51.401472 -304.696876)
			)
		)
	)
	(zone
		(layer "In11.Cu")
		(hatch none 0.5)
		(connect_pads
			(clearance 0)
		)
		(min_thickness 0.25)
		(keepout
			(tracks allowed)
			(vias allowed)
			(pads allowed)
			(copperpour allowed)
			(footprints allowed)
		)
		(placement
			(enabled no)
			(sheetname "")
		)
		(fill
			(thermal_gap 0.5)
			(thermal_bridge_width 0.5)
			(island_removal_mode 0)
		)
		(polygon
			(pts
				(xy 298.68622 -214.596726) (xy 298.68622 -214.04707) (xy 299.31614 -214.04707) (xy 299.31614 -214.596726)
			)
		)
	)
	(zone
		(layer "In11.Cu")
		(hatch none 0.5)
		(connect_pads
			(clearance 0)
		)
		(min_thickness 0.25)
		(keepout
			(tracks allowed)
			(vias allowed)
			(pads allowed)
			(copperpour allowed)
			(footprints allowed)
		)
		(placement
			(enabled no)
			(sheetname "")
		)
		(fill
			(thermal_gap 0.5)
			(thermal_bridge_width 0.5)
			(island_removal_mode 0)
		)
		(polygon
			(pts
				(xy 420.461186 -287.468564) (xy 420.461186 -287.192974) (xy 421.019986 -287.192974) (xy 421.019986 -287.468564)
			)
		)
	)
	(zone
		(layer "In11.Cu")
		(hatch none 0.5)
		(connect_pads
			(clearance 0)
		)
		(min_thickness 0.25)
		(keepout
			(tracks allowed)
			(vias allowed)
			(pads allowed)
			(copperpour allowed)
			(footprints allowed)
		)
		(placement
			(enabled no)
			(sheetname "")
		)
		(fill
			(thermal_gap 0.5)
			(thermal_bridge_width 0.5)
			(island_removal_mode 0)
		)
		(polygon
			(pts
				(xy 294.586152 -198.446898) (xy 294.586152 -197.897242) (xy 295.216072 -197.897242) (xy 295.216072 -198.446898)
			)
		)
	)
	(zone
		(layer "In11.Cu")
		(hatch none 0.5)
		(connect_pads
			(clearance 0)
		)
		(min_thickness 0.25)
		(keepout
			(tracks allowed)
			(vias allowed)
			(pads allowed)
			(copperpour allowed)
			(footprints allowed)
		)
		(placement
			(enabled no)
			(sheetname "")
		)
		(fill
			(thermal_gap 0.5)
			(thermal_bridge_width 0.5)
			(island_removal_mode 0)
		)
		(polygon
			(pts
				(xy 177.170842 -312.864754) (xy 177.170842 -313.140344) (xy 176.612042 -313.140344) (xy 176.612042 -312.864754)
			)
		)
	)
	(zone
		(layer "In11.Cu")
		(hatch none 0.5)
		(connect_pads
			(clearance 0)
		)
		(min_thickness 0.25)
		(keepout
			(tracks allowed)
			(vias allowed)
			(pads allowed)
			(copperpour allowed)
			(footprints allowed)
		)
		(placement
			(enabled no)
			(sheetname "")
		)
		(fill
			(thermal_gap 0.5)
			(thermal_bridge_width 0.5)
			(island_removal_mode 0)
		)
		(polygon
			(pts
				(xy 450.636386 -240.718594) (xy 450.636386 -240.443004) (xy 451.195186 -240.443004) (xy 451.195186 -240.718594)
			)
		)
	)
	(zone
		(layer "In11.Cu")
		(hatch none 0.5)
		(connect_pads
			(clearance 0)
		)
		(min_thickness 0.25)
		(keepout
			(tracks allowed)
			(vias allowed)
			(pads allowed)
			(copperpour allowed)
			(footprints allowed)
		)
		(placement
			(enabled no)
			(sheetname "")
		)
		(fill
			(thermal_gap 0.5)
			(thermal_bridge_width 0.5)
			(island_removal_mode 0)
		)
		(polygon
			(pts
				(xy 425.11091 -218.514676) (xy 425.11091 -218.790266) (xy 424.55211 -218.790266) (xy 424.55211 -218.514676)
			)
		)
	)
	(zone
		(layer "In11.Cu")
		(hatch none 0.5)
		(connect_pads
			(clearance 0)
		)
		(min_thickness 0.25)
		(keepout
			(tracks allowed)
			(vias allowed)
			(pads allowed)
			(copperpour allowed)
			(footprints allowed)
		)
		(placement
			(enabled no)
			(sheetname "")
		)
		(fill
			(thermal_gap 0.5)
			(thermal_bridge_width 0.5)
			(island_removal_mode 0)
		)
		(polygon
			(pts
				(xy 424.561254 -222.018606) (xy 424.561254 -221.743016) (xy 425.120054 -221.743016) (xy 425.120054 -222.018606)
			)
		)
	)
	(zone
		(layer "In11.Cu")
		(hatch none 0.5)
		(connect_pads
			(clearance 0)
		)
		(min_thickness 0.25)
		(keepout
			(tracks allowed)
			(vias allowed)
			(pads allowed)
			(copperpour allowed)
			(footprints allowed)
		)
		(placement
			(enabled no)
			(sheetname "")
		)
		(fill
			(thermal_gap 0.5)
			(thermal_bridge_width 0.5)
			(island_removal_mode 0)
		)
		(polygon
			(pts
				(xy 424.561254 -279.818592) (xy 424.561254 -279.543002) (xy 425.120054 -279.543002) (xy 425.120054 -279.818592)
			)
		)
	)
	(zone
		(layer "In11.Cu")
		(hatch none 0.5)
		(connect_pads
			(clearance 0)
		)
		(min_thickness 0.25)
		(keepout
			(tracks allowed)
			(vias allowed)
			(pads allowed)
			(copperpour allowed)
			(footprints allowed)
		)
		(placement
			(enabled no)
			(sheetname "")
		)
		(fill
			(thermal_gap 0.5)
			(thermal_bridge_width 0.5)
			(island_removal_mode 0)
		)
		(polygon
			(pts
				(xy 177.170842 -261.864856) (xy 177.170842 -262.140446) (xy 176.612042 -262.140446) (xy 176.612042 -261.864856)
			)
		)
	)
	(zone
		(layer "In11.Cu")
		(hatch none 0.5)
		(connect_pads
			(clearance 0)
		)
		(min_thickness 0.25)
		(keepout
			(tracks allowed)
			(vias allowed)
			(pads allowed)
			(copperpour allowed)
			(footprints allowed)
		)
		(placement
			(enabled no)
			(sheetname "")
		)
		(fill
			(thermal_gap 0.5)
			(thermal_bridge_width 0.5)
			(island_removal_mode 0)
		)
		(polygon
			(pts
				(xy 420.461186 -316.36843) (xy 420.461186 -316.09284) (xy 421.019986 -316.09284) (xy 421.019986 -316.36843)
			)
		)
	)
	(zone
		(layer "In11.Cu")
		(hatch none 0.5)
		(connect_pads
			(clearance 0)
		)
		(min_thickness 0.25)
		(keepout
			(tracks allowed)
			(vias allowed)
			(pads allowed)
			(copperpour allowed)
			(footprints allowed)
		)
		(placement
			(enabled no)
			(sheetname "")
		)
		(fill
			(thermal_gap 0.5)
			(thermal_bridge_width 0.5)
			(island_removal_mode 0)
		)
		(polygon
			(pts
				(xy 388.00532 -259.01269) (xy 388.454646 -259.01269) (xy 389.836406 -260.39445) (xy 394.984986 -260.39445)
				(xy 395.376146 -260.78561) (xy 395.858746 -261.26821) (xy 395.858746 -261.55269) (xy 395.256766 -262.15467)
				(xy 394.438886 -262.15467) (xy 389.066786 -262.15467) (xy 388.416546 -262.15467) (xy 387.956806 -261.69493)
				(xy 387.956806 -261.505954) (xy 388.116064 -261.346696) (xy 388.144004 -261.346696) (xy 388.155434 -261.335266)
				(xy 388.155434 -261.132828) (xy 387.9596 -260.936994) (xy 387.956806 -260.936994) (xy 387.956806 -260.719316)
				(xy 388.079488 -260.596634) (xy 388.079488 -260.13029) (xy 388.00532 -260.056122)
			)
		)
	)
	(zone
		(layer "In11.Cu")
		(hatch none 0.5)
		(connect_pads
			(clearance 0)
		)
		(min_thickness 0.25)
		(keepout
			(tracks allowed)
			(vias allowed)
			(pads allowed)
			(copperpour allowed)
			(footprints allowed)
		)
		(placement
			(enabled no)
			(sheetname "")
		)
		(fill
			(thermal_gap 0.5)
			(thermal_bridge_width 0.5)
			(island_removal_mode 0)
		)
		(polygon
			(pts
				(xy 268.51102 -234.996736) (xy 268.51102 -234.44708) (xy 269.14094 -234.44708) (xy 269.14094 -234.996736)
			)
		)
	)
	(zone
		(layer "In11.Cu")
		(hatch none 0.5)
		(connect_pads
			(clearance 0)
		)
		(min_thickness 0.25)
		(keepout
			(tracks not_allowed)
			(vias allowed)
			(pads allowed)
			(copperpour not_allowed)
			(footprints allowed)
		)
		(placement
			(enabled no)
			(sheetname "")
		)
		(fill
			(thermal_gap 0.5)
			(thermal_bridge_width 0.5)
			(island_removal_mode 0)
		)
		(polygon
			(pts
				(arc
					(start 131.242054 -428.960788)
					(mid 131.264372 -429.01467)
					(end 131.318254 -429.036988)
				)
				(arc
					(start 132.258054 -429.036988)
					(mid 132.311936 -429.01467)
					(end 132.334254 -428.960788)
				)
				(arc
					(start 132.334254 -426.419264)
					(mid 132.311936 -426.365382)
					(end 132.258054 -426.343064)
				)
				(arc
					(start 131.318254 -426.343064)
					(mid 131.264372 -426.365382)
					(end 131.242054 -426.419264)
				)
			)
		)
	)
	(zone
		(layer "In11.Cu")
		(hatch none 0.5)
		(connect_pads
			(clearance 0)
		)
		(min_thickness 0.25)
		(keepout
			(tracks allowed)
			(vias allowed)
			(pads allowed)
			(copperpour allowed)
			(footprints allowed)
		)
		(placement
			(enabled no)
			(sheetname "")
		)
		(fill
			(thermal_gap 0.5)
			(thermal_bridge_width 0.5)
			(island_removal_mode 0)
		)
		(polygon
			(pts
				(xy 421.010842 -223.614742) (xy 421.010842 -223.890332) (xy 420.452042 -223.890332) (xy 420.452042 -223.614742)
			)
		)
	)
	(zone
		(layer "In11.Cu")
		(hatch none 0.5)
		(connect_pads
			(clearance 0)
		)
		(min_thickness 0.25)
		(keepout
			(tracks allowed)
			(vias allowed)
			(pads allowed)
			(copperpour allowed)
			(footprints allowed)
		)
		(placement
			(enabled no)
			(sheetname "")
		)
		(fill
			(thermal_gap 0.5)
			(thermal_bridge_width 0.5)
			(island_removal_mode 0)
		)
		(polygon
			(pts
				(xy 172.521118 -218.618562) (xy 172.521118 -218.342972) (xy 173.079918 -218.342972) (xy 173.079918 -218.618562)
			)
		)
	)
	(zone
		(layer "In11.Cu")
		(hatch none 0.5)
		(connect_pads
			(clearance 0)
		)
		(min_thickness 0.25)
		(keepout
			(tracks allowed)
			(vias allowed)
			(pads allowed)
			(copperpour allowed)
			(footprints allowed)
		)
		(placement
			(enabled no)
			(sheetname "")
		)
		(fill
			(thermal_gap 0.5)
			(thermal_bridge_width 0.5)
			(island_removal_mode 0)
		)
		(polygon
			(pts
				(xy 424.561254 -237.31855) (xy 424.561254 -237.04296) (xy 425.120054 -237.04296) (xy 425.120054 -237.31855)
			)
		)
	)
	(zone
		(layer "In11.Cu")
		(hatch none 0.5)
		(connect_pads
			(clearance 0)
		)
		(min_thickness 0.25)
		(keepout
			(tracks allowed)
			(vias allowed)
			(pads allowed)
			(copperpour allowed)
			(footprints allowed)
		)
		(placement
			(enabled no)
			(sheetname "")
		)
		(fill
			(thermal_gap 0.5)
			(thermal_bridge_width 0.5)
			(island_removal_mode 0)
		)
		(polygon
			(pts
				(xy 176.621186 -271.318482) (xy 176.621186 -271.042892) (xy 177.179986 -271.042892) (xy 177.179986 -271.318482)
			)
		)
	)
	(zone
		(layer "In11.Cu")
		(hatch none 0.5)
		(connect_pads
			(clearance 0)
		)
		(min_thickness 0.25)
		(keepout
			(tracks allowed)
			(vias allowed)
			(pads allowed)
			(copperpour allowed)
			(footprints allowed)
		)
		(placement
			(enabled no)
			(sheetname "")
		)
		(fill
			(thermal_gap 0.5)
			(thermal_bridge_width 0.5)
			(island_removal_mode 0)
		)
		(polygon
			(pts
				(xy 176.621186 -219.468446) (xy 176.621186 -219.192856) (xy 177.179986 -219.192856) (xy 177.179986 -219.468446)
			)
		)
	)
	(zone
		(layer "In11.Cu")
		(hatch none 0.5)
		(connect_pads
			(clearance 0)
		)
		(min_thickness 0.25)
		(keepout
			(tracks allowed)
			(vias allowed)
			(pads allowed)
			(copperpour allowed)
			(footprints allowed)
		)
		(placement
			(enabled no)
			(sheetname "")
		)
		(fill
			(thermal_gap 0.5)
			(thermal_bridge_width 0.5)
			(island_removal_mode 0)
		)
		(polygon
			(pts
				(xy 20.624292 -265.579352) (xy 20.624292 -265.042142) (xy 21.183092 -265.042142) (xy 21.183092 -265.579352)
			)
		)
	)
	(zone
		(layer "In11.Cu")
		(hatch none 0.5)
		(connect_pads
			(clearance 0)
		)
		(min_thickness 0.25)
		(keepout
			(tracks allowed)
			(vias allowed)
			(pads allowed)
			(copperpour allowed)
			(footprints allowed)
		)
		(placement
			(enabled no)
			(sheetname "")
		)
		(fill
			(thermal_gap 0.5)
			(thermal_bridge_width 0.5)
			(island_removal_mode 0)
		)
		(polygon
			(pts
				(xy 176.621186 -278.968454) (xy 176.621186 -278.692864) (xy 177.179986 -278.692864) (xy 177.179986 -278.968454)
			)
		)
	)
	(zone
		(layer "In11.Cu")
		(hatch none 0.5)
		(connect_pads
			(clearance 0)
		)
		(min_thickness 0.25)
		(keepout
			(tracks allowed)
			(vias allowed)
			(pads allowed)
			(copperpour allowed)
			(footprints allowed)
		)
		(placement
			(enabled no)
			(sheetname "")
		)
		(fill
			(thermal_gap 0.5)
			(thermal_bridge_width 0.5)
			(island_removal_mode 0)
		)
		(polygon
			(pts
				(xy 172.521118 -208.41843) (xy 172.521118 -208.14284) (xy 173.079918 -208.14284) (xy 173.079918 -208.41843)
			)
		)
	)
	(zone
		(layer "In11.Cu")
		(hatch none 0.5)
		(connect_pads
			(clearance 0)
		)
		(min_thickness 0.25)
		(keepout
			(tracks allowed)
			(vias allowed)
			(pads allowed)
			(copperpour allowed)
			(footprints allowed)
		)
		(placement
			(enabled no)
			(sheetname "")
		)
		(fill
			(thermal_gap 0.5)
			(thermal_bridge_width 0.5)
			(island_removal_mode 0)
		)
		(polygon
			(pts
				(xy 46.646084 -273.24685) (xy 46.646084 -272.697194) (xy 47.276004 -272.697194) (xy 47.276004 -273.24685)
			)
		)
	)
	(zone
		(layer "In11.Cu")
		(hatch none 0.5)
		(connect_pads
			(clearance 0)
		)
		(min_thickness 0.25)
		(keepout
			(tracks allowed)
			(vias allowed)
			(pads allowed)
			(copperpour allowed)
			(footprints allowed)
		)
		(placement
			(enabled no)
			(sheetname "")
		)
		(fill
			(thermal_gap 0.5)
			(thermal_bridge_width 0.5)
			(island_removal_mode 0)
		)
		(polygon
			(pts
				(xy 298.68622 -236.696758) (xy 298.68622 -236.147102) (xy 299.31614 -236.147102) (xy 299.31614 -236.696758)
			)
		)
	)
	(zone
		(layer "In11.Cu")
		(hatch none 0.5)
		(connect_pads
			(clearance 0)
		)
		(min_thickness 0.25)
		(keepout
			(tracks allowed)
			(vias allowed)
			(pads allowed)
			(copperpour allowed)
			(footprints allowed)
		)
		(placement
			(enabled no)
			(sheetname "")
		)
		(fill
			(thermal_gap 0.5)
			(thermal_bridge_width 0.5)
			(island_removal_mode 0)
		)
		(polygon
			(pts
				(xy 177.170842 -248.26468) (xy 177.170842 -248.54027) (xy 176.612042 -248.54027) (xy 176.612042 -248.26468)
			)
		)
	)
	(zone
		(layer "In11.Cu")
		(hatch none 0.5)
		(connect_pads
			(clearance 0)
		)
		(min_thickness 0.25)
		(keepout
			(tracks allowed)
			(vias allowed)
			(pads allowed)
			(copperpour allowed)
			(footprints allowed)
		)
		(placement
			(enabled no)
			(sheetname "")
		)
		(fill
			(thermal_gap 0.5)
			(thermal_bridge_width 0.5)
			(island_removal_mode 0)
		)
		(polygon
			(pts
				(xy 298.71162 -278.34717) (xy 298.71162 -277.797514) (xy 299.34154 -277.797514) (xy 299.34154 -278.34717)
			)
		)
	)
	(zone
		(layer "In11.Cu")
		(hatch none 0.5)
		(connect_pads
			(clearance 0)
		)
		(min_thickness 0.25)
		(keepout
			(tracks allowed)
			(vias allowed)
			(pads allowed)
			(copperpour allowed)
			(footprints allowed)
		)
		(placement
			(enabled no)
			(sheetname "")
		)
		(fill
			(thermal_gap 0.5)
			(thermal_bridge_width 0.5)
			(island_removal_mode 0)
		)
		(polygon
			(pts
				(xy 298.68622 -233.296968) (xy 298.68622 -232.747312) (xy 299.31614 -232.747312) (xy 299.31614 -233.296968)
			)
		)
	)
	(zone
		(layer "In11.Cu")
		(hatch none 0.5)
		(connect_pads
			(clearance 0)
		)
		(min_thickness 0.25)
		(keepout
			(tracks allowed)
			(vias allowed)
			(pads allowed)
			(copperpour allowed)
			(footprints allowed)
		)
		(placement
			(enabled no)
			(sheetname "")
		)
		(fill
			(thermal_gap 0.5)
			(thermal_bridge_width 0.5)
			(island_removal_mode 0)
		)
		(polygon
			(pts
				(xy 424.561254 -293.418514) (xy 424.561254 -293.142924) (xy 425.120054 -293.142924) (xy 425.120054 -293.418514)
			)
		)
	)
	(zone
		(layer "In11.Cu")
		(hatch none 0.5)
		(connect_pads
			(clearance 0)
		)
		(min_thickness 0.25)
		(keepout
			(tracks allowed)
			(vias allowed)
			(pads allowed)
			(copperpour allowed)
			(footprints allowed)
		)
		(placement
			(enabled no)
			(sheetname "")
		)
		(fill
			(thermal_gap 0.5)
			(thermal_bridge_width 0.5)
			(island_removal_mode 0)
		)
		(polygon
			(pts
				(xy 50.746152 -223.94672) (xy 50.746152 -223.397064) (xy 51.376072 -223.397064) (xy 51.376072 -223.94672)
			)
		)
	)
	(zone
		(layer "In11.Cu")
		(hatch none 0.5)
		(connect_pads
			(clearance 0)
		)
		(min_thickness 0.25)
		(keepout
			(tracks allowed)
			(vias allowed)
			(pads allowed)
			(copperpour allowed)
			(footprints allowed)
		)
		(placement
			(enabled no)
			(sheetname "")
		)
		(fill
			(thermal_gap 0.5)
			(thermal_bridge_width 0.5)
			(island_removal_mode 0)
		)
		(polygon
			(pts
				(xy 20.61845 -278.342344) (xy 20.61845 -277.802086) (xy 21.186394 -277.802086) (xy 21.486876 -277.802086)
				(xy 21.591016 -277.906226) (xy 21.591016 -278.171656) (xy 21.420328 -278.342344) (xy 21.17725 -278.342344)
			)
		)
	)
	(zone
		(layer "In11.Cu")
		(hatch none 0.5)
		(connect_pads
			(clearance 0)
		)
		(min_thickness 0.25)
		(keepout
			(tracks allowed)
			(vias allowed)
			(pads allowed)
			(copperpour allowed)
			(footprints allowed)
		)
		(placement
			(enabled no)
			(sheetname "")
		)
		(fill
			(thermal_gap 0.5)
			(thermal_bridge_width 0.5)
			(island_removal_mode 0)
		)
		(polygon
			(pts
				(xy 50.53076 -267.881608) (xy 50.53076 -266.007088) (xy 51.88204 -266.007088) (xy 51.88204 -267.881608)
			)
		)
	)
	(zone
		(layer "In11.Cu")
		(hatch none 0.5)
		(connect_pads
			(clearance 0)
		)
		(min_thickness 0.25)
		(keepout
			(tracks allowed)
			(vias allowed)
			(pads allowed)
			(copperpour allowed)
			(footprints allowed)
		)
		(placement
			(enabled no)
			(sheetname "")
		)
		(fill
			(thermal_gap 0.5)
			(thermal_bridge_width 0.5)
			(island_removal_mode 0)
		)
		(polygon
			(pts
				(xy 50.746152 -218.846908) (xy 50.746152 -218.297252) (xy 51.376072 -218.297252) (xy 51.376072 -218.846908)
			)
		)
	)
	(zone
		(layer "In11.Cu")
		(hatch none 0.5)
		(connect_pads
			(clearance 0)
		)
		(min_thickness 0.25)
		(keepout
			(tracks allowed)
			(vias allowed)
			(pads allowed)
			(copperpour allowed)
			(footprints allowed)
		)
		(placement
			(enabled no)
			(sheetname "")
		)
		(fill
			(thermal_gap 0.5)
			(thermal_bridge_width 0.5)
			(island_removal_mode 0)
		)
		(polygon
			(pts
				(xy 177.170842 -266.964668) (xy 177.170842 -267.240258) (xy 176.612042 -267.240258) (xy 176.612042 -266.964668)
			)
		)
	)
	(zone
		(layer "In11.Cu")
		(hatch none 0.5)
		(connect_pads
			(clearance 0)
		)
		(min_thickness 0.25)
		(keepout
			(tracks allowed)
			(vias allowed)
			(pads allowed)
			(copperpour allowed)
			(footprints allowed)
		)
		(placement
			(enabled no)
			(sheetname "")
		)
		(fill
			(thermal_gap 0.5)
			(thermal_bridge_width 0.5)
			(island_removal_mode 0)
		)
		(polygon
			(pts
				(xy 202.696318 -229.668578) (xy 202.696318 -229.392988) (xy 203.255118 -229.392988) (xy 203.255118 -229.668578)
			)
		)
	)
	(zone
		(layer "In11.Cu")
		(hatch none 0.5)
		(connect_pads
			(clearance 0)
		)
		(min_thickness 0.25)
		(keepout
			(tracks allowed)
			(vias allowed)
			(pads allowed)
			(copperpour allowed)
			(footprints allowed)
		)
		(placement
			(enabled no)
			(sheetname "")
		)
		(fill
			(thermal_gap 0.5)
			(thermal_bridge_width 0.5)
			(island_removal_mode 0)
		)
		(polygon
			(pts
				(xy 192.258442 -261.864856) (xy 192.258442 -262.140446) (xy 191.699642 -262.140446) (xy 191.699642 -261.864856)
			)
		)
	)
	(zone
		(layer "In11.Cu")
		(hatch none 0.5)
		(connect_pads
			(clearance 0)
		)
		(min_thickness 0.25)
		(keepout
			(tracks allowed)
			(vias allowed)
			(pads allowed)
			(copperpour allowed)
			(footprints allowed)
		)
		(placement
			(enabled no)
			(sheetname "")
		)
		(fill
			(thermal_gap 0.5)
			(thermal_bridge_width 0.5)
			(island_removal_mode 0)
		)
		(polygon
			(pts
				(xy 206.796386 -267.918438) (xy 206.796386 -267.642848) (xy 207.355186 -267.642848) (xy 207.355186 -267.918438)
			)
		)
	)
	(zone
		(layer "In11.Cu")
		(hatch none 0.5)
		(connect_pads
			(clearance 0)
		)
		(min_thickness 0.25)
		(keepout
			(tracks allowed)
			(vias allowed)
			(pads allowed)
			(copperpour allowed)
			(footprints allowed)
		)
		(placement
			(enabled no)
			(sheetname "")
		)
		(fill
			(thermal_gap 0.5)
			(thermal_bridge_width 0.5)
			(island_removal_mode 0)
		)
		(polygon
			(pts
				(xy 173.070774 -234.664758) (xy 173.070774 -234.940348) (xy 172.511974 -234.940348) (xy 172.511974 -234.664758)
			)
		)
	)
	(zone
		(layer "In11.Cu")
		(hatch none 0.5)
		(connect_pads
			(clearance 0)
		)
		(min_thickness 0.25)
		(keepout
			(tracks allowed)
			(vias allowed)
			(pads allowed)
			(copperpour allowed)
			(footprints allowed)
		)
		(placement
			(enabled no)
			(sheetname "")
		)
		(fill
			(thermal_gap 0.5)
			(thermal_bridge_width 0.5)
			(island_removal_mode 0)
		)
		(polygon
			(pts
				(xy 268.569186 -246.907812) (xy 268.569186 -246.359172) (xy 269.094966 -246.359172) (xy 269.094966 -246.907812)
			)
		)
	)
	(zone
		(layer "In11.Cu")
		(hatch none 0.5)
		(connect_pads
			(clearance 0)
		)
		(min_thickness 0.25)
		(keepout
			(tracks allowed)
			(vias allowed)
			(pads allowed)
			(copperpour allowed)
			(footprints allowed)
		)
		(placement
			(enabled no)
			(sheetname "")
		)
		(fill
			(thermal_gap 0.5)
			(thermal_bridge_width 0.5)
			(island_removal_mode 0)
		)
		(polygon
			(pts
				(xy 420.461186 -222.018606) (xy 420.461186 -221.743016) (xy 421.019986 -221.743016) (xy 421.019986 -222.018606)
			)
		)
	)
	(zone
		(layer "In11.Cu")
		(hatch none 0.5)
		(connect_pads
			(clearance 0)
		)
		(min_thickness 0.25)
		(keepout
			(tracks allowed)
			(vias allowed)
			(pads allowed)
			(copperpour allowed)
			(footprints allowed)
		)
		(placement
			(enabled no)
			(sheetname "")
		)
		(fill
			(thermal_gap 0.5)
			(thermal_bridge_width 0.5)
			(island_removal_mode 0)
		)
		(polygon
			(pts
				(xy 420.461186 -307.868574) (xy 420.461186 -307.592984) (xy 421.019986 -307.592984) (xy 421.019986 -307.868574)
			)
		)
	)
	(zone
		(layer "In11.Cu")
		(hatch none 0.5)
		(connect_pads
			(clearance 0)
		)
		(min_thickness 0.25)
		(keepout
			(tracks allowed)
			(vias allowed)
			(pads allowed)
			(copperpour allowed)
			(footprints allowed)
		)
		(placement
			(enabled no)
			(sheetname "")
		)
		(fill
			(thermal_gap 0.5)
			(thermal_bridge_width 0.5)
			(island_removal_mode 0)
		)
		(polygon
			(pts
				(xy 50.746152 -233.296968) (xy 50.746152 -232.747312) (xy 51.376072 -232.747312) (xy 51.376072 -233.296968)
			)
		)
	)
	(zone
		(layer "In11.Cu")
		(hatch none 0.5)
		(connect_pads
			(clearance 0)
		)
		(min_thickness 0.25)
		(keepout
			(tracks allowed)
			(vias allowed)
			(pads allowed)
			(copperpour allowed)
			(footprints allowed)
		)
		(placement
			(enabled no)
			(sheetname "")
		)
		(fill
			(thermal_gap 0.5)
			(thermal_bridge_width 0.5)
			(island_removal_mode 0)
		)
		(polygon
			(pts
				(xy 450.636386 -231.3686) (xy 450.636386 -231.09301) (xy 451.195186 -231.09301) (xy 451.195186 -231.3686)
			)
		)
	)
	(zone
		(layer "In11.Cu")
		(hatch none 0.5)
		(connect_pads
			(clearance 0)
		)
		(min_thickness 0.25)
		(keepout
			(tracks allowed)
			(vias allowed)
			(pads allowed)
			(copperpour allowed)
			(footprints allowed)
		)
		(placement
			(enabled no)
			(sheetname "")
		)
		(fill
			(thermal_gap 0.5)
			(thermal_bridge_width 0.5)
			(island_removal_mode 0)
		)
		(polygon
			(pts
				(xy 421.010842 -196.414644) (xy 421.010842 -196.690234) (xy 420.452042 -196.690234) (xy 420.452042 -196.414644)
			)
		)
	)
	(zone
		(layer "In11.Cu")
		(hatch none 0.5)
		(connect_pads
			(clearance 0)
		)
		(min_thickness 0.25)
		(keepout
			(tracks allowed)
			(vias allowed)
			(pads allowed)
			(copperpour allowed)
			(footprints allowed)
		)
		(placement
			(enabled no)
			(sheetname "")
		)
		(fill
			(thermal_gap 0.5)
			(thermal_bridge_width 0.5)
			(island_removal_mode 0)
		)
		(polygon
			(pts
				(xy 298.71162 -284.29712) (xy 298.71162 -283.747464) (xy 299.34154 -283.747464) (xy 299.34154 -284.29712)
			)
		)
	)
	(zone
		(layer "In11.Cu")
		(hatch none 0.5)
		(connect_pads
			(clearance 0)
		)
		(min_thickness 0.25)
		(keepout
			(tracks allowed)
			(vias allowed)
			(pads allowed)
			(copperpour allowed)
			(footprints allowed)
		)
		(placement
			(enabled no)
			(sheetname "")
		)
		(fill
			(thermal_gap 0.5)
			(thermal_bridge_width 0.5)
			(island_removal_mode 0)
		)
		(polygon
			(pts
				(xy 93.15704 -338.369148) (xy 93.15704 -335.194148) (xy 97.43186 -335.194148) (xy 97.43186 -338.369148)
			)
		)
	)
	(zone
		(layer "In11.Cu")
		(hatch none 0.5)
		(connect_pads
			(clearance 0)
		)
		(min_thickness 0.25)
		(keepout
			(tracks allowed)
			(vias allowed)
			(pads allowed)
			(copperpour allowed)
			(footprints allowed)
		)
		(placement
			(enabled no)
			(sheetname "")
		)
		(fill
			(thermal_gap 0.5)
			(thermal_bridge_width 0.5)
			(island_removal_mode 0)
		)
		(polygon
			(pts
				(xy 172.521118 -222.018606) (xy 172.521118 -221.743016) (xy 173.079918 -221.743016) (xy 173.079918 -222.018606)
			)
		)
	)
	(zone
		(layer "In11.Cu")
		(hatch none 0.5)
		(connect_pads
			(clearance 0)
		)
		(min_thickness 0.25)
		(keepout
			(tracks allowed)
			(vias allowed)
			(pads allowed)
			(copperpour allowed)
			(footprints allowed)
		)
		(placement
			(enabled no)
			(sheetname "")
		)
		(fill
			(thermal_gap 0.5)
			(thermal_bridge_width 0.5)
			(island_removal_mode 0)
		)
		(polygon
			(pts
				(xy 420.461186 -290.868608) (xy 420.461186 -290.593018) (xy 421.019986 -290.593018) (xy 421.019986 -290.868608)
			)
		)
	)
	(zone
		(layer "In11.Cu")
		(hatch none 0.5)
		(connect_pads
			(clearance 0)
		)
		(min_thickness 0.25)
		(keepout
			(tracks allowed)
			(vias allowed)
			(pads allowed)
			(copperpour allowed)
			(footprints allowed)
		)
		(placement
			(enabled no)
			(sheetname "")
		)
		(fill
			(thermal_gap 0.5)
			(thermal_bridge_width 0.5)
			(island_removal_mode 0)
		)
		(polygon
			(pts
				(xy 177.170842 -278.014684) (xy 177.170842 -278.290274) (xy 176.612042 -278.290274) (xy 176.612042 -278.014684)
			)
		)
	)
	(zone
		(layer "In11.Cu")
		(hatch none 0.5)
		(connect_pads
			(clearance 0)
		)
		(min_thickness 0.25)
		(keepout
			(tracks allowed)
			(vias allowed)
			(pads allowed)
			(copperpour allowed)
			(footprints allowed)
		)
		(placement
			(enabled no)
			(sheetname "")
		)
		(fill
			(thermal_gap 0.5)
			(thermal_bridge_width 0.5)
			(island_removal_mode 0)
		)
		(polygon
			(pts
				(xy 425.11091 -215.114632) (xy 425.11091 -215.390222) (xy 424.55211 -215.390222) (xy 424.55211 -215.114632)
			)
		)
	)
	(zone
		(layer "In11.Cu")
		(hatch none 0.5)
		(connect_pads
			(clearance 0)
		)
		(min_thickness 0.25)
		(keepout
			(tracks not_allowed)
			(vias allowed)
			(pads allowed)
			(copperpour not_allowed)
			(footprints allowed)
		)
		(placement
			(enabled no)
			(sheetname "")
		)
		(fill
			(thermal_gap 0.5)
			(thermal_bridge_width 0.5)
			(island_removal_mode 0)
		)
		(polygon
			(pts
				(arc
					(start 412.242 -428.960788)
					(mid 412.264318 -429.01467)
					(end 412.3182 -429.036988)
				)
				(arc
					(start 413.258 -429.036988)
					(mid 413.311882 -429.01467)
					(end 413.3342 -428.960788)
				)
				(arc
					(start 413.3342 -426.419264)
					(mid 413.311882 -426.365382)
					(end 413.258 -426.343064)
				)
				(arc
					(start 412.3182 -426.343064)
					(mid 412.264318 -426.365382)
					(end 412.242 -426.419264)
				)
			)
		)
	)
	(zone
		(layer "In11.Cu")
		(hatch none 0.5)
		(connect_pads
			(clearance 0)
		)
		(min_thickness 0.25)
		(keepout
			(tracks allowed)
			(vias allowed)
			(pads allowed)
			(copperpour allowed)
			(footprints allowed)
		)
		(placement
			(enabled no)
			(sheetname "")
		)
		(fill
			(thermal_gap 0.5)
			(thermal_bridge_width 0.5)
			(island_removal_mode 0)
		)
		(polygon
			(pts
				(xy 421.010842 -267.814806) (xy 421.010842 -268.090396) (xy 420.452042 -268.090396) (xy 420.452042 -267.814806)
			)
		)
	)
	(zone
		(layer "In11.Cu")
		(hatch none 0.5)
		(connect_pads
			(clearance 0)
		)
		(min_thickness 0.25)
		(keepout
			(tracks allowed)
			(vias allowed)
			(pads allowed)
			(copperpour allowed)
			(footprints allowed)
		)
		(placement
			(enabled no)
			(sheetname "")
		)
		(fill
			(thermal_gap 0.5)
			(thermal_bridge_width 0.5)
			(island_removal_mode 0)
		)
		(polygon
			(pts
				(xy 420.461186 -284.918404) (xy 420.461186 -284.642814) (xy 421.019986 -284.642814) (xy 421.019986 -284.918404)
			)
		)
	)
	(zone
		(layer "In11.Cu")
		(hatch none 0.5)
		(connect_pads
			(clearance 0)
		)
		(min_thickness 0.25)
		(keepout
			(tracks allowed)
			(vias allowed)
			(pads allowed)
			(copperpour allowed)
			(footprints allowed)
		)
		(placement
			(enabled no)
			(sheetname "")
		)
		(fill
			(thermal_gap 0.5)
			(thermal_bridge_width 0.5)
			(island_removal_mode 0)
		)
		(polygon
			(pts
				(xy 135.80745 -250.250198) (xy 133.976618 -252.08103) (xy 124.721366 -252.08103) (xy 124.721366 -252.919738)
				(xy 124.522738 -253.118366) (xy 124.522738 -253.966726) (xy 124.588778 -254.032766) (xy 124.997718 -254.032766)
				(xy 125.13691 -253.893574) (xy 125.253242 -253.893574) (xy 125.253242 -253.83363) (xy 125.253242 -253.708154)
				(xy 125.264418 -253.696978) (xy 125.535944 -253.696978) (xy 125.73254 -253.893574) (xy 137.178796 -253.89332)
				(xy 137.182606 -253.896876) (xy 140.18895 -253.896876) (xy 140.192506 -253.896876) (xy 140.348462 -254.052832)
				(xy 140.348462 -258.515104) (xy 141.992604 -260.158992) (xy 146.591782 -260.158992) (xy 146.686016 -260.158992)
				(xy 146.724878 -260.12013) (xy 147.077938 -260.12013) (xy 148.393658 -261.43585) (xy 149.163278 -261.43585)
				(xy 150.181818 -260.41731) (xy 150.181818 -258.59359) (xy 150.506938 -258.26847) (xy 150.506938 -256.551938)
				(xy 150.181818 -256.226818) (xy 150.007066 -256.052066) (xy 149.870922 -255.915922) (xy 149.202648 -255.915922)
				(xy 148.340572 -255.053846) (xy 148.166582 -254.879856) (xy 148.166582 -254.514858) (xy 148.069046 -254.417322)
				(xy 148.069046 -254.156718) (xy 148.010118 -254.09779) (xy 147.761706 -254.09779) (xy 147.464272 -254.395224)
				(xy 147.001992 -253.932944) (xy 148.181568 -252.753368) (xy 148.181568 -250.884182) (xy 147.15871 -249.861578)
				(xy 150.128478 -246.89181) (xy 150.128478 -246.28475) (xy 149.80412 -245.960392) (xy 148.824696 -245.960392)
				(xy 141.103096 -245.960392) (xy 140.93952 -246.123968) (xy 138.61034 -246.123968) (xy 138.37666 -246.357648)
				(xy 138.37666 -246.798592) (xy 138.309604 -246.865648) (xy 138.309604 -248.228104) (xy 138.309604 -249.416824)
				(xy 138.15822 -249.568208) (xy 138.15822 -249.805952) (xy 138.08202 -249.882152) (xy 137.882376 -249.882152)
				(xy 137.51433 -250.250198) (xy 137.360406 -250.404122) (xy 136.9187 -250.404122) (xy 136.764776 -250.250198)
			)
		)
	)
	(zone
		(layer "In11.Cu")
		(hatch none 0.5)
		(connect_pads
			(clearance 0)
		)
		(min_thickness 0.25)
		(keepout
			(tracks allowed)
			(vias allowed)
			(pads allowed)
			(copperpour allowed)
			(footprints allowed)
		)
		(placement
			(enabled no)
			(sheetname "")
		)
		(fill
			(thermal_gap 0.5)
			(thermal_bridge_width 0.5)
			(island_removal_mode 0)
		)
		(polygon
			(pts
				(xy 202.696318 -278.968454) (xy 202.696318 -278.692864) (xy 203.255118 -278.692864) (xy 203.255118 -278.968454)
			)
		)
	)
	(zone
		(layer "In11.Cu")
		(hatch none 0.5)
		(connect_pads
			(clearance 0)
		)
		(min_thickness 0.25)
		(keepout
			(tracks allowed)
			(vias allowed)
			(pads allowed)
			(copperpour allowed)
			(footprints allowed)
		)
		(placement
			(enabled no)
			(sheetname "")
		)
		(fill
			(thermal_gap 0.5)
			(thermal_bridge_width 0.5)
			(island_removal_mode 0)
		)
		(polygon
			(pts
				(xy 425.11091 -232.114852) (xy 425.11091 -232.390442) (xy 424.55211 -232.390442) (xy 424.55211 -232.114852)
			)
		)
	)
	(zone
		(layer "In11.Cu")
		(hatch none 0.5)
		(connect_pads
			(clearance 0)
		)
		(min_thickness 0.25)
		(keepout
			(tracks allowed)
			(vias allowed)
			(pads allowed)
			(copperpour allowed)
			(footprints allowed)
		)
		(placement
			(enabled no)
			(sheetname "")
		)
		(fill
			(thermal_gap 0.5)
			(thermal_bridge_width 0.5)
			(island_removal_mode 0)
		)
		(polygon
			(pts
				(xy 425.11091 -270.364712) (xy 425.11091 -270.640302) (xy 424.55211 -270.640302) (xy 424.55211 -270.364712)
			)
		)
	)
	(zone
		(layer "In11.Cu")
		(hatch none 0.5)
		(connect_pads
			(clearance 0)
		)
		(min_thickness 0.25)
		(keepout
			(tracks allowed)
			(vias allowed)
			(pads allowed)
			(copperpour allowed)
			(footprints allowed)
		)
		(placement
			(enabled no)
			(sheetname "")
		)
		(fill
			(thermal_gap 0.5)
			(thermal_bridge_width 0.5)
			(island_removal_mode 0)
		)
		(polygon
			(pts
				(xy 187.608718 -281.518614) (xy 187.608718 -281.243024) (xy 188.167518 -281.243024) (xy 188.167518 -281.518614)
			)
		)
	)
	(zone
		(layer "In11.Cu")
		(hatch none 0.5)
		(connect_pads
			(clearance 0)
		)
		(min_thickness 0.25)
		(keepout
			(tracks allowed)
			(vias allowed)
			(pads allowed)
			(copperpour allowed)
			(footprints allowed)
		)
		(placement
			(enabled no)
			(sheetname "")
		)
		(fill
			(thermal_gap 0.5)
			(thermal_bridge_width 0.5)
			(island_removal_mode 0)
		)
		(polygon
			(pts
				(xy 425.11091 -203.214732) (xy 425.11091 -203.490322) (xy 424.55211 -203.490322) (xy 424.55211 -203.214732)
			)
		)
	)
	(zone
		(layer "In11.Cu")
		(hatch none 0.5)
		(connect_pads
			(clearance 0)
		)
		(min_thickness 0.25)
		(keepout
			(tracks allowed)
			(vias allowed)
			(pads allowed)
			(copperpour allowed)
			(footprints allowed)
		)
		(placement
			(enabled no)
			(sheetname "")
		)
		(fill
			(thermal_gap 0.5)
			(thermal_bridge_width 0.5)
			(island_removal_mode 0)
		)
		(polygon
			(pts
				(xy 46.646084 -212.04682) (xy 46.646084 -211.497164) (xy 47.276004 -211.497164) (xy 47.276004 -212.04682)
			)
		)
	)
	(zone
		(layer "In11.Cu")
		(hatch none 0.5)
		(connect_pads
			(clearance 0)
		)
		(min_thickness 0.25)
		(keepout
			(tracks allowed)
			(vias allowed)
			(pads allowed)
			(copperpour allowed)
			(footprints allowed)
		)
		(placement
			(enabled no)
			(sheetname "")
		)
		(fill
			(thermal_gap 0.5)
			(thermal_bridge_width 0.5)
			(island_removal_mode 0)
		)
		(polygon
			(pts
				(xy 203.245974 -279.714706) (xy 203.245974 -279.990296) (xy 202.687174 -279.990296) (xy 202.687174 -279.714706)
			)
		)
	)
	(zone
		(layer "In11.Cu")
		(hatch none 0.5)
		(connect_pads
			(clearance 0)
		)
		(min_thickness 0.25)
		(keepout
			(tracks allowed)
			(vias allowed)
			(pads allowed)
			(copperpour allowed)
			(footprints allowed)
		)
		(placement
			(enabled no)
			(sheetname "")
		)
		(fill
			(thermal_gap 0.5)
			(thermal_bridge_width 0.5)
			(island_removal_mode 0)
		)
		(polygon
			(pts
				(xy 425.11091 -194.714622) (xy 425.11091 -194.990212) (xy 424.55211 -194.990212) (xy 424.55211 -194.714622)
			)
		)
	)
	(zone
		(layer "In11.Cu")
		(hatch none 0.5)
		(connect_pads
			(clearance 0)
		)
		(min_thickness 0.25)
		(keepout
			(tracks allowed)
			(vias allowed)
			(pads allowed)
			(copperpour allowed)
			(footprints allowed)
		)
		(placement
			(enabled no)
			(sheetname "")
		)
		(fill
			(thermal_gap 0.5)
			(thermal_bridge_width 0.5)
			(island_removal_mode 0)
		)
		(polygon
			(pts
				(xy 177.170842 -218.514676) (xy 177.170842 -218.790266) (xy 176.612042 -218.790266) (xy 176.612042 -218.514676)
			)
		)
	)
	(zone
		(layer "In11.Cu")
		(hatch none 0.5)
		(connect_pads
			(clearance 0)
		)
		(min_thickness 0.25)
		(keepout
			(tracks allowed)
			(vias allowed)
			(pads allowed)
			(copperpour allowed)
			(footprints allowed)
		)
		(placement
			(enabled no)
			(sheetname "")
		)
		(fill
			(thermal_gap 0.5)
			(thermal_bridge_width 0.5)
			(island_removal_mode 0)
		)
		(polygon
			(pts
				(xy 50.746152 -227.346764) (xy 50.746152 -226.797108) (xy 51.376072 -226.797108) (xy 51.376072 -227.346764)
			)
		)
	)
	(zone
		(layer "In11.Cu")
		(hatch none 0.5)
		(connect_pads
			(clearance 0)
		)
		(min_thickness 0.25)
		(keepout
			(tracks allowed)
			(vias allowed)
			(pads allowed)
			(copperpour allowed)
			(footprints allowed)
		)
		(placement
			(enabled no)
			(sheetname "")
		)
		(fill
			(thermal_gap 0.5)
			(thermal_bridge_width 0.5)
			(island_removal_mode 0)
		)
		(polygon
			(pts
				(xy 20.629118 -250.297696) (xy 20.629118 -249.749056) (xy 21.154898 -249.749056) (xy 21.154898 -250.297696)
			)
		)
	)
	(zone
		(layer "In11.Cu")
		(hatch none 0.5)
		(connect_pads
			(clearance 0)
		)
		(min_thickness 0.25)
		(keepout
			(tracks allowed)
			(vias allowed)
			(pads allowed)
			(copperpour allowed)
			(footprints allowed)
		)
		(placement
			(enabled no)
			(sheetname "")
		)
		(fill
			(thermal_gap 0.5)
			(thermal_bridge_width 0.5)
			(island_removal_mode 0)
		)
		(polygon
			(pts
				(xy 177.170842 -221.064836) (xy 177.170842 -221.340426) (xy 176.612042 -221.340426) (xy 176.612042 -221.064836)
			)
		)
	)
	(zone
		(layer "In11.Cu")
		(hatch none 0.5)
		(connect_pads
			(clearance 0)
		)
		(min_thickness 0.25)
		(keepout
			(tracks allowed)
			(vias allowed)
			(pads allowed)
			(copperpour allowed)
			(footprints allowed)
		)
		(placement
			(enabled no)
			(sheetname "")
		)
		(fill
			(thermal_gap 0.5)
			(thermal_bridge_width 0.5)
			(island_removal_mode 0)
		)
		(polygon
			(pts
				(xy 50.771552 -276.647148) (xy 50.771552 -276.097492) (xy 51.401472 -276.097492) (xy 51.401472 -276.647148)
			)
		)
	)
	(zone
		(layer "In11.Cu")
		(hatch none 0.5)
		(connect_pads
			(clearance 0)
		)
		(min_thickness 0.25)
		(keepout
			(tracks allowed)
			(vias allowed)
			(pads allowed)
			(copperpour allowed)
			(footprints allowed)
		)
		(placement
			(enabled no)
			(sheetname "")
		)
		(fill
			(thermal_gap 0.5)
			(thermal_bridge_width 0.5)
			(island_removal_mode 0)
		)
		(polygon
			(pts
				(xy 50.746152 -211.196936) (xy 50.746152 -210.64728) (xy 51.376072 -210.64728) (xy 51.376072 -211.196936)
			)
		)
	)
	(zone
		(layer "In11.Cu")
		(hatch none 0.5)
		(connect_pads
			(clearance 0)
		)
		(min_thickness 0.25)
		(keepout
			(tracks allowed)
			(vias allowed)
			(pads allowed)
			(copperpour allowed)
			(footprints allowed)
		)
		(placement
			(enabled no)
			(sheetname "")
		)
		(fill
			(thermal_gap 0.5)
			(thermal_bridge_width 0.5)
			(island_removal_mode 0)
		)
		(polygon
			(pts
				(xy 421.010842 -283.964634) (xy 421.010842 -284.240224) (xy 420.452042 -284.240224) (xy 420.452042 -283.964634)
			)
		)
	)
	(zone
		(layer "In11.Cu")
		(hatch none 0.5)
		(connect_pads
			(clearance 0)
		)
		(min_thickness 0.25)
		(keepout
			(tracks allowed)
			(vias allowed)
			(pads allowed)
			(copperpour allowed)
			(footprints allowed)
		)
		(placement
			(enabled no)
			(sheetname "")
		)
		(fill
			(thermal_gap 0.5)
			(thermal_bridge_width 0.5)
			(island_removal_mode 0)
		)
		(polygon
			(pts
				(xy 425.11091 -311.164732) (xy 425.11091 -311.440322) (xy 424.55211 -311.440322) (xy 424.55211 -311.164732)
			)
		)
	)
	(zone
		(layer "In11.Cu")
		(hatch none 0.5)
		(connect_pads
			(clearance 0)
		)
		(min_thickness 0.25)
		(keepout
			(tracks allowed)
			(vias allowed)
			(pads allowed)
			(copperpour allowed)
			(footprints allowed)
		)
		(placement
			(enabled no)
			(sheetname "")
		)
		(fill
			(thermal_gap 0.5)
			(thermal_bridge_width 0.5)
			(island_removal_mode 0)
		)
		(polygon
			(pts
				(xy 176.621186 -303.618392) (xy 176.621186 -303.342802) (xy 177.179986 -303.342802) (xy 177.179986 -303.618392)
			)
		)
	)
	(zone
		(layer "In11.Cu")
		(hatch none 0.5)
		(connect_pads
			(clearance 0)
		)
		(min_thickness 0.25)
		(keepout
			(tracks allowed)
			(vias allowed)
			(pads allowed)
			(copperpour allowed)
			(footprints allowed)
		)
		(placement
			(enabled no)
			(sheetname "")
		)
		(fill
			(thermal_gap 0.5)
			(thermal_bridge_width 0.5)
			(island_removal_mode 0)
		)
		(polygon
			(pts
				(xy 46.646084 -219.696792) (xy 46.646084 -219.147136) (xy 47.276004 -219.147136) (xy 47.276004 -219.696792)
			)
		)
	)
	(zone
		(layer "In11.Cu")
		(hatch none 0.5)
		(connect_pads
			(clearance 0)
		)
		(min_thickness 0.25)
		(keepout
			(tracks allowed)
			(vias allowed)
			(pads allowed)
			(copperpour allowed)
			(footprints allowed)
		)
		(placement
			(enabled no)
			(sheetname "")
		)
		(fill
			(thermal_gap 0.5)
			(thermal_bridge_width 0.5)
			(island_removal_mode 0)
		)
		(polygon
			(pts
				(xy 425.11091 -213.41461) (xy 425.11091 -213.6902) (xy 424.55211 -213.6902) (xy 424.55211 -213.41461)
			)
		)
	)
	(zone
		(layer "In11.Cu")
		(hatch none 0.5)
		(connect_pads
			(clearance 0)
		)
		(min_thickness 0.25)
		(keepout
			(tracks allowed)
			(vias allowed)
			(pads allowed)
			(copperpour allowed)
			(footprints allowed)
		)
		(placement
			(enabled no)
			(sheetname "")
		)
		(fill
			(thermal_gap 0.5)
			(thermal_bridge_width 0.5)
			(island_removal_mode 0)
		)
		(polygon
			(pts
				(xy 188.158374 -233.81462) (xy 188.158374 -234.09021) (xy 187.599574 -234.09021) (xy 187.599574 -233.81462)
			)
		)
	)
	(zone
		(layer "In11.Cu")
		(hatch none 0.5)
		(connect_pads
			(clearance 0)
		)
		(min_thickness 0.25)
		(keepout
			(tracks allowed)
			(vias allowed)
			(pads allowed)
			(copperpour allowed)
			(footprints allowed)
		)
		(placement
			(enabled no)
			(sheetname "")
		)
		(fill
			(thermal_gap 0.5)
			(thermal_bridge_width 0.5)
			(island_removal_mode 0)
		)
		(polygon
			(pts
				(xy 172.521118 -283.218382) (xy 172.521118 -282.942792) (xy 173.079918 -282.942792) (xy 173.079918 -283.218382)
			)
		)
	)
	(zone
		(layer "In11.Cu")
		(hatch none 0.5)
		(connect_pads
			(clearance 0)
		)
		(min_thickness 0.25)
		(keepout
			(tracks allowed)
			(vias allowed)
			(pads allowed)
			(copperpour allowed)
			(footprints allowed)
		)
		(placement
			(enabled no)
			(sheetname "")
		)
		(fill
			(thermal_gap 0.5)
			(thermal_bridge_width 0.5)
			(island_removal_mode 0)
		)
		(polygon
			(pts
				(xy 294.586152 -213.746842) (xy 294.586152 -213.197186) (xy 295.216072 -213.197186) (xy 295.216072 -213.746842)
			)
		)
	)
	(zone
		(layer "In11.Cu")
		(hatch none 0.5)
		(connect_pads
			(clearance 0)
		)
		(min_thickness 0.25)
		(keepout
			(tracks allowed)
			(vias allowed)
			(pads allowed)
			(copperpour allowed)
			(footprints allowed)
		)
		(placement
			(enabled no)
			(sheetname "")
		)
		(fill
			(thermal_gap 0.5)
			(thermal_bridge_width 0.5)
			(island_removal_mode 0)
		)
		(polygon
			(pts
				(xy 177.170842 -263.564624) (xy 177.170842 -263.840214) (xy 176.612042 -263.840214) (xy 176.612042 -263.564624)
			)
		)
	)
	(zone
		(layer "In11.Cu")
		(hatch none 0.5)
		(connect_pads
			(clearance 0)
		)
		(min_thickness 0.25)
		(keepout
			(tracks allowed)
			(vias allowed)
			(pads allowed)
			(copperpour allowed)
			(footprints allowed)
		)
		(placement
			(enabled no)
			(sheetname "")
		)
		(fill
			(thermal_gap 0.5)
			(thermal_bridge_width 0.5)
			(island_removal_mode 0)
		)
		(polygon
			(pts
				(xy 177.170842 -224.464626) (xy 177.170842 -224.740216) (xy 176.612042 -224.740216) (xy 176.612042 -224.464626)
			)
		)
	)
	(zone
		(layer "In11.Cu")
		(hatch none 0.5)
		(connect_pads
			(clearance 0)
		)
		(min_thickness 0.25)
		(keepout
			(tracks allowed)
			(vias allowed)
			(pads allowed)
			(copperpour allowed)
			(footprints allowed)
		)
		(placement
			(enabled no)
			(sheetname "")
		)
		(fill
			(thermal_gap 0.5)
			(thermal_bridge_width 0.5)
			(island_removal_mode 0)
		)
		(polygon
			(pts
				(xy 173.070774 -247.414796) (xy 173.070774 -247.690386) (xy 172.511974 -247.690386) (xy 172.511974 -247.414796)
			)
		)
	)
	(zone
		(layer "In11.Cu")
		(hatch none 0.5)
		(connect_pads
			(clearance 0)
		)
		(min_thickness 0.25)
		(keepout
			(tracks allowed)
			(vias allowed)
			(pads allowed)
			(copperpour allowed)
			(footprints allowed)
		)
		(placement
			(enabled no)
			(sheetname "")
		)
		(fill
			(thermal_gap 0.5)
			(thermal_bridge_width 0.5)
			(island_removal_mode 0)
		)
		(polygon
			(pts
				(xy 432.105054 -267.068554) (xy 432.105054 -266.792964) (xy 432.663854 -266.792964) (xy 432.663854 -267.068554)
			)
		)
	)
	(zone
		(layer "In11.Cu")
		(hatch none 0.5)
		(connect_pads
			(clearance 0)
		)
		(min_thickness 0.25)
		(keepout
			(tracks allowed)
			(vias allowed)
			(pads allowed)
			(copperpour allowed)
			(footprints allowed)
		)
		(placement
			(enabled no)
			(sheetname "")
		)
		(fill
			(thermal_gap 0.5)
			(thermal_bridge_width 0.5)
			(island_removal_mode 0)
		)
		(polygon
			(pts
				(xy 387.32968 -272.35531) (xy 389.153146 -272.35531) (xy 389.419846 -272.62201) (xy 389.419846 -274.37207)
				(xy 389.313166 -274.47875) (xy 387.994906 -274.47875) (xy 387.631686 -274.11553) (xy 387.32968 -274.11553)
			)
		)
	)
	(zone
		(layer "In11.Cu")
		(hatch none 0.5)
		(connect_pads
			(clearance 0)
		)
		(min_thickness 0.25)
		(keepout
			(tracks allowed)
			(vias allowed)
			(pads allowed)
			(copperpour allowed)
			(footprints allowed)
		)
		(placement
			(enabled no)
			(sheetname "")
		)
		(fill
			(thermal_gap 0.5)
			(thermal_bridge_width 0.5)
			(island_removal_mode 0)
		)
		(polygon
			(pts
				(xy 203.245974 -296.714672) (xy 203.245974 -296.990262) (xy 202.687174 -296.990262) (xy 202.687174 -296.714672)
			)
		)
	)
	(zone
		(layer "In11.Cu")
		(hatch none 0.5)
		(connect_pads
			(clearance 0)
		)
		(min_thickness 0.25)
		(keepout
			(tracks allowed)
			(vias allowed)
			(pads allowed)
			(copperpour allowed)
			(footprints allowed)
		)
		(placement
			(enabled no)
			(sheetname "")
		)
		(fill
			(thermal_gap 0.5)
			(thermal_bridge_width 0.5)
			(island_removal_mode 0)
		)
		(polygon
			(pts
				(xy 451.186042 -270.364712) (xy 451.186042 -270.640302) (xy 450.627242 -270.640302) (xy 450.627242 -270.364712)
			)
		)
	)
	(zone
		(layer "In11.Cu")
		(hatch none 0.5)
		(connect_pads
			(clearance 0)
		)
		(min_thickness 0.25)
		(keepout
			(tracks allowed)
			(vias allowed)
			(pads allowed)
			(copperpour allowed)
			(footprints allowed)
		)
		(placement
			(enabled no)
			(sheetname "")
		)
		(fill
			(thermal_gap 0.5)
			(thermal_bridge_width 0.5)
			(island_removal_mode 0)
		)
		(polygon
			(pts
				(xy 425.11091 -304.364644) (xy 425.11091 -304.640234) (xy 424.55211 -304.640234) (xy 424.55211 -304.364644)
			)
		)
	)
	(zone
		(layer "In11.Cu")
		(hatch none 0.5)
		(connect_pads
			(clearance 0)
		)
		(min_thickness 0.25)
		(keepout
			(tracks allowed)
			(vias allowed)
			(pads allowed)
			(copperpour allowed)
			(footprints allowed)
		)
		(placement
			(enabled no)
			(sheetname "")
		)
		(fill
			(thermal_gap 0.5)
			(thermal_bridge_width 0.5)
			(island_removal_mode 0)
		)
		(polygon
			(pts
				(xy 424.561254 -273.018504) (xy 424.561254 -272.742914) (xy 425.120054 -272.742914) (xy 425.120054 -273.018504)
			)
		)
	)
	(zone
		(layer "In11.Cu")
		(hatch none 0.5)
		(connect_pads
			(clearance 0)
		)
		(min_thickness 0.25)
		(keepout
			(tracks allowed)
			(vias allowed)
			(pads allowed)
			(copperpour allowed)
			(footprints allowed)
		)
		(placement
			(enabled no)
			(sheetname "")
		)
		(fill
			(thermal_gap 0.5)
			(thermal_bridge_width 0.5)
			(island_removal_mode 0)
		)
		(polygon
			(pts
				(xy 20.570952 -220.54693) (xy 20.570952 -219.997274) (xy 21.200872 -219.997274) (xy 21.200872 -220.54693)
			)
		)
	)
	(zone
		(layer "In11.Cu")
		(hatch none 0.5)
		(connect_pads
			(clearance 0)
		)
		(min_thickness 0.25)
		(keepout
			(tracks allowed)
			(vias allowed)
			(pads allowed)
			(copperpour allowed)
			(footprints allowed)
		)
		(placement
			(enabled no)
			(sheetname "")
		)
		(fill
			(thermal_gap 0.5)
			(thermal_bridge_width 0.5)
			(island_removal_mode 0)
		)
		(polygon
			(pts
				(xy 172.521118 -304.46853) (xy 172.521118 -304.19294) (xy 173.079918 -304.19294) (xy 173.079918 -304.46853)
			)
		)
	)
	(zone
		(layer "In11.Cu")
		(hatch none 0.5)
		(connect_pads
			(clearance 0)
		)
		(min_thickness 0.25)
		(keepout
			(tracks allowed)
			(vias allowed)
			(pads allowed)
			(copperpour allowed)
			(footprints allowed)
		)
		(placement
			(enabled no)
			(sheetname "")
		)
		(fill
			(thermal_gap 0.5)
			(thermal_bridge_width 0.5)
			(island_removal_mode 0)
		)
		(polygon
			(pts
				(xy 421.010842 -219.364814) (xy 421.010842 -219.640404) (xy 420.452042 -219.640404) (xy 420.452042 -219.364814)
			)
		)
	)
	(zone
		(layer "In11.Cu")
		(hatch none 0.5)
		(connect_pads
			(clearance 0)
		)
		(min_thickness 0.25)
		(keepout
			(tracks allowed)
			(vias allowed)
			(pads allowed)
			(copperpour allowed)
			(footprints allowed)
		)
		(placement
			(enabled no)
			(sheetname "")
		)
		(fill
			(thermal_gap 0.5)
			(thermal_bridge_width 0.5)
			(island_removal_mode 0)
		)
		(polygon
			(pts
				(xy 46.646084 -291.946838) (xy 46.646084 -291.397182) (xy 47.276004 -291.397182) (xy 47.276004 -291.946838)
			)
		)
	)
	(zone
		(layer "In11.Cu")
		(hatch none 0.5)
		(connect_pads
			(clearance 0)
		)
		(min_thickness 0.25)
		(keepout
			(tracks allowed)
			(vias allowed)
			(pads allowed)
			(copperpour allowed)
			(footprints allowed)
		)
		(placement
			(enabled no)
			(sheetname "")
		)
		(fill
			(thermal_gap 0.5)
			(thermal_bridge_width 0.5)
			(island_removal_mode 0)
		)
		(polygon
			(pts
				(xy 421.010842 -295.864788) (xy 421.010842 -296.140378) (xy 420.452042 -296.140378) (xy 420.452042 -295.864788)
			)
		)
	)
	(zone
		(layer "In11.Cu")
		(hatch none 0.5)
		(connect_pads
			(clearance 0)
		)
		(min_thickness 0.25)
		(keepout
			(tracks allowed)
			(vias allowed)
			(pads allowed)
			(copperpour allowed)
			(footprints allowed)
		)
		(placement
			(enabled no)
			(sheetname "")
		)
		(fill
			(thermal_gap 0.5)
			(thermal_bridge_width 0.5)
			(island_removal_mode 0)
		)
		(polygon
			(pts
				(xy 294.586152 -226.49688) (xy 294.586152 -225.947224) (xy 295.216072 -225.947224) (xy 295.216072 -226.49688)
			)
		)
	)
	(zone
		(layer "In11.Cu")
		(hatch none 0.5)
		(connect_pads
			(clearance 0)
		)
		(min_thickness 0.25)
		(keepout
			(tracks allowed)
			(vias allowed)
			(pads allowed)
			(copperpour allowed)
			(footprints allowed)
		)
		(placement
			(enabled no)
			(sheetname "")
		)
		(fill
			(thermal_gap 0.5)
			(thermal_bridge_width 0.5)
			(island_removal_mode 0)
		)
		(polygon
			(pts
				(xy 421.010842 -301.814738) (xy 421.010842 -302.090328) (xy 420.452042 -302.090328) (xy 420.452042 -301.814738)
			)
		)
	)
	(zone
		(layer "In11.Cu")
		(hatch none 0.5)
		(connect_pads
			(clearance 0)
		)
		(min_thickness 0.25)
		(keepout
			(tracks allowed)
			(vias allowed)
			(pads allowed)
			(copperpour allowed)
			(footprints allowed)
		)
		(placement
			(enabled no)
			(sheetname "")
		)
		(fill
			(thermal_gap 0.5)
			(thermal_bridge_width 0.5)
			(island_removal_mode 0)
		)
		(polygon
			(pts
				(xy 294.586152 -252.84684) (xy 294.586152 -252.297184) (xy 295.216072 -252.297184) (xy 295.216072 -252.84684)
			)
		)
	)
	(zone
		(layer "In11.Cu")
		(hatch none 0.5)
		(connect_pads
			(clearance 0)
		)
		(min_thickness 0.25)
		(keepout
			(tracks allowed)
			(vias allowed)
			(pads allowed)
			(copperpour allowed)
			(footprints allowed)
		)
		(placement
			(enabled no)
			(sheetname "")
		)
		(fill
			(thermal_gap 0.5)
			(thermal_bridge_width 0.5)
			(island_removal_mode 0)
		)
		(polygon
			(pts
				(xy 436.098442 -235.514642) (xy 436.098442 -235.790232) (xy 435.539642 -235.790232) (xy 435.539642 -235.514642)
			)
		)
	)
	(zone
		(layer "In11.Cu")
		(hatch none 0.5)
		(connect_pads
			(clearance 0)
		)
		(min_thickness 0.25)
		(keepout
			(tracks allowed)
			(vias allowed)
			(pads allowed)
			(copperpour allowed)
			(footprints allowed)
		)
		(placement
			(enabled no)
			(sheetname "")
		)
		(fill
			(thermal_gap 0.5)
			(thermal_bridge_width 0.5)
			(island_removal_mode 0)
		)
		(polygon
			(pts
				(xy 294.586152 -247.746774) (xy 294.586152 -247.197118) (xy 295.216072 -247.197118) (xy 295.216072 -247.746774)
			)
		)
	)
	(zone
		(layer "In11.Cu")
		(hatch none 0.5)
		(connect_pads
			(clearance 0)
		)
		(min_thickness 0.25)
		(keepout
			(tracks allowed)
			(vias allowed)
			(pads allowed)
			(copperpour allowed)
			(footprints allowed)
		)
		(placement
			(enabled no)
			(sheetname "")
		)
		(fill
			(thermal_gap 0.5)
			(thermal_bridge_width 0.5)
			(island_removal_mode 0)
		)
		(polygon
			(pts
				(xy 291.194998 -260.501638) (xy 291.194998 -259.933186) (xy 291.720778 -259.933186) (xy 291.720778 -260.501638)
			)
		)
	)
	(zone
		(layer "In11.Cu")
		(hatch none 0.5)
		(connect_pads
			(clearance 0)
		)
		(min_thickness 0.25)
		(keepout
			(tracks allowed)
			(vias allowed)
			(pads allowed)
			(copperpour allowed)
			(footprints allowed)
		)
		(placement
			(enabled no)
			(sheetname "")
		)
		(fill
			(thermal_gap 0.5)
			(thermal_bridge_width 0.5)
			(island_removal_mode 0)
		)
		(polygon
			(pts
				(xy 450.636386 -219.468446) (xy 450.636386 -219.192856) (xy 451.195186 -219.192856) (xy 451.195186 -219.468446)
			)
		)
	)
	(zone
		(layer "In11.Cu")
		(hatch none 0.5)
		(connect_pads
			(clearance 0)
		)
		(min_thickness 0.25)
		(keepout
			(tracks allowed)
			(vias allowed)
			(pads allowed)
			(copperpour allowed)
			(footprints allowed)
		)
		(placement
			(enabled no)
			(sheetname "")
		)
		(fill
			(thermal_gap 0.5)
			(thermal_bridge_width 0.5)
			(island_removal_mode 0)
		)
		(polygon
			(pts
				(xy 428.554642 -267.814806) (xy 428.554642 -268.090396) (xy 427.995842 -268.090396) (xy 427.995842 -267.814806)
			)
		)
	)
	(zone
		(layer "In11.Cu")
		(hatch none 0.5)
		(connect_pads
			(clearance 0)
		)
		(min_thickness 0.25)
		(keepout
			(tracks allowed)
			(vias allowed)
			(pads allowed)
			(copperpour allowed)
			(footprints allowed)
		)
		(placement
			(enabled no)
			(sheetname "")
		)
		(fill
			(thermal_gap 0.5)
			(thermal_bridge_width 0.5)
			(island_removal_mode 0)
		)
		(polygon
			(pts
				(xy 268.56436 -295.350692) (xy 268.56436 -294.800274) (xy 269.12316 -294.800274) (xy 269.12316 -295.350692)
			)
		)
	)
	(zone
		(layer "In11.Cu")
		(hatch none 0.5)
		(connect_pads
			(clearance 0)
		)
		(min_thickness 0.25)
		(keepout
			(tracks allowed)
			(vias allowed)
			(pads allowed)
			(copperpour allowed)
			(footprints allowed)
		)
		(placement
			(enabled no)
			(sheetname "")
		)
		(fill
			(thermal_gap 0.5)
			(thermal_bridge_width 0.5)
			(island_removal_mode 0)
		)
		(polygon
			(pts
				(xy 203.245974 -204.914754) (xy 203.245974 -205.190344) (xy 202.687174 -205.190344) (xy 202.687174 -204.914754)
			)
		)
	)
	(zone
		(layer "In11.Cu")
		(hatch none 0.5)
		(connect_pads
			(clearance 0)
		)
		(min_thickness 0.25)
		(keepout
			(tracks allowed)
			(vias allowed)
			(pads allowed)
			(copperpour allowed)
			(footprints allowed)
		)
		(placement
			(enabled no)
			(sheetname "")
		)
		(fill
			(thermal_gap 0.5)
			(thermal_bridge_width 0.5)
			(island_removal_mode 0)
		)
		(polygon
			(pts
				(xy 421.010842 -237.214664) (xy 421.010842 -237.490254) (xy 420.452042 -237.490254) (xy 420.452042 -237.214664)
			)
		)
	)
	(zone
		(layer "In11.Cu")
		(hatch none 0.5)
		(connect_pads
			(clearance 0)
		)
		(min_thickness 0.25)
		(keepout
			(tracks allowed)
			(vias allowed)
			(pads allowed)
			(copperpour allowed)
			(footprints allowed)
		)
		(placement
			(enabled no)
			(sheetname "")
		)
		(fill
			(thermal_gap 0.5)
			(thermal_bridge_width 0.5)
			(island_removal_mode 0)
		)
		(polygon
			(pts
				(xy 425.11091 -272.064734) (xy 425.11091 -272.340324) (xy 424.55211 -272.340324) (xy 424.55211 -272.064734)
			)
		)
	)
	(zone
		(layer "In11.Cu")
		(hatch none 0.5)
		(connect_pads
			(clearance 0)
		)
		(min_thickness 0.25)
		(keepout
			(tracks allowed)
			(vias allowed)
			(pads allowed)
			(copperpour allowed)
			(footprints allowed)
		)
		(placement
			(enabled no)
			(sheetname "")
		)
		(fill
			(thermal_gap 0.5)
			(thermal_bridge_width 0.5)
			(island_removal_mode 0)
		)
		(polygon
			(pts
				(xy 424.561254 -252.618494) (xy 424.561254 -252.342904) (xy 425.120054 -252.342904) (xy 425.120054 -252.618494)
			)
		)
	)
	(zone
		(layer "In11.Cu")
		(hatch none 0.5)
		(connect_pads
			(clearance 0)
		)
		(min_thickness 0.25)
		(keepout
			(tracks allowed)
			(vias allowed)
			(pads allowed)
			(copperpour allowed)
			(footprints allowed)
		)
		(placement
			(enabled no)
			(sheetname "")
		)
		(fill
			(thermal_gap 0.5)
			(thermal_bridge_width 0.5)
			(island_removal_mode 0)
		)
		(polygon
			(pts
				(xy 421.010842 -215.96477) (xy 421.010842 -216.24036) (xy 420.452042 -216.24036) (xy 420.452042 -215.96477)
			)
		)
	)
	(zone
		(layer "In11.Cu")
		(hatch none 0.5)
		(connect_pads
			(clearance 0)
		)
		(min_thickness 0.25)
		(keepout
			(tracks allowed)
			(vias allowed)
			(pads allowed)
			(copperpour allowed)
			(footprints allowed)
		)
		(placement
			(enabled no)
			(sheetname "")
		)
		(fill
			(thermal_gap 0.5)
			(thermal_bridge_width 0.5)
			(island_removal_mode 0)
		)
		(polygon
			(pts
				(xy 268.51102 -195.896738) (xy 268.51102 -195.347082) (xy 269.14094 -195.347082) (xy 269.14094 -195.896738)
			)
		)
	)
	(zone
		(layer "In11.Cu")
		(hatch none 0.5)
		(connect_pads
			(clearance 0)
		)
		(min_thickness 0.25)
		(keepout
			(tracks allowed)
			(vias allowed)
			(pads allowed)
			(copperpour allowed)
			(footprints allowed)
		)
		(placement
			(enabled no)
			(sheetname "")
		)
		(fill
			(thermal_gap 0.5)
			(thermal_bridge_width 0.5)
			(island_removal_mode 0)
		)
		(polygon
			(pts
				(xy 176.621186 -234.76839) (xy 176.621186 -234.4928) (xy 177.179986 -234.4928) (xy 177.179986 -234.76839)
			)
		)
	)
	(zone
		(layer "In11.Cu")
		(hatch none 0.5)
		(connect_pads
			(clearance 0)
		)
		(min_thickness 0.25)
		(keepout
			(tracks allowed)
			(vias allowed)
			(pads allowed)
			(copperpour allowed)
			(footprints allowed)
		)
		(placement
			(enabled no)
			(sheetname "")
		)
		(fill
			(thermal_gap 0.5)
			(thermal_bridge_width 0.5)
			(island_removal_mode 0)
		)
		(polygon
			(pts
				(xy 50.771552 -270.696944) (xy 50.771552 -270.147288) (xy 51.401472 -270.147288) (xy 51.401472 -270.696944)
			)
		)
	)
	(zone
		(layer "In11.Cu")
		(hatch none 0.5)
		(connect_pads
			(clearance 0)
		)
		(min_thickness 0.25)
		(keepout
			(tracks allowed)
			(vias allowed)
			(pads allowed)
			(copperpour allowed)
			(footprints allowed)
		)
		(placement
			(enabled no)
			(sheetname "")
		)
		(fill
			(thermal_gap 0.5)
			(thermal_bridge_width 0.5)
			(island_removal_mode 0)
		)
		(polygon
			(pts
				(xy 425.11091 -278.864822) (xy 425.11091 -279.140412) (xy 424.55211 -279.140412) (xy 424.55211 -278.864822)
			)
		)
	)
	(zone
		(layer "In11.Cu")
		(hatch none 0.5)
		(connect_pads
			(clearance 0)
		)
		(min_thickness 0.25)
		(keepout
			(tracks allowed)
			(vias allowed)
			(pads allowed)
			(copperpour allowed)
			(footprints allowed)
		)
		(placement
			(enabled no)
			(sheetname "")
		)
		(fill
			(thermal_gap 0.5)
			(thermal_bridge_width 0.5)
			(island_removal_mode 0)
		)
		(polygon
			(pts
				(xy 203.245974 -239.764824) (xy 203.245974 -240.040414) (xy 202.687174 -240.040414) (xy 202.687174 -239.764824)
			)
		)
	)
	(zone
		(layer "In11.Cu")
		(hatch none 0.5)
		(connect_pads
			(clearance 0)
		)
		(min_thickness 0.25)
		(keepout
			(tracks allowed)
			(vias allowed)
			(pads allowed)
			(copperpour allowed)
			(footprints allowed)
		)
		(placement
			(enabled no)
			(sheetname "")
		)
		(fill
			(thermal_gap 0.5)
			(thermal_bridge_width 0.5)
			(island_removal_mode 0)
		)
		(polygon
			(pts
				(xy 425.11091 -227.014786) (xy 425.11091 -227.290376) (xy 424.55211 -227.290376) (xy 424.55211 -227.014786)
			)
		)
	)
	(zone
		(layer "In11.Cu")
		(hatch none 0.5)
		(connect_pads
			(clearance 0)
		)
		(min_thickness 0.25)
		(keepout
			(tracks allowed)
			(vias allowed)
			(pads allowed)
			(copperpour allowed)
			(footprints allowed)
		)
		(placement
			(enabled no)
			(sheetname "")
		)
		(fill
			(thermal_gap 0.5)
			(thermal_bridge_width 0.5)
			(island_removal_mode 0)
		)
		(polygon
			(pts
				(xy 177.170842 -204.914754) (xy 177.170842 -205.190344) (xy 176.612042 -205.190344) (xy 176.612042 -204.914754)
			)
		)
	)
	(zone
		(layer "In11.Cu")
		(hatch none 0.5)
		(connect_pads
			(clearance 0)
		)
		(min_thickness 0.25)
		(keepout
			(tracks allowed)
			(vias allowed)
			(pads allowed)
			(copperpour allowed)
			(footprints allowed)
		)
		(placement
			(enabled no)
			(sheetname "")
		)
		(fill
			(thermal_gap 0.5)
			(thermal_bridge_width 0.5)
			(island_removal_mode 0)
		)
		(polygon
			(pts
				(xy 173.070774 -205.764638) (xy 173.070774 -206.040228) (xy 172.511974 -206.040228) (xy 172.511974 -205.764638)
			)
		)
	)
	(zone
		(layer "In11.Cu")
		(hatch none 0.5)
		(connect_pads
			(clearance 0)
		)
		(min_thickness 0.25)
		(keepout
			(tracks allowed)
			(vias allowed)
			(pads allowed)
			(copperpour allowed)
			(footprints allowed)
		)
		(placement
			(enabled no)
			(sheetname "")
		)
		(fill
			(thermal_gap 0.5)
			(thermal_bridge_width 0.5)
			(island_removal_mode 0)
		)
		(polygon
			(pts
				(xy 84.749894 -291.49675) (xy 84.74964 -285.699454) (xy 84.141818 -285.091632) (xy 84.141818 -284.99943)
				(xy 83.204812 -284.062424) (xy 83.204812 -283.976826) (xy 83.58886 -283.592778) (xy 83.58886 -282.860496)
				(xy 84.462874 -281.986482) (xy 83.37804 -280.901648) (xy 83.37804 -280.701496) (xy 84.035392 -280.044144)
				(xy 84.035392 -280.000456) (xy 83.023964 -278.989028) (xy 83.023964 -278.777192) (xy 82.877406 -278.630634)
				(xy 82.594958 -278.348186) (xy 82.594958 -277.842726) (xy 83.333844 -277.10384) (xy 83.333844 -276.244304)
				(xy 83.288378 -276.198838) (xy 83.052666 -276.198838) (xy 83.0072 -276.153372) (xy 83.0072 -271.340072)
				(xy 82.89544 -271.228312) (xy 82.89544 -260.048248) (xy 83.01355 -259.930138) (xy 83.571842 -259.930138)
				(xy 83.876642 -260.234938) (xy 85.37575 -260.234938) (xy 97.183194 -260.234938) (xy 97.183194 -259.616956)
				(xy 85.37575 -259.616956) (xy 85.37575 -259.587238) (xy 84.143342 -259.587238) (xy 83.747356 -259.191252)
				(xy 82.905854 -259.191252) (xy 82.859118 -259.144516) (xy 82.859118 -255.026414) (xy 82.987134 -254.898398)
				(xy 85.99424 -254.898398) (xy 86.975442 -253.917196) (xy 87.1347 -253.757938) (xy 94.168976 -253.757938)
				(xy 94.168976 -252.579632) (xy 95.183706 -252.579632) (xy 99.04603 -252.579632) (xy 101.00945 -250.616212)
				(xy 101.00945 -250.456954) (xy 101.00945 -249.458734) (xy 100.83419 -249.283474) (xy 98.316542 -249.283474)
				(xy 98.22053 -249.379486) (xy 97.914206 -249.379486) (xy 97.78111 -249.512582) (xy 97.78111 -249.814334)
				(xy 97.7773 -249.818144) (xy 97.7773 -250.115324) (xy 97.22485 -250.667774) (xy 97.00895 -250.883674)
				(xy 94.315026 -250.883674) (xy 94.225872 -250.79452) (xy 94.225872 -249.892566) (xy 94.197424 -249.864118)
				(xy 88.393524 -249.864118) (xy 88.347804 -249.818398) (xy 84.739734 -249.818398) (xy 84.64296 -249.818398)
				(xy 84.603844 -249.779282) (xy 84.603844 -248.966736) (xy 83.642708 -248.966736) (xy 83.59648 -248.920508)
				(xy 83.59648 -241.08664) (xy 83.242912 -240.733072) (xy 83.242912 -240.075466) (xy 83.128866 -239.96142)
				(xy 82.493866 -239.96142) (xy 82.296 -239.763554) (xy 82.296 -225.793046) (xy 82.543142 -225.545904)
				(xy 82.543142 -225.477578) (xy 82.20329 -225.137726) (xy 82.20329 -225.005138) (xy 82.74304 -224.465388)
				(xy 82.74304 -224.318576) (xy 82.231738 -223.807274) (xy 82.231738 -223.70923) (xy 82.716116 -223.224852)
				(xy 82.716116 -222.562928) (xy 82.50555 -222.352362) (xy 82.50555 -221.121224) (xy 83.092544 -220.53423)
				(xy 83.092544 -220.45041) (xy 83.732878 -219.810076) (xy 83.732878 -216.906856) (xy 83.77428 -216.865454)
				(xy 84.74837 -215.891364) (xy 84.74837 -210.893406) (xy 103.738172 -210.893152) (xy 103.739696 -291.496496)
			)
		)
	)
	(zone
		(layer "In11.Cu")
		(hatch none 0.5)
		(connect_pads
			(clearance 0)
		)
		(min_thickness 0.25)
		(keepout
			(tracks allowed)
			(vias allowed)
			(pads allowed)
			(copperpour allowed)
			(footprints allowed)
		)
		(placement
			(enabled no)
			(sheetname "")
		)
		(fill
			(thermal_gap 0.5)
			(thermal_bridge_width 0.5)
			(island_removal_mode 0)
		)
		(polygon
			(pts
				(xy 203.245974 -289.0647) (xy 203.245974 -289.34029) (xy 202.687174 -289.34029) (xy 202.687174 -289.0647)
			)
		)
	)
	(zone
		(layer "In11.Cu")
		(hatch none 0.5)
		(connect_pads
			(clearance 0)
		)
		(min_thickness 0.25)
		(keepout
			(tracks allowed)
			(vias allowed)
			(pads allowed)
			(copperpour allowed)
			(footprints allowed)
		)
		(placement
			(enabled no)
			(sheetname "")
		)
		(fill
			(thermal_gap 0.5)
			(thermal_bridge_width 0.5)
			(island_removal_mode 0)
		)
		(polygon
			(pts
				(xy 268.56436 -303.000664) (xy 268.56436 -302.450246) (xy 269.12316 -302.450246) (xy 269.12316 -303.000664)
			)
		)
	)
	(zone
		(layer "In11.Cu")
		(hatch none 0.5)
		(connect_pads
			(clearance 0)
		)
		(min_thickness 0.25)
		(keepout
			(tracks allowed)
			(vias allowed)
			(pads allowed)
			(copperpour allowed)
			(footprints allowed)
		)
		(placement
			(enabled no)
			(sheetname "")
		)
		(fill
			(thermal_gap 0.5)
			(thermal_bridge_width 0.5)
			(island_removal_mode 0)
		)
		(polygon
			(pts
				(xy 424.561254 -214.36838) (xy 424.561254 -214.09279) (xy 425.120054 -214.09279) (xy 425.120054 -214.36838)
			)
		)
	)
	(zone
		(layer "In11.Cu")
		(hatch none 0.5)
		(connect_pads
			(clearance 0)
		)
		(min_thickness 0.25)
		(keepout
			(tracks allowed)
			(vias allowed)
			(pads allowed)
			(copperpour allowed)
			(footprints allowed)
		)
		(placement
			(enabled no)
			(sheetname "")
		)
		(fill
			(thermal_gap 0.5)
			(thermal_bridge_width 0.5)
			(island_removal_mode 0)
		)
		(polygon
			(pts
				(xy 364.16996 -355.001068) (xy 364.16996 -353.431348) (xy 365.10722 -353.431348) (xy 365.10722 -355.001068)
			)
		)
	)
	(zone
		(layer "In11.Cu")
		(hatch none 0.5)
		(connect_pads
			(clearance 0)
		)
		(min_thickness 0.25)
		(keepout
			(tracks allowed)
			(vias allowed)
			(pads allowed)
			(copperpour allowed)
			(footprints allowed)
		)
		(placement
			(enabled no)
			(sheetname "")
		)
		(fill
			(thermal_gap 0.5)
			(thermal_bridge_width 0.5)
			(island_removal_mode 0)
		)
		(polygon
			(pts
				(xy 450.636386 -250.918472) (xy 450.636386 -250.642882) (xy 451.195186 -250.642882) (xy 451.195186 -250.918472)
			)
		)
	)
	(zone
		(layer "In11.Cu")
		(hatch none 0.5)
		(connect_pads
			(clearance 0)
		)
		(min_thickness 0.25)
		(keepout
			(tracks allowed)
			(vias allowed)
			(pads allowed)
			(copperpour allowed)
			(footprints allowed)
		)
		(placement
			(enabled no)
			(sheetname "")
		)
		(fill
			(thermal_gap 0.5)
			(thermal_bridge_width 0.5)
			(island_removal_mode 0)
		)
		(polygon
			(pts
				(xy 172.521118 -235.618528) (xy 172.521118 -235.342938) (xy 173.079918 -235.342938) (xy 173.079918 -235.618528)
			)
		)
	)
	(zone
		(layer "In11.Cu")
		(hatch none 0.5)
		(connect_pads
			(clearance 0)
		)
		(min_thickness 0.25)
		(keepout
			(tracks allowed)
			(vias allowed)
			(pads allowed)
			(copperpour allowed)
			(footprints allowed)
		)
		(placement
			(enabled no)
			(sheetname "")
		)
		(fill
			(thermal_gap 0.5)
			(thermal_bridge_width 0.5)
			(island_removal_mode 0)
		)
		(polygon
			(pts
				(xy 451.186042 -215.114632) (xy 451.186042 -215.390222) (xy 450.627242 -215.390222) (xy 450.627242 -215.114632)
			)
		)
	)
	(zone
		(layer "In11.Cu")
		(hatch none 0.5)
		(connect_pads
			(clearance 0)
		)
		(min_thickness 0.25)
		(keepout
			(tracks allowed)
			(vias allowed)
			(pads allowed)
			(copperpour allowed)
			(footprints allowed)
		)
		(placement
			(enabled no)
			(sheetname "")
		)
		(fill
			(thermal_gap 0.5)
			(thermal_bridge_width 0.5)
			(island_removal_mode 0)
		)
		(polygon
			(pts
				(xy 298.68622 -227.346764) (xy 298.68622 -226.797108) (xy 299.31614 -226.797108) (xy 299.31614 -227.346764)
			)
		)
	)
	(zone
		(layer "In11.Cu")
		(hatch none 0.5)
		(connect_pads
			(clearance 0)
		)
		(min_thickness 0.25)
		(keepout
			(tracks allowed)
			(vias allowed)
			(pads allowed)
			(copperpour allowed)
			(footprints allowed)
		)
		(placement
			(enabled no)
			(sheetname "")
		)
		(fill
			(thermal_gap 0.5)
			(thermal_bridge_width 0.5)
			(island_removal_mode 0)
		)
		(polygon
			(pts
				(xy 424.561254 -200.768458) (xy 424.561254 -200.492868) (xy 425.120054 -200.492868) (xy 425.120054 -200.768458)
			)
		)
	)
	(zone
		(layer "In11.Cu")
		(hatch none 0.5)
		(connect_pads
			(clearance 0)
		)
		(min_thickness 0.25)
		(keepout
			(tracks allowed)
			(vias allowed)
			(pads allowed)
			(copperpour allowed)
			(footprints allowed)
		)
		(placement
			(enabled no)
			(sheetname "")
		)
		(fill
			(thermal_gap 0.5)
			(thermal_bridge_width 0.5)
			(island_removal_mode 0)
		)
		(polygon
			(pts
				(xy 46.646084 -264.74674) (xy 46.646084 -264.197084) (xy 47.276004 -264.197084) (xy 47.276004 -264.74674)
			)
		)
	)
	(zone
		(layer "In11.Cu")
		(hatch none 0.5)
		(connect_pads
			(clearance 0)
		)
		(min_thickness 0.25)
		(keepout
			(tracks allowed)
			(vias allowed)
			(pads allowed)
			(copperpour allowed)
			(footprints allowed)
		)
		(placement
			(enabled no)
			(sheetname "")
		)
		(fill
			(thermal_gap 0.5)
			(thermal_bridge_width 0.5)
			(island_removal_mode 0)
		)
		(polygon
			(pts
				(xy 50.771552 -278.34717) (xy 50.771552 -277.797514) (xy 51.401472 -277.797514) (xy 51.401472 -278.34717)
			)
		)
	)
	(zone
		(layer "In11.Cu")
		(hatch none 0.5)
		(connect_pads
			(clearance 0)
		)
		(min_thickness 0.25)
		(keepout
			(tracks allowed)
			(vias allowed)
			(pads allowed)
			(copperpour allowed)
			(footprints allowed)
		)
		(placement
			(enabled no)
			(sheetname "")
		)
		(fill
			(thermal_gap 0.5)
			(thermal_bridge_width 0.5)
			(island_removal_mode 0)
		)
		(polygon
			(pts
				(xy 203.245974 -230.41483) (xy 203.245974 -230.69042) (xy 202.687174 -230.69042) (xy 202.687174 -230.41483)
			)
		)
	)
	(zone
		(layer "In11.Cu")
		(hatch none 0.5)
		(connect_pads
			(clearance 0)
		)
		(min_thickness 0.25)
		(keepout
			(tracks allowed)
			(vias allowed)
			(pads allowed)
			(copperpour allowed)
			(footprints allowed)
		)
		(placement
			(enabled no)
			(sheetname "")
		)
		(fill
			(thermal_gap 0.5)
			(thermal_bridge_width 0.5)
			(island_removal_mode 0)
		)
		(polygon
			(pts
				(xy 420.461186 -301.068486) (xy 420.461186 -300.792896) (xy 421.019986 -300.792896) (xy 421.019986 -301.068486)
			)
		)
	)
	(zone
		(layer "In11.Cu")
		(hatch none 0.5)
		(connect_pads
			(clearance 0)
		)
		(min_thickness 0.25)
		(keepout
			(tracks allowed)
			(vias allowed)
			(pads allowed)
			(copperpour allowed)
			(footprints allowed)
		)
		(placement
			(enabled no)
			(sheetname "")
		)
		(fill
			(thermal_gap 0.5)
			(thermal_bridge_width 0.5)
			(island_removal_mode 0)
		)
		(polygon
			(pts
				(xy 20.570952 -203.546964) (xy 20.570952 -202.997308) (xy 21.200872 -202.997308) (xy 21.200872 -203.546964)
			)
		)
	)
	(zone
		(layer "In11.Cu")
		(hatch none 0.5)
		(connect_pads
			(clearance 0)
		)
		(min_thickness 0.25)
		(keepout
			(tracks allowed)
			(vias allowed)
			(pads allowed)
			(copperpour allowed)
			(footprints allowed)
		)
		(placement
			(enabled no)
			(sheetname "")
		)
		(fill
			(thermal_gap 0.5)
			(thermal_bridge_width 0.5)
			(island_removal_mode 0)
		)
		(polygon
			(pts
				(xy 176.621186 -279.818592) (xy 176.621186 -279.543002) (xy 177.179986 -279.543002) (xy 177.179986 -279.818592)
			)
		)
	)
	(zone
		(layer "In11.Cu")
		(hatch none 0.5)
		(connect_pads
			(clearance 0)
		)
		(min_thickness 0.25)
		(keepout
			(tracks allowed)
			(vias allowed)
			(pads allowed)
			(copperpour allowed)
			(footprints allowed)
		)
		(placement
			(enabled no)
			(sheetname "")
		)
		(fill
			(thermal_gap 0.5)
			(thermal_bridge_width 0.5)
			(island_removal_mode 0)
		)
		(polygon
			(pts
				(xy 201.462386 -269.34287) (xy 202.021186 -269.34287) (xy 202.404218 -269.34287) (xy 203.280518 -269.34287)
				(xy 203.280518 -269.85595) (xy 202.404218 -269.85595) (xy 202.404218 -270.24711) (xy 200.946258 -270.24711)
				(xy 200.946258 -269.34287)
			)
		)
	)
	(zone
		(layer "In11.Cu")
		(hatch none 0.5)
		(connect_pads
			(clearance 0)
		)
		(min_thickness 0.25)
		(keepout
			(tracks allowed)
			(vias allowed)
			(pads allowed)
			(copperpour allowed)
			(footprints allowed)
		)
		(placement
			(enabled no)
			(sheetname "")
		)
		(fill
			(thermal_gap 0.5)
			(thermal_bridge_width 0.5)
			(island_removal_mode 0)
		)
		(polygon
			(pts
				(xy 451.186042 -267.814806) (xy 451.186042 -268.090396) (xy 450.627242 -268.090396) (xy 450.06895 -268.090396)
				(xy 450.06895 -267.599414) (xy 451.186042 -267.599414)
			)
		)
	)
	(zone
		(layer "In11.Cu")
		(hatch none 0.5)
		(connect_pads
			(clearance 0)
		)
		(min_thickness 0.25)
		(keepout
			(tracks allowed)
			(vias allowed)
			(pads allowed)
			(copperpour allowed)
			(footprints allowed)
		)
		(placement
			(enabled no)
			(sheetname "")
		)
		(fill
			(thermal_gap 0.5)
			(thermal_bridge_width 0.5)
			(island_removal_mode 0)
		)
		(polygon
			(pts
				(xy 425.11091 -297.56481) (xy 425.11091 -297.8404) (xy 424.55211 -297.8404) (xy 424.55211 -297.56481)
			)
		)
	)
	(zone
		(layer "In11.Cu")
		(hatch none 0.5)
		(connect_pads
			(clearance 0)
		)
		(min_thickness 0.25)
		(keepout
			(tracks allowed)
			(vias allowed)
			(pads allowed)
			(copperpour allowed)
			(footprints allowed)
		)
		(placement
			(enabled no)
			(sheetname "")
		)
		(fill
			(thermal_gap 0.5)
			(thermal_bridge_width 0.5)
			(island_removal_mode 0)
		)
		(polygon
			(pts
				(xy 172.521118 -233.918506) (xy 172.521118 -233.642916) (xy 173.079918 -233.642916) (xy 173.079918 -233.918506)
			)
		)
	)
	(zone
		(layer "In11.Cu")
		(hatch none 0.5)
		(connect_pads
			(clearance 0)
		)
		(min_thickness 0.25)
		(keepout
			(tracks allowed)
			(vias allowed)
			(pads allowed)
			(copperpour allowed)
			(footprints allowed)
		)
		(placement
			(enabled no)
			(sheetname "")
		)
		(fill
			(thermal_gap 0.5)
			(thermal_bridge_width 0.5)
			(island_removal_mode 0)
		)
		(polygon
			(pts
				(xy 176.621186 -277.268432) (xy 176.621186 -276.992842) (xy 177.179986 -276.992842) (xy 177.179986 -277.268432)
			)
		)
	)
	(zone
		(layer "In11.Cu")
		(hatch none 0.5)
		(connect_pads
			(clearance 0)
		)
		(min_thickness 0.25)
		(keepout
			(tracks allowed)
			(vias allowed)
			(pads allowed)
			(copperpour allowed)
			(footprints allowed)
		)
		(placement
			(enabled no)
			(sheetname "")
		)
		(fill
			(thermal_gap 0.5)
			(thermal_bridge_width 0.5)
			(island_removal_mode 0)
		)
		(polygon
			(pts
				(xy 188.158374 -235.514642) (xy 188.158374 -235.790232) (xy 187.599574 -235.790232) (xy 187.599574 -235.514642)
			)
		)
	)
	(zone
		(layer "In11.Cu")
		(hatch none 0.5)
		(connect_pads
			(clearance 0)
		)
		(min_thickness 0.25)
		(keepout
			(tracks allowed)
			(vias allowed)
			(pads allowed)
			(copperpour allowed)
			(footprints allowed)
		)
		(placement
			(enabled no)
			(sheetname "")
		)
		(fill
			(thermal_gap 0.5)
			(thermal_bridge_width 0.5)
			(island_removal_mode 0)
		)
		(polygon
			(pts
				(xy 173.070774 -312.014616) (xy 173.070774 -312.290206) (xy 172.511974 -312.290206) (xy 172.511974 -312.014616)
			)
		)
	)
	(zone
		(layer "In11.Cu")
		(hatch none 0.5)
		(connect_pads
			(clearance 0)
		)
		(min_thickness 0.25)
		(keepout
			(tracks allowed)
			(vias allowed)
			(pads allowed)
			(copperpour allowed)
			(footprints allowed)
		)
		(placement
			(enabled no)
			(sheetname "")
		)
		(fill
			(thermal_gap 0.5)
			(thermal_bridge_width 0.5)
			(island_removal_mode 0)
		)
		(polygon
			(pts
				(xy 432.65471 -267.814806) (xy 432.65471 -268.090396) (xy 432.09591 -268.090396) (xy 432.09591 -267.814806)
			)
		)
	)
	(zone
		(layer "In11.Cu")
		(hatch none 0.5)
		(connect_pads
			(clearance 0)
		)
		(min_thickness 0.25)
		(keepout
			(tracks allowed)
			(vias allowed)
			(pads allowed)
			(copperpour allowed)
			(footprints allowed)
		)
		(placement
			(enabled no)
			(sheetname "")
		)
		(fill
			(thermal_gap 0.5)
			(thermal_bridge_width 0.5)
			(island_removal_mode 0)
		)
		(polygon
			(pts
				(xy 177.170842 -290.764722) (xy 177.170842 -291.040312) (xy 176.612042 -291.040312) (xy 176.612042 -290.764722)
			)
		)
	)
	(zone
		(layer "In11.Cu")
		(hatch none 0.5)
		(connect_pads
			(clearance 0)
		)
		(min_thickness 0.25)
		(keepout
			(tracks allowed)
			(vias allowed)
			(pads allowed)
			(copperpour allowed)
			(footprints allowed)
		)
		(placement
			(enabled no)
			(sheetname "")
		)
		(fill
			(thermal_gap 0.5)
			(thermal_bridge_width 0.5)
			(island_removal_mode 0)
		)
		(polygon
			(pts
				(xy 173.070774 -303.51476) (xy 173.070774 -303.79035) (xy 172.511974 -303.79035) (xy 172.511974 -303.51476)
			)
		)
	)
	(zone
		(layer "In11.Cu")
		(hatch none 0.5)
		(connect_pads
			(clearance 0)
		)
		(min_thickness 0.25)
		(keepout
			(tracks allowed)
			(vias allowed)
			(pads allowed)
			(copperpour allowed)
			(footprints allowed)
		)
		(placement
			(enabled no)
			(sheetname "")
		)
		(fill
			(thermal_gap 0.5)
			(thermal_bridge_width 0.5)
			(island_removal_mode 0)
		)
		(polygon
			(pts
				(xy 173.070774 -292.464744) (xy 173.070774 -292.740334) (xy 172.511974 -292.740334) (xy 172.511974 -292.464744)
			)
		)
	)
	(zone
		(layer "In11.Cu")
		(hatch none 0.5)
		(connect_pads
			(clearance 0)
		)
		(min_thickness 0.25)
		(keepout
			(tracks allowed)
			(vias allowed)
			(pads allowed)
			(copperpour allowed)
			(footprints allowed)
		)
		(placement
			(enabled no)
			(sheetname "")
		)
		(fill
			(thermal_gap 0.5)
			(thermal_bridge_width 0.5)
			(island_removal_mode 0)
		)
		(polygon
			(pts
				(xy 298.71162 -306.396898) (xy 298.71162 -305.847242) (xy 299.34154 -305.847242) (xy 299.34154 -306.396898)
			)
		)
	)
	(zone
		(layer "In11.Cu")
		(hatch none 0.5)
		(connect_pads
			(clearance 0)
		)
		(min_thickness 0.25)
		(keepout
			(tracks allowed)
			(vias allowed)
			(pads allowed)
			(copperpour allowed)
			(footprints allowed)
		)
		(placement
			(enabled no)
			(sheetname "")
		)
		(fill
			(thermal_gap 0.5)
			(thermal_bridge_width 0.5)
			(island_removal_mode 0)
		)
		(polygon
			(pts
				(xy 177.170842 -311.164732) (xy 177.170842 -311.440322) (xy 176.612042 -311.440322) (xy 176.612042 -311.164732)
			)
		)
	)
	(zone
		(layer "In11.Cu")
		(hatch none 0.5)
		(connect_pads
			(clearance 0)
		)
		(min_thickness 0.25)
		(keepout
			(tracks allowed)
			(vias allowed)
			(pads allowed)
			(copperpour allowed)
			(footprints allowed)
		)
		(placement
			(enabled no)
			(sheetname "")
		)
		(fill
			(thermal_gap 0.5)
			(thermal_bridge_width 0.5)
			(island_removal_mode 0)
		)
		(polygon
			(pts
				(xy 177.170842 -302.664622) (xy 177.170842 -302.940212) (xy 176.612042 -302.940212) (xy 176.612042 -302.664622)
			)
		)
	)
	(zone
		(layer "In11.Cu")
		(hatch none 0.5)
		(connect_pads
			(clearance 0)
		)
		(min_thickness 0.25)
		(keepout
			(tracks allowed)
			(vias allowed)
			(pads allowed)
			(copperpour allowed)
			(footprints allowed)
		)
		(placement
			(enabled no)
			(sheetname "")
		)
		(fill
			(thermal_gap 0.5)
			(thermal_bridge_width 0.5)
			(island_removal_mode 0)
		)
		(polygon
			(pts
				(xy 46.646084 -210.346798) (xy 46.646084 -209.797142) (xy 47.276004 -209.797142) (xy 47.276004 -210.346798)
			)
		)
	)
	(zone
		(layer "In11.Cu")
		(hatch none 0.5)
		(connect_pads
			(clearance 0)
		)
		(min_thickness 0.25)
		(keepout
			(tracks allowed)
			(vias allowed)
			(pads allowed)
			(copperpour allowed)
			(footprints allowed)
		)
		(placement
			(enabled no)
			(sheetname "")
		)
		(fill
			(thermal_gap 0.5)
			(thermal_bridge_width 0.5)
			(island_removal_mode 0)
		)
		(polygon
			(pts
				(xy 420.461186 -213.518496) (xy 420.461186 -213.242906) (xy 421.019986 -213.242906) (xy 421.019986 -213.518496)
			)
		)
	)
	(zone
		(layer "In11.Cu")
		(hatch none 0.5)
		(connect_pads
			(clearance 0)
		)
		(min_thickness 0.25)
		(keepout
			(tracks allowed)
			(vias allowed)
			(pads allowed)
			(copperpour allowed)
			(footprints allowed)
		)
		(placement
			(enabled no)
			(sheetname "")
		)
		(fill
			(thermal_gap 0.5)
			(thermal_bridge_width 0.5)
			(island_removal_mode 0)
		)
		(polygon
			(pts
				(xy 424.561254 -231.3686) (xy 424.561254 -231.09301) (xy 425.120054 -231.09301) (xy 425.120054 -231.3686)
			)
		)
	)
	(zone
		(layer "In11.Cu")
		(hatch none 0.5)
		(connect_pads
			(clearance 0)
		)
		(min_thickness 0.25)
		(keepout
			(tracks allowed)
			(vias allowed)
			(pads allowed)
			(copperpour allowed)
			(footprints allowed)
		)
		(placement
			(enabled no)
			(sheetname "")
		)
		(fill
			(thermal_gap 0.5)
			(thermal_bridge_width 0.5)
			(island_removal_mode 0)
		)
		(polygon
			(pts
				(xy 424.561254 -220.318584) (xy 424.561254 -220.042994) (xy 425.120054 -220.042994) (xy 425.120054 -220.318584)
			)
		)
	)
	(zone
		(layer "In11.Cu")
		(hatch none 0.5)
		(connect_pads
			(clearance 0)
		)
		(min_thickness 0.25)
		(keepout
			(tracks allowed)
			(vias allowed)
			(pads allowed)
			(copperpour allowed)
			(footprints allowed)
		)
		(placement
			(enabled no)
			(sheetname "")
		)
		(fill
			(thermal_gap 0.5)
			(thermal_bridge_width 0.5)
			(island_removal_mode 0)
		)
		(polygon
			(pts
				(xy 50.746152 -208.646776) (xy 50.746152 -208.09712) (xy 51.376072 -208.09712) (xy 51.376072 -208.646776)
			)
		)
	)
	(zone
		(layer "In11.Cu")
		(hatch none 0.5)
		(connect_pads
			(clearance 0)
		)
		(min_thickness 0.25)
		(keepout
			(tracks allowed)
			(vias allowed)
			(pads allowed)
			(copperpour allowed)
			(footprints allowed)
		)
		(placement
			(enabled no)
			(sheetname "")
		)
		(fill
			(thermal_gap 0.5)
			(thermal_bridge_width 0.5)
			(island_removal_mode 0)
		)
		(polygon
			(pts
				(xy 176.621186 -202.46848) (xy 176.621186 -202.19289) (xy 177.179986 -202.19289) (xy 177.179986 -202.46848)
			)
		)
	)
	(zone
		(layer "In11.Cu")
		(hatch none 0.5)
		(connect_pads
			(clearance 0)
		)
		(min_thickness 0.25)
		(keepout
			(tracks allowed)
			(vias allowed)
			(pads allowed)
			(copperpour allowed)
			(footprints allowed)
		)
		(placement
			(enabled no)
			(sheetname "")
		)
		(fill
			(thermal_gap 0.5)
			(thermal_bridge_width 0.5)
			(island_removal_mode 0)
		)
		(polygon
			(pts
				(xy 348.1324 -292.992048) (xy 348.1324 -292.080188) (xy 350.18472 -292.080188) (xy 350.18472 -292.992048)
			)
		)
	)
	(zone
		(layer "In11.Cu")
		(hatch none 0.5)
		(connect_pads
			(clearance 0)
		)
		(min_thickness 0.25)
		(keepout
			(tracks allowed)
			(vias allowed)
			(pads allowed)
			(copperpour allowed)
			(footprints allowed)
		)
		(placement
			(enabled no)
			(sheetname "")
		)
		(fill
			(thermal_gap 0.5)
			(thermal_bridge_width 0.5)
			(island_removal_mode 0)
		)
		(polygon
			(pts
				(xy 180.064918 -268.768576) (xy 180.064918 -268.492986) (xy 180.623718 -268.492986) (xy 180.623718 -268.768576)
			)
		)
	)
	(zone
		(layer "In11.Cu")
		(hatch none 0.5)
		(connect_pads
			(clearance 0)
		)
		(min_thickness 0.25)
		(keepout
			(tracks allowed)
			(vias allowed)
			(pads allowed)
			(copperpour allowed)
			(footprints allowed)
		)
		(placement
			(enabled no)
			(sheetname "")
		)
		(fill
			(thermal_gap 0.5)
			(thermal_bridge_width 0.5)
			(island_removal_mode 0)
		)
		(polygon
			(pts
				(xy 20.570952 -225.646742) (xy 20.570952 -225.097086) (xy 21.200872 -225.097086) (xy 21.200872 -225.646742)
			)
		)
	)
	(zone
		(layer "In11.Cu")
		(hatch none 0.5)
		(connect_pads
			(clearance 0)
		)
		(min_thickness 0.25)
		(keepout
			(tracks allowed)
			(vias allowed)
			(pads allowed)
			(copperpour allowed)
			(footprints allowed)
		)
		(placement
			(enabled no)
			(sheetname "")
		)
		(fill
			(thermal_gap 0.5)
			(thermal_bridge_width 0.5)
			(island_removal_mode 0)
		)
		(polygon
			(pts
				(xy 172.521118 -216.91854) (xy 172.521118 -216.64295) (xy 173.079918 -216.64295) (xy 173.079918 -216.91854)
			)
		)
	)
	(zone
		(layer "In11.Cu")
		(hatch none 0.5)
		(connect_pads
			(clearance 0)
		)
		(min_thickness 0.25)
		(keepout
			(tracks allowed)
			(vias allowed)
			(pads allowed)
			(copperpour allowed)
			(footprints allowed)
		)
		(placement
			(enabled no)
			(sheetname "")
		)
		(fill
			(thermal_gap 0.5)
			(thermal_bridge_width 0.5)
			(island_removal_mode 0)
		)
		(polygon
			(pts
				(xy 294.586152 -215.446864) (xy 294.586152 -214.897208) (xy 295.216072 -214.897208) (xy 295.216072 -215.446864)
			)
		)
	)
	(zone
		(layer "In11.Cu")
		(hatch none 0.5)
		(connect_pads
			(clearance 0)
		)
		(min_thickness 0.25)
		(keepout
			(tracks allowed)
			(vias allowed)
			(pads allowed)
			(copperpour allowed)
			(footprints allowed)
		)
		(placement
			(enabled no)
			(sheetname "")
		)
		(fill
			(thermal_gap 0.5)
			(thermal_bridge_width 0.5)
			(island_removal_mode 0)
		)
		(polygon
			(pts
				(xy 116.14912 -355.105208) (xy 116.14912 -353.464368) (xy 117.16004 -353.464368) (xy 117.16004 -355.105208)
			)
		)
	)
	(zone
		(layer "In11.Cu")
		(hatch none 0.5)
		(connect_pads
			(clearance 0)
		)
		(min_thickness 0.25)
		(keepout
			(tracks allowed)
			(vias allowed)
			(pads allowed)
			(copperpour allowed)
			(footprints allowed)
		)
		(placement
			(enabled no)
			(sheetname "")
		)
		(fill
			(thermal_gap 0.5)
			(thermal_bridge_width 0.5)
			(island_removal_mode 0)
		)
		(polygon
			(pts
				(xy 35.696144 -267.319506) (xy 35.696144 -266.737846) (xy 36.254944 -266.737846) (xy 36.254944 -267.319506)
			)
		)
	)
	(zone
		(layer "In11.Cu")
		(hatch none 0.5)
		(connect_pads
			(clearance 0)
		)
		(min_thickness 0.25)
		(keepout
			(tracks allowed)
			(vias allowed)
			(pads allowed)
			(copperpour allowed)
			(footprints allowed)
		)
		(placement
			(enabled no)
			(sheetname "")
		)
		(fill
			(thermal_gap 0.5)
			(thermal_bridge_width 0.5)
			(island_removal_mode 0)
		)
		(polygon
			(pts
				(xy 177.170842 -230.41483) (xy 177.170842 -230.69042) (xy 176.612042 -230.69042) (xy 176.612042 -230.41483)
			)
		)
	)
	(zone
		(layer "In11.Cu")
		(hatch none 0.5)
		(connect_pads
			(clearance 0)
		)
		(min_thickness 0.25)
		(keepout
			(tracks allowed)
			(vias allowed)
			(pads allowed)
			(copperpour allowed)
			(footprints allowed)
		)
		(placement
			(enabled no)
			(sheetname "")
		)
		(fill
			(thermal_gap 0.5)
			(thermal_bridge_width 0.5)
			(island_removal_mode 0)
		)
		(polygon
			(pts
				(xy 20.570952 -205.246732) (xy 20.570952 -204.697076) (xy 21.200872 -204.697076) (xy 21.200872 -205.246732)
			)
		)
	)
	(zone
		(layer "In11.Cu")
		(hatch none 0.5)
		(connect_pads
			(clearance 0)
		)
		(min_thickness 0.25)
		(keepout
			(tracks allowed)
			(vias allowed)
			(pads allowed)
			(copperpour allowed)
			(footprints allowed)
		)
		(placement
			(enabled no)
			(sheetname "")
		)
		(fill
			(thermal_gap 0.5)
			(thermal_bridge_width 0.5)
			(island_removal_mode 0)
		)
		(polygon
			(pts
				(xy 298.71162 -309.796942) (xy 298.71162 -309.247286) (xy 299.34154 -309.247286) (xy 299.34154 -309.796942)
			)
		)
	)
	(zone
		(layer "In11.Cu")
		(hatch none 0.5)
		(connect_pads
			(clearance 0)
		)
		(min_thickness 0.25)
		(keepout
			(tracks allowed)
			(vias allowed)
			(pads allowed)
			(copperpour allowed)
			(footprints allowed)
		)
		(placement
			(enabled no)
			(sheetname "")
		)
		(fill
			(thermal_gap 0.5)
			(thermal_bridge_width 0.5)
			(island_removal_mode 0)
		)
		(polygon
			(pts
				(xy 268.51102 -201.846942) (xy 268.51102 -201.297286) (xy 269.14094 -201.297286) (xy 269.14094 -201.846942)
			)
		)
	)
	(zone
		(layer "In11.Cu")
		(hatch none 0.5)
		(connect_pads
			(clearance 0)
		)
		(min_thickness 0.25)
		(keepout
			(tracks allowed)
			(vias allowed)
			(pads allowed)
			(copperpour allowed)
			(footprints allowed)
		)
		(placement
			(enabled no)
			(sheetname "")
		)
		(fill
			(thermal_gap 0.5)
			(thermal_bridge_width 0.5)
			(island_removal_mode 0)
		)
		(polygon
			(pts
				(xy 450.636386 -289.74288) (xy 451.195186 -289.74288) (xy 451.195186 -290.01847) (xy 451.195186 -290.385754)
				(xy 450.268594 -290.385754) (xy 450.268594 -289.74288)
			)
		)
	)
	(zone
		(layer "In11.Cu")
		(hatch none 0.5)
		(connect_pads
			(clearance 0)
		)
		(min_thickness 0.25)
		(keepout
			(tracks allowed)
			(vias allowed)
			(pads allowed)
			(copperpour allowed)
			(footprints allowed)
		)
		(placement
			(enabled no)
			(sheetname "")
		)
		(fill
			(thermal_gap 0.5)
			(thermal_bridge_width 0.5)
			(island_removal_mode 0)
		)
		(polygon
			(pts
				(xy 451.186042 -227.014786) (xy 451.186042 -227.290376) (xy 450.627242 -227.290376) (xy 450.627242 -227.014786)
			)
		)
	)
	(zone
		(layer "In11.Cu")
		(hatch none 0.5)
		(connect_pads
			(clearance 0)
		)
		(min_thickness 0.25)
		(keepout
			(tracks allowed)
			(vias allowed)
			(pads allowed)
			(copperpour allowed)
			(footprints allowed)
		)
		(placement
			(enabled no)
			(sheetname "")
		)
		(fill
			(thermal_gap 0.5)
			(thermal_bridge_width 0.5)
			(island_removal_mode 0)
		)
		(polygon
			(pts
				(xy 188.158374 -212.564726) (xy 188.158374 -212.840316) (xy 187.599574 -212.840316) (xy 187.599574 -212.564726)
			)
		)
	)
	(zone
		(layer "In11.Cu")
		(hatch none 0.5)
		(connect_pads
			(clearance 0)
		)
		(min_thickness 0.25)
		(keepout
			(tracks allowed)
			(vias allowed)
			(pads allowed)
			(copperpour allowed)
			(footprints allowed)
		)
		(placement
			(enabled no)
			(sheetname "")
		)
		(fill
			(thermal_gap 0.5)
			(thermal_bridge_width 0.5)
			(island_removal_mode 0)
		)
		(polygon
			(pts
				(xy 176.621186 -205.868524) (xy 176.621186 -205.592934) (xy 177.179986 -205.592934) (xy 177.179986 -205.868524)
			)
		)
	)
	(zone
		(layer "In11.Cu")
		(hatch none 0.5)
		(connect_pads
			(clearance 0)
		)
		(min_thickness 0.25)
		(keepout
			(tracks not_allowed)
			(vias allowed)
			(pads allowed)
			(copperpour not_allowed)
			(footprints allowed)
		)
		(placement
			(enabled no)
			(sheetname "")
		)
		(fill
			(thermal_gap 0.5)
			(thermal_bridge_width 0.5)
			(island_removal_mode 0)
		)
		(polygon
			(pts
				(arc
					(start 337.142074 -428.960788)
					(mid 337.164392 -429.01467)
					(end 337.218274 -429.036988)
				)
				(arc
					(start 338.158074 -429.036988)
					(mid 338.211956 -429.01467)
					(end 338.234274 -428.960788)
				)
				(arc
					(start 338.234274 -426.419264)
					(mid 338.211956 -426.365382)
					(end 338.158074 -426.343064)
				)
				(arc
					(start 337.218274 -426.343064)
					(mid 337.164392 -426.365382)
					(end 337.142074 -426.419264)
				)
			)
		)
	)
	(zone
		(layer "In11.Cu")
		(hatch none 0.5)
		(connect_pads
			(clearance 0)
		)
		(min_thickness 0.25)
		(keepout
			(tracks allowed)
			(vias allowed)
			(pads allowed)
			(copperpour allowed)
			(footprints allowed)
		)
		(placement
			(enabled no)
			(sheetname "")
		)
		(fill
			(thermal_gap 0.5)
			(thermal_bridge_width 0.5)
			(island_removal_mode 0)
		)
		(polygon
			(pts
				(xy 50.771552 -309.796942) (xy 50.771552 -309.247286) (xy 51.401472 -309.247286) (xy 51.401472 -309.796942)
			)
		)
	)
	(zone
		(layer "In11.Cu")
		(hatch none 0.5)
		(connect_pads
			(clearance 0)
		)
		(min_thickness 0.25)
		(keepout
			(tracks allowed)
			(vias allowed)
			(pads allowed)
			(copperpour allowed)
			(footprints allowed)
		)
		(placement
			(enabled no)
			(sheetname "")
		)
		(fill
			(thermal_gap 0.5)
			(thermal_bridge_width 0.5)
			(island_removal_mode 0)
		)
		(polygon
			(pts
				(xy 20.624292 -274.950682) (xy 20.624292 -274.400264) (xy 21.183092 -274.400264) (xy 21.183092 -274.950682)
			)
		)
	)
	(zone
		(layer "In11.Cu")
		(hatch none 0.5)
		(connect_pads
			(clearance 0)
		)
		(min_thickness 0.25)
		(keepout
			(tracks allowed)
			(vias allowed)
			(pads allowed)
			(copperpour allowed)
			(footprints allowed)
		)
		(placement
			(enabled no)
			(sheetname "")
		)
		(fill
			(thermal_gap 0.5)
			(thermal_bridge_width 0.5)
			(island_removal_mode 0)
		)
		(polygon
			(pts
				(xy 451.186042 -197.264782) (xy 451.186042 -197.540372) (xy 450.627242 -197.540372) (xy 450.627242 -197.264782)
			)
		)
	)
	(zone
		(layer "In11.Cu")
		(hatch none 0.5)
		(connect_pads
			(clearance 0)
		)
		(min_thickness 0.25)
		(keepout
			(tracks allowed)
			(vias allowed)
			(pads allowed)
			(copperpour allowed)
			(footprints allowed)
		)
		(placement
			(enabled no)
			(sheetname "")
		)
		(fill
			(thermal_gap 0.5)
			(thermal_bridge_width 0.5)
			(island_removal_mode 0)
		)
		(polygon
			(pts
				(xy 50.771552 -263.896856) (xy 50.771552 -263.3472) (xy 51.401472 -263.3472) (xy 51.401472 -263.896856)
			)
		)
	)
	(zone
		(layer "In11.Cu")
		(hatch none 0.5)
		(connect_pads
			(clearance 0)
		)
		(min_thickness 0.25)
		(keepout
			(tracks allowed)
			(vias allowed)
			(pads allowed)
			(copperpour allowed)
			(footprints allowed)
		)
		(placement
			(enabled no)
			(sheetname "")
		)
		(fill
			(thermal_gap 0.5)
			(thermal_bridge_width 0.5)
			(island_removal_mode 0)
		)
		(polygon
			(pts
				(xy 294.586152 -249.446796) (xy 294.586152 -248.89714) (xy 295.216072 -248.89714) (xy 295.216072 -249.446796)
			)
		)
	)
	(zone
		(layer "In11.Cu")
		(hatch none 0.5)
		(connect_pads
			(clearance 0)
		)
		(min_thickness 0.25)
		(keepout
			(tracks allowed)
			(vias allowed)
			(pads allowed)
			(copperpour allowed)
			(footprints allowed)
		)
		(placement
			(enabled no)
			(sheetname "")
		)
		(fill
			(thermal_gap 0.5)
			(thermal_bridge_width 0.5)
			(island_removal_mode 0)
		)
		(polygon
			(pts
				(xy 184.164986 -268.768576) (xy 184.164986 -268.492986) (xy 184.723786 -268.492986) (xy 184.723786 -268.768576)
			)
		)
	)
	(zone
		(layer "In11.Cu")
		(hatch none 0.5)
		(connect_pads
			(clearance 0)
		)
		(min_thickness 0.25)
		(keepout
			(tracks allowed)
			(vias allowed)
			(pads allowed)
			(copperpour allowed)
			(footprints allowed)
		)
		(placement
			(enabled no)
			(sheetname "")
		)
		(fill
			(thermal_gap 0.5)
			(thermal_bridge_width 0.5)
			(island_removal_mode 0)
		)
		(polygon
			(pts
				(xy 202.696318 -305.318414) (xy 202.696318 -305.042824) (xy 203.255118 -305.042824) (xy 203.255118 -305.318414)
			)
		)
	)
	(zone
		(layer "In11.Cu")
		(hatch none 0.5)
		(connect_pads
			(clearance 0)
		)
		(min_thickness 0.25)
		(keepout
			(tracks allowed)
			(vias allowed)
			(pads allowed)
			(copperpour allowed)
			(footprints allowed)
		)
		(placement
			(enabled no)
			(sheetname "")
		)
		(fill
			(thermal_gap 0.5)
			(thermal_bridge_width 0.5)
			(island_removal_mode 0)
		)
		(polygon
			(pts
				(xy 173.070774 -196.414644) (xy 173.070774 -196.690234) (xy 172.511974 -196.690234) (xy 172.511974 -196.414644)
			)
		)
	)
	(zone
		(layer "In11.Cu")
		(hatch none 0.5)
		(connect_pads
			(clearance 0)
		)
		(min_thickness 0.25)
		(keepout
			(tracks allowed)
			(vias allowed)
			(pads allowed)
			(copperpour allowed)
			(footprints allowed)
		)
		(placement
			(enabled no)
			(sheetname "")
		)
		(fill
			(thermal_gap 0.5)
			(thermal_bridge_width 0.5)
			(island_removal_mode 0)
		)
		(polygon
			(pts
				(xy 173.070774 -214.264748) (xy 173.070774 -214.540338) (xy 172.511974 -214.540338) (xy 172.511974 -214.264748)
			)
		)
	)
	(zone
		(layer "In11.Cu")
		(hatch none 0.5)
		(connect_pads
			(clearance 0)
		)
		(min_thickness 0.25)
		(keepout
			(tracks allowed)
			(vias allowed)
			(pads allowed)
			(copperpour allowed)
			(footprints allowed)
		)
		(placement
			(enabled no)
			(sheetname "")
		)
		(fill
			(thermal_gap 0.5)
			(thermal_bridge_width 0.5)
			(island_removal_mode 0)
		)
		(polygon
			(pts
				(xy 425.11091 -280.56459) (xy 425.11091 -280.84018) (xy 424.55211 -280.84018) (xy 424.55211 -280.56459)
			)
		)
	)
	(zone
		(layer "In11.Cu")
		(hatch none 0.5)
		(connect_pads
			(clearance 0)
		)
		(min_thickness 0.25)
		(keepout
			(tracks allowed)
			(vias allowed)
			(pads allowed)
			(copperpour allowed)
			(footprints allowed)
		)
		(placement
			(enabled no)
			(sheetname "")
		)
		(fill
			(thermal_gap 0.5)
			(thermal_bridge_width 0.5)
			(island_removal_mode 0)
		)
		(polygon
			(pts
				(xy 173.070774 -299.264832) (xy 173.070774 -299.540422) (xy 172.511974 -299.540422) (xy 172.511974 -299.264832)
			)
		)
	)
	(zone
		(layer "In11.Cu")
		(hatch none 0.5)
		(connect_pads
			(clearance 0)
		)
		(min_thickness 0.25)
		(keepout
			(tracks allowed)
			(vias allowed)
			(pads allowed)
			(copperpour allowed)
			(footprints allowed)
		)
		(placement
			(enabled no)
			(sheetname "")
		)
		(fill
			(thermal_gap 0.5)
			(thermal_bridge_width 0.5)
			(island_removal_mode 0)
		)
		(polygon
			(pts
				(xy 176.621186 -210.96859) (xy 176.621186 -210.693) (xy 177.179986 -210.693) (xy 177.179986 -210.96859)
			)
		)
	)
	(zone
		(layer "In11.Cu")
		(hatch none 0.5)
		(connect_pads
			(clearance 0)
		)
		(min_thickness 0.25)
		(keepout
			(tracks allowed)
			(vias allowed)
			(pads allowed)
			(copperpour allowed)
			(footprints allowed)
		)
		(placement
			(enabled no)
			(sheetname "")
		)
		(fill
			(thermal_gap 0.5)
			(thermal_bridge_width 0.5)
			(island_removal_mode 0)
		)
		(polygon
			(pts
				(xy 421.010842 -247.414796) (xy 421.010842 -247.690386) (xy 420.452042 -247.690386) (xy 420.452042 -247.414796)
			)
		)
	)
	(zone
		(layer "In11.Cu")
		(hatch none 0.5)
		(connect_pads
			(clearance 0)
		)
		(min_thickness 0.25)
		(keepout
			(tracks allowed)
			(vias allowed)
			(pads allowed)
			(copperpour allowed)
			(footprints allowed)
		)
		(placement
			(enabled no)
			(sheetname "")
		)
		(fill
			(thermal_gap 0.5)
			(thermal_bridge_width 0.5)
			(island_removal_mode 0)
		)
		(polygon
			(pts
				(xy 203.245974 -295.01465) (xy 203.245974 -295.29024) (xy 202.687174 -295.29024) (xy 202.687174 -295.01465)
			)
		)
	)
	(zone
		(layer "In11.Cu")
		(hatch none 0.5)
		(connect_pads
			(clearance 0)
		)
		(min_thickness 0.25)
		(keepout
			(tracks allowed)
			(vias allowed)
			(pads allowed)
			(copperpour allowed)
			(footprints allowed)
		)
		(placement
			(enabled no)
			(sheetname "")
		)
		(fill
			(thermal_gap 0.5)
			(thermal_bridge_width 0.5)
			(island_removal_mode 0)
		)
		(polygon
			(pts
				(xy 203.245974 -284.814772) (xy 203.245974 -285.090362) (xy 202.687174 -285.090362) (xy 202.582018 -285.090362)
				(xy 202.582018 -283.79547) (xy 203.245974 -283.79547)
			)
		)
	)
	(zone
		(layer "In11.Cu")
		(hatch none 0.5)
		(connect_pads
			(clearance 0)
		)
		(min_thickness 0.25)
		(keepout
			(tracks allowed)
			(vias allowed)
			(pads allowed)
			(copperpour allowed)
			(footprints allowed)
		)
		(placement
			(enabled no)
			(sheetname "")
		)
		(fill
			(thermal_gap 0.5)
			(thermal_bridge_width 0.5)
			(island_removal_mode 0)
		)
		(polygon
			(pts
				(xy 202.696318 -240.718594) (xy 202.696318 -240.443004) (xy 203.255118 -240.443004) (xy 203.255118 -240.718594)
			)
		)
	)
	(zone
		(layer "In11.Cu")
		(hatch none 0.5)
		(connect_pads
			(clearance 0)
		)
		(min_thickness 0.25)
		(keepout
			(tracks allowed)
			(vias allowed)
			(pads allowed)
			(copperpour allowed)
			(footprints allowed)
		)
		(placement
			(enabled no)
			(sheetname "")
		)
		(fill
			(thermal_gap 0.5)
			(thermal_bridge_width 0.5)
			(island_removal_mode 0)
		)
		(polygon
			(pts
				(xy 405.923242 -224.464626) (xy 405.923242 -224.740216) (xy 405.364442 -224.740216) (xy 405.364442 -224.464626)
			)
		)
	)
	(zone
		(layer "In11.Cu")
		(hatch none 0.5)
		(connect_pads
			(clearance 0)
		)
		(min_thickness 0.25)
		(keepout
			(tracks allowed)
			(vias allowed)
			(pads allowed)
			(copperpour allowed)
			(footprints allowed)
		)
		(placement
			(enabled no)
			(sheetname "")
		)
		(fill
			(thermal_gap 0.5)
			(thermal_bridge_width 0.5)
			(island_removal_mode 0)
		)
		(polygon
			(pts
				(xy 20.62353 -252.001782) (xy 20.62353 -251.43333) (xy 21.14931 -251.43333) (xy 21.14931 -252.001782)
			)
		)
	)
	(zone
		(layer "In11.Cu")
		(hatch none 0.5)
		(connect_pads
			(clearance 0)
		)
		(min_thickness 0.25)
		(keepout
			(tracks allowed)
			(vias allowed)
			(pads allowed)
			(copperpour allowed)
			(footprints allowed)
		)
		(placement
			(enabled no)
			(sheetname "")
		)
		(fill
			(thermal_gap 0.5)
			(thermal_bridge_width 0.5)
			(island_removal_mode 0)
		)
		(polygon
			(pts
				(xy 173.070774 -274.61464) (xy 173.070774 -274.89023) (xy 172.511974 -274.89023) (xy 172.511974 -274.61464)
			)
		)
	)
	(zone
		(layer "In11.Cu")
		(hatch none 0.5)
		(connect_pads
			(clearance 0)
		)
		(min_thickness 0.25)
		(keepout
			(tracks allowed)
			(vias allowed)
			(pads allowed)
			(copperpour allowed)
			(footprints allowed)
		)
		(placement
			(enabled no)
			(sheetname "")
		)
		(fill
			(thermal_gap 0.5)
			(thermal_bridge_width 0.5)
			(island_removal_mode 0)
		)
		(polygon
			(pts
				(xy 298.71162 -298.746926) (xy 298.71162 -298.19727) (xy 299.34154 -298.19727) (xy 299.34154 -298.746926)
			)
		)
	)
	(zone
		(layer "In11.Cu")
		(hatch none 0.5)
		(connect_pads
			(clearance 0)
		)
		(min_thickness 0.25)
		(keepout
			(tracks allowed)
			(vias allowed)
			(pads allowed)
			(copperpour allowed)
			(footprints allowed)
		)
		(placement
			(enabled no)
			(sheetname "")
		)
		(fill
			(thermal_gap 0.5)
			(thermal_bridge_width 0.5)
			(island_removal_mode 0)
		)
		(polygon
			(pts
				(xy 50.771552 -300.446948) (xy 50.771552 -299.897292) (xy 51.401472 -299.897292) (xy 51.401472 -300.446948)
			)
		)
	)
	(zone
		(layer "In11.Cu")
		(hatch none 0.5)
		(connect_pads
			(clearance 0)
		)
		(min_thickness 0.25)
		(keepout
			(tracks allowed)
			(vias allowed)
			(pads allowed)
			(copperpour allowed)
			(footprints allowed)
		)
		(placement
			(enabled no)
			(sheetname "")
		)
		(fill
			(thermal_gap 0.5)
			(thermal_bridge_width 0.5)
			(island_removal_mode 0)
		)
		(polygon
			(pts
				(xy 177.170842 -287.364678) (xy 177.170842 -287.640268) (xy 176.612042 -287.640268) (xy 176.612042 -287.364678)
			)
		)
	)
	(zone
		(layer "In11.Cu")
		(hatch none 0.5)
		(connect_pads
			(clearance 0)
		)
		(min_thickness 0.25)
		(keepout
			(tracks allowed)
			(vias allowed)
			(pads allowed)
			(copperpour allowed)
			(footprints allowed)
		)
		(placement
			(enabled no)
			(sheetname "")
		)
		(fill
			(thermal_gap 0.5)
			(thermal_bridge_width 0.5)
			(island_removal_mode 0)
		)
		(polygon
			(pts
				(xy 173.070774 -229.564692) (xy 173.070774 -229.840282) (xy 172.511974 -229.840282) (xy 172.511974 -229.564692)
			)
		)
	)
	(zone
		(layer "In11.Cu")
		(hatch none 0.5)
		(connect_pads
			(clearance 0)
		)
		(min_thickness 0.25)
		(keepout
			(tracks allowed)
			(vias allowed)
			(pads allowed)
			(copperpour allowed)
			(footprints allowed)
		)
		(placement
			(enabled no)
			(sheetname "")
		)
		(fill
			(thermal_gap 0.5)
			(thermal_bridge_width 0.5)
			(island_removal_mode 0)
		)
		(polygon
			(pts
				(xy 298.71162 -276.647148) (xy 298.71162 -276.097492) (xy 299.34154 -276.097492) (xy 299.34154 -276.647148)
			)
		)
	)
	(zone
		(layer "In11.Cu")
		(hatch none 0.5)
		(connect_pads
			(clearance 0)
		)
		(min_thickness 0.25)
		(keepout
			(tracks allowed)
			(vias allowed)
			(pads allowed)
			(copperpour allowed)
			(footprints allowed)
		)
		(placement
			(enabled no)
			(sheetname "")
		)
		(fill
			(thermal_gap 0.5)
			(thermal_bridge_width 0.5)
			(island_removal_mode 0)
		)
		(polygon
			(pts
				(xy 180.614574 -267.814806) (xy 180.614574 -268.090396) (xy 180.055774 -268.090396) (xy 180.055774 -267.814806)
			)
		)
	)
	(zone
		(layer "In11.Cu")
		(hatch none 0.5)
		(connect_pads
			(clearance 0)
		)
		(min_thickness 0.25)
		(keepout
			(tracks allowed)
			(vias allowed)
			(pads allowed)
			(copperpour allowed)
			(footprints allowed)
		)
		(placement
			(enabled no)
			(sheetname "")
		)
		(fill
			(thermal_gap 0.5)
			(thermal_bridge_width 0.5)
			(island_removal_mode 0)
		)
		(polygon
			(pts
				(xy 46.646084 -206.09687) (xy 46.646084 -205.547214) (xy 47.276004 -205.547214) (xy 47.276004 -206.09687)
			)
		)
	)
	(zone
		(layer "In11.Cu")
		(hatch none 0.5)
		(connect_pads
			(clearance 0)
		)
		(min_thickness 0.25)
		(keepout
			(tracks allowed)
			(vias allowed)
			(pads allowed)
			(copperpour allowed)
			(footprints allowed)
		)
		(placement
			(enabled no)
			(sheetname "")
		)
		(fill
			(thermal_gap 0.5)
			(thermal_bridge_width 0.5)
			(island_removal_mode 0)
		)
		(polygon
			(pts
				(xy 202.696318 -233.918506) (xy 202.696318 -233.642916) (xy 203.255118 -233.642916) (xy 203.255118 -233.918506)
			)
		)
	)
	(zone
		(layer "In11.Cu")
		(hatch none 0.5)
		(connect_pads
			(clearance 0)
		)
		(min_thickness 0.25)
		(keepout
			(tracks allowed)
			(vias allowed)
			(pads allowed)
			(copperpour allowed)
			(footprints allowed)
		)
		(placement
			(enabled no)
			(sheetname "")
		)
		(fill
			(thermal_gap 0.5)
			(thermal_bridge_width 0.5)
			(island_removal_mode 0)
		)
		(polygon
			(pts
				(xy 451.186042 -278.014684) (xy 451.186042 -278.290274) (xy 450.627242 -278.290274) (xy 450.627242 -278.014684)
			)
		)
	)
	(zone
		(layer "In11.Cu")
		(hatch none 0.5)
		(connect_pads
			(clearance 0)
		)
		(min_thickness 0.25)
		(keepout
			(tracks allowed)
			(vias allowed)
			(pads allowed)
			(copperpour allowed)
			(footprints allowed)
		)
		(placement
			(enabled no)
			(sheetname "")
		)
		(fill
			(thermal_gap 0.5)
			(thermal_bridge_width 0.5)
			(island_removal_mode 0)
		)
		(polygon
			(pts
				(xy 421.010842 -282.264612) (xy 421.010842 -282.540202) (xy 420.452042 -282.540202) (xy 420.452042 -282.264612)
			)
		)
	)
	(zone
		(layer "In11.Cu")
		(hatch none 0.5)
		(connect_pads
			(clearance 0)
		)
		(min_thickness 0.25)
		(keepout
			(tracks allowed)
			(vias allowed)
			(pads allowed)
			(copperpour allowed)
			(footprints allowed)
		)
		(placement
			(enabled no)
			(sheetname "")
		)
		(fill
			(thermal_gap 0.5)
			(thermal_bridge_width 0.5)
			(island_removal_mode 0)
		)
		(polygon
			(pts
				(xy 294.586152 -207.796892) (xy 294.586152 -207.247236) (xy 295.216072 -207.247236) (xy 295.216072 -207.796892)
			)
		)
	)
	(zone
		(layer "In11.Cu")
		(hatch none 0.5)
		(connect_pads
			(clearance 0)
		)
		(min_thickness 0.25)
		(keepout
			(tracks allowed)
			(vias allowed)
			(pads allowed)
			(copperpour allowed)
			(footprints allowed)
		)
		(placement
			(enabled no)
			(sheetname "")
		)
		(fill
			(thermal_gap 0.5)
			(thermal_bridge_width 0.5)
			(island_removal_mode 0)
		)
		(polygon
			(pts
				(xy 173.070774 -271.21485) (xy 173.070774 -271.49044) (xy 172.511974 -271.49044) (xy 172.511974 -271.21485)
			)
		)
	)
	(zone
		(layer "In11.Cu")
		(hatch none 0.5)
		(connect_pads
			(clearance 0)
		)
		(min_thickness 0.25)
		(keepout
			(tracks allowed)
			(vias allowed)
			(pads allowed)
			(copperpour allowed)
			(footprints allowed)
		)
		(placement
			(enabled no)
			(sheetname "")
		)
		(fill
			(thermal_gap 0.5)
			(thermal_bridge_width 0.5)
			(island_removal_mode 0)
		)
		(polygon
			(pts
				(xy 432.65471 -266.114784) (xy 432.65471 -266.390374) (xy 432.09591 -266.390374) (xy 432.09591 -266.114784)
			)
		)
	)
	(zone
		(layer "In11.Cu")
		(hatch none 0.5)
		(connect_pads
			(clearance 0)
		)
		(min_thickness 0.25)
		(keepout
			(tracks allowed)
			(vias allowed)
			(pads allowed)
			(copperpour allowed)
			(footprints allowed)
		)
		(placement
			(enabled no)
			(sheetname "")
		)
		(fill
			(thermal_gap 0.5)
			(thermal_bridge_width 0.5)
			(island_removal_mode 0)
		)
		(polygon
			(pts
				(xy 46.646084 -313.196732) (xy 46.646084 -312.647076) (xy 47.276004 -312.647076) (xy 47.276004 -313.196732)
			)
		)
	)
	(zone
		(layer "In11.Cu")
		(hatch none 0.5)
		(connect_pads
			(clearance 0)
		)
		(min_thickness 0.25)
		(keepout
			(tracks allowed)
			(vias allowed)
			(pads allowed)
			(copperpour allowed)
			(footprints allowed)
		)
		(placement
			(enabled no)
			(sheetname "")
		)
		(fill
			(thermal_gap 0.5)
			(thermal_bridge_width 0.5)
			(island_removal_mode 0)
		)
		(polygon
			(pts
				(xy 421.010842 -300.114716) (xy 421.010842 -300.390306) (xy 420.452042 -300.390306) (xy 420.452042 -300.114716)
			)
		)
	)
	(zone
		(layer "In11.Cu")
		(hatch none 0.5)
		(connect_pads
			(clearance 0)
		)
		(min_thickness 0.25)
		(keepout
			(tracks allowed)
			(vias allowed)
			(pads allowed)
			(copperpour allowed)
			(footprints allowed)
		)
		(placement
			(enabled no)
			(sheetname "")
		)
		(fill
			(thermal_gap 0.5)
			(thermal_bridge_width 0.5)
			(island_removal_mode 0)
		)
		(polygon
			(pts
				(xy 188.158374 -277.1648) (xy 188.158374 -277.44039) (xy 187.599574 -277.44039) (xy 187.599574 -277.1648)
			)
		)
	)
	(zone
		(layer "In11.Cu")
		(hatch none 0.5)
		(connect_pads
			(clearance 0)
		)
		(min_thickness 0.25)
		(keepout
			(tracks allowed)
			(vias allowed)
			(pads allowed)
			(copperpour allowed)
			(footprints allowed)
		)
		(placement
			(enabled no)
			(sheetname "")
		)
		(fill
			(thermal_gap 0.5)
			(thermal_bridge_width 0.5)
			(island_removal_mode 0)
		)
		(polygon
			(pts
				(xy 172.521118 -197.368414) (xy 172.521118 -197.092824) (xy 173.079918 -197.092824) (xy 173.079918 -197.368414)
			)
		)
	)
	(zone
		(layer "In11.Cu")
		(hatch none 0.5)
		(connect_pads
			(clearance 0)
		)
		(min_thickness 0.25)
		(keepout
			(tracks allowed)
			(vias allowed)
			(pads allowed)
			(copperpour allowed)
			(footprints allowed)
		)
		(placement
			(enabled no)
			(sheetname "")
		)
		(fill
			(thermal_gap 0.5)
			(thermal_bridge_width 0.5)
			(island_removal_mode 0)
		)
		(polygon
			(pts
				(xy 432.105054 -268.768576) (xy 432.105054 -268.492986) (xy 432.663854 -268.492986) (xy 432.663854 -268.768576)
			)
		)
	)
	(zone
		(layer "In11.Cu")
		(hatch none 0.5)
		(connect_pads
			(clearance 0)
		)
		(min_thickness 0.25)
		(keepout
			(tracks allowed)
			(vias allowed)
			(pads allowed)
			(copperpour allowed)
			(footprints allowed)
		)
		(placement
			(enabled no)
			(sheetname "")
		)
		(fill
			(thermal_gap 0.5)
			(thermal_bridge_width 0.5)
			(island_removal_mode 0)
		)
		(polygon
			(pts
				(xy 420.461186 -295.118536) (xy 420.461186 -294.842946) (xy 421.019986 -294.842946) (xy 421.019986 -295.118536)
			)
		)
	)
	(zone
		(layer "In11.Cu")
		(hatch none 0.5)
		(connect_pads
			(clearance 0)
		)
		(min_thickness 0.25)
		(keepout
			(tracks allowed)
			(vias allowed)
			(pads allowed)
			(copperpour allowed)
			(footprints allowed)
		)
		(placement
			(enabled no)
			(sheetname "")
		)
		(fill
			(thermal_gap 0.5)
			(thermal_bridge_width 0.5)
			(island_removal_mode 0)
		)
		(polygon
			(pts
				(xy 268.56436 -283.450538) (xy 268.56436 -282.90012) (xy 269.12316 -282.90012) (xy 269.12316 -283.450538)
			)
		)
	)
	(zone
		(layer "In11.Cu")
		(hatch none 0.5)
		(connect_pads
			(clearance 0)
		)
		(min_thickness 0.25)
		(keepout
			(tracks allowed)
			(vias allowed)
			(pads allowed)
			(copperpour allowed)
			(footprints allowed)
		)
		(placement
			(enabled no)
			(sheetname "")
		)
		(fill
			(thermal_gap 0.5)
			(thermal_bridge_width 0.5)
			(island_removal_mode 0)
		)
		(polygon
			(pts
				(xy 50.771552 -283.446982) (xy 50.771552 -282.897326) (xy 51.401472 -282.897326) (xy 51.401472 -283.446982)
			)
		)
	)
	(zone
		(layer "In11.Cu")
		(hatch none 0.5)
		(connect_pads
			(clearance 0)
		)
		(min_thickness 0.25)
		(keepout
			(tracks allowed)
			(vias allowed)
			(pads allowed)
			(copperpour allowed)
			(footprints allowed)
		)
		(placement
			(enabled no)
			(sheetname "")
		)
		(fill
			(thermal_gap 0.5)
			(thermal_bridge_width 0.5)
			(island_removal_mode 0)
		)
		(polygon
			(pts
				(xy 172.521118 -284.918404) (xy 172.521118 -284.642814) (xy 173.079918 -284.642814) (xy 173.079918 -284.918404)
			)
		)
	)
	(zone
		(layer "In11.Cu")
		(hatch none 0.5)
		(connect_pads
			(clearance 0)
		)
		(min_thickness 0.25)
		(keepout
			(tracks allowed)
			(vias allowed)
			(pads allowed)
			(copperpour allowed)
			(footprints allowed)
		)
		(placement
			(enabled no)
			(sheetname "")
		)
		(fill
			(thermal_gap 0.5)
			(thermal_bridge_width 0.5)
			(island_removal_mode 0)
		)
		(polygon
			(pts
				(xy 424.561254 -259.418582) (xy 424.561254 -259.142992) (xy 425.120054 -259.142992) (xy 425.120054 -259.418582)
			)
		)
	)
	(zone
		(layer "In11.Cu")
		(hatch none 0.5)
		(connect_pads
			(clearance 0)
		)
		(min_thickness 0.25)
		(keepout
			(tracks allowed)
			(vias allowed)
			(pads allowed)
			(copperpour allowed)
			(footprints allowed)
		)
		(placement
			(enabled no)
			(sheetname "")
		)
		(fill
			(thermal_gap 0.5)
			(thermal_bridge_width 0.5)
			(island_removal_mode 0)
		)
		(polygon
			(pts
				(xy 176.621186 -313.818524) (xy 176.621186 -313.542934) (xy 177.179986 -313.542934) (xy 177.179986 -313.818524)
			)
		)
	)
	(zone
		(layer "In11.Cu")
		(hatch none 0.5)
		(connect_pads
			(clearance 0)
		)
		(min_thickness 0.25)
		(keepout
			(tracks allowed)
			(vias allowed)
			(pads allowed)
			(copperpour allowed)
			(footprints allowed)
		)
		(placement
			(enabled no)
			(sheetname "")
		)
		(fill
			(thermal_gap 0.5)
			(thermal_bridge_width 0.5)
			(island_removal_mode 0)
		)
		(polygon
			(pts
				(xy 172.444918 -264.518394) (xy 172.444918 -264.242804) (xy 173.003718 -264.242804) (xy 173.003718 -264.518394)
			)
		)
	)
	(zone
		(layer "In11.Cu")
		(hatch none 0.5)
		(connect_pads
			(clearance 0)
		)
		(min_thickness 0.25)
		(keepout
			(tracks allowed)
			(vias allowed)
			(pads allowed)
			(copperpour allowed)
			(footprints allowed)
		)
		(placement
			(enabled no)
			(sheetname "")
		)
		(fill
			(thermal_gap 0.5)
			(thermal_bridge_width 0.5)
			(island_removal_mode 0)
		)
		(polygon
			(pts
				(xy 177.170842 -211.714842) (xy 177.170842 -211.990432) (xy 176.612042 -211.990432) (xy 176.612042 -211.714842)
			)
		)
	)
	(zone
		(layer "In11.Cu")
		(hatch none 0.5)
		(connect_pads
			(clearance 0)
		)
		(min_thickness 0.25)
		(keepout
			(tracks allowed)
			(vias allowed)
			(pads allowed)
			(copperpour allowed)
			(footprints allowed)
		)
		(placement
			(enabled no)
			(sheetname "")
		)
		(fill
			(thermal_gap 0.5)
			(thermal_bridge_width 0.5)
			(island_removal_mode 0)
		)
		(polygon
			(pts
				(xy 50.746152 -220.54693) (xy 50.746152 -219.997274) (xy 51.376072 -219.997274) (xy 51.376072 -220.54693)
			)
		)
	)
	(zone
		(layer "In11.Cu")
		(hatch none 0.5)
		(connect_pads
			(clearance 0)
		)
		(min_thickness 0.25)
		(keepout
			(tracks allowed)
			(vias allowed)
			(pads allowed)
			(copperpour allowed)
			(footprints allowed)
		)
		(placement
			(enabled no)
			(sheetname "")
		)
		(fill
			(thermal_gap 0.5)
			(thermal_bridge_width 0.5)
			(island_removal_mode 0)
		)
		(polygon
			(pts
				(xy 298.68622 -200.14692) (xy 298.68622 -199.597264) (xy 299.31614 -199.597264) (xy 299.31614 -200.14692)
			)
		)
	)
	(zone
		(layer "In11.Cu")
		(hatch none 0.5)
		(connect_pads
			(clearance 0)
		)
		(min_thickness 0.25)
		(keepout
			(tracks allowed)
			(vias allowed)
			(pads allowed)
			(copperpour allowed)
			(footprints allowed)
		)
		(placement
			(enabled no)
			(sheetname "")
		)
		(fill
			(thermal_gap 0.5)
			(thermal_bridge_width 0.5)
			(island_removal_mode 0)
		)
		(polygon
			(pts
				(xy 409.473654 -226.268534) (xy 409.473654 -225.992944) (xy 410.032454 -225.992944) (xy 410.032454 -226.268534)
			)
		)
	)
	(zone
		(layer "In11.Cu")
		(hatch none 0.5)
		(connect_pads
			(clearance 0)
		)
		(min_thickness 0.25)
		(keepout
			(tracks allowed)
			(vias allowed)
			(pads allowed)
			(copperpour allowed)
			(footprints allowed)
		)
		(placement
			(enabled no)
			(sheetname "")
		)
		(fill
			(thermal_gap 0.5)
			(thermal_bridge_width 0.5)
			(island_removal_mode 0)
		)
		(polygon
			(pts
				(xy 202.696318 -282.092908) (xy 203.255118 -282.092908) (xy 203.255118 -282.368498) (xy 202.696318 -282.368498)
				(xy 202.400916 -282.368498) (xy 202.400916 -282.883356) (xy 201.771504 -282.883356) (xy 201.771504 -282.092908)
				(xy 202.400916 -282.092908)
			)
		)
	)
	(zone
		(layer "In11.Cu")
		(hatch none 0.5)
		(connect_pads
			(clearance 0)
		)
		(min_thickness 0.25)
		(keepout
			(tracks allowed)
			(vias allowed)
			(pads allowed)
			(copperpour allowed)
			(footprints allowed)
		)
		(placement
			(enabled no)
			(sheetname "")
		)
		(fill
			(thermal_gap 0.5)
			(thermal_bridge_width 0.5)
			(island_removal_mode 0)
		)
		(polygon
			(pts
				(xy 298.68622 -228.196902) (xy 298.68622 -227.647246) (xy 299.31614 -227.647246) (xy 299.31614 -228.196902)
			)
		)
	)
	(zone
		(layer "In11.Cu")
		(hatch none 0.5)
		(connect_pads
			(clearance 0)
		)
		(min_thickness 0.25)
		(keepout
			(tracks allowed)
			(vias allowed)
			(pads allowed)
			(copperpour allowed)
			(footprints allowed)
		)
		(placement
			(enabled no)
			(sheetname "")
		)
		(fill
			(thermal_gap 0.5)
			(thermal_bridge_width 0.5)
			(island_removal_mode 0)
		)
		(polygon
			(pts
				(xy 425.11091 -260.164834) (xy 425.11091 -260.440424) (xy 424.55211 -260.440424) (xy 424.55211 -260.164834)
			)
		)
	)
	(zone
		(layer "In11.Cu")
		(hatch none 0.5)
		(connect_pads
			(clearance 0)
		)
		(min_thickness 0.25)
		(keepout
			(tracks allowed)
			(vias allowed)
			(pads allowed)
			(copperpour allowed)
			(footprints allowed)
		)
		(placement
			(enabled no)
			(sheetname "")
		)
		(fill
			(thermal_gap 0.5)
			(thermal_bridge_width 0.5)
			(island_removal_mode 0)
		)
		(polygon
			(pts
				(xy 421.010842 -240.614708) (xy 421.010842 -240.890298) (xy 420.452042 -240.890298) (xy 420.452042 -240.614708)
			)
		)
	)
	(zone
		(layer "In11.Cu")
		(hatch none 0.5)
		(connect_pads
			(clearance 0)
		)
		(min_thickness 0.25)
		(keepout
			(tracks allowed)
			(vias allowed)
			(pads allowed)
			(copperpour allowed)
			(footprints allowed)
		)
		(placement
			(enabled no)
			(sheetname "")
		)
		(fill
			(thermal_gap 0.5)
			(thermal_bridge_width 0.5)
			(island_removal_mode 0)
		)
		(polygon
			(pts
				(xy 439.648854 -210.118452) (xy 439.648854 -209.842862) (xy 440.207654 -209.842862) (xy 440.207654 -210.118452)
			)
		)
	)
	(zone
		(layer "In11.Cu")
		(hatch none 0.5)
		(connect_pads
			(clearance 0)
		)
		(min_thickness 0.25)
		(keepout
			(tracks allowed)
			(vias allowed)
			(pads allowed)
			(copperpour allowed)
			(footprints allowed)
		)
		(placement
			(enabled no)
			(sheetname "")
		)
		(fill
			(thermal_gap 0.5)
			(thermal_bridge_width 0.5)
			(island_removal_mode 0)
		)
		(polygon
			(pts
				(xy 458.729842 -266.964668) (xy 458.729842 -267.240258) (xy 458.171042 -267.240258) (xy 458.171042 -266.964668)
			)
		)
	)
	(zone
		(layer "In11.Cu")
		(hatch none 0.5)
		(connect_pads
			(clearance 0)
		)
		(min_thickness 0.25)
		(keepout
			(tracks allowed)
			(vias allowed)
			(pads allowed)
			(copperpour allowed)
			(footprints allowed)
		)
		(placement
			(enabled no)
			(sheetname "")
		)
		(fill
			(thermal_gap 0.5)
			(thermal_bridge_width 0.5)
			(island_removal_mode 0)
		)
		(polygon
			(pts
				(xy 173.070774 -219.364814) (xy 173.070774 -219.640404) (xy 172.511974 -219.640404) (xy 172.511974 -219.364814)
			)
		)
	)
	(zone
		(layer "In11.Cu")
		(hatch none 0.5)
		(connect_pads
			(clearance 0)
		)
		(min_thickness 0.25)
		(keepout
			(tracks allowed)
			(vias allowed)
			(pads allowed)
			(copperpour allowed)
			(footprints allowed)
		)
		(placement
			(enabled no)
			(sheetname "")
		)
		(fill
			(thermal_gap 0.5)
			(thermal_bridge_width 0.5)
			(island_removal_mode 0)
		)
		(polygon
			(pts
				(xy 425.11091 -221.064836) (xy 425.11091 -221.340426) (xy 424.55211 -221.340426) (xy 424.55211 -221.064836)
			)
		)
	)
	(zone
		(layer "In11.Cu")
		(hatch none 0.5)
		(connect_pads
			(clearance 0)
		)
		(min_thickness 0.25)
		(keepout
			(tracks allowed)
			(vias allowed)
			(pads allowed)
			(copperpour allowed)
			(footprints allowed)
		)
		(placement
			(enabled no)
			(sheetname "")
		)
		(fill
			(thermal_gap 0.5)
			(thermal_bridge_width 0.5)
			(island_removal_mode 0)
		)
		(polygon
			(pts
				(xy 20.624292 -306.400708) (xy 20.624292 -305.85029) (xy 21.183092 -305.85029) (xy 21.183092 -306.400708)
			)
		)
	)
	(zone
		(layer "In11.Cu")
		(hatch none 0.5)
		(connect_pads
			(clearance 0)
		)
		(min_thickness 0.25)
		(keepout
			(tracks allowed)
			(vias allowed)
			(pads allowed)
			(copperpour allowed)
			(footprints allowed)
		)
		(placement
			(enabled no)
			(sheetname "")
		)
		(fill
			(thermal_gap 0.5)
			(thermal_bridge_width 0.5)
			(island_removal_mode 0)
		)
		(polygon
			(pts
				(xy 450.636386 -229.668578) (xy 450.636386 -229.392988) (xy 451.195186 -229.392988) (xy 451.195186 -229.668578)
			)
		)
	)
	(zone
		(layer "In11.Cu")
		(hatch none 0.5)
		(connect_pads
			(clearance 0)
		)
		(min_thickness 0.25)
		(keepout
			(tracks allowed)
			(vias allowed)
			(pads allowed)
			(copperpour allowed)
			(footprints allowed)
		)
		(placement
			(enabled no)
			(sheetname "")
		)
		(fill
			(thermal_gap 0.5)
			(thermal_bridge_width 0.5)
			(island_removal_mode 0)
		)
		(polygon
			(pts
				(xy 294.586152 -301.296832) (xy 294.586152 -300.747176) (xy 295.216072 -300.747176) (xy 295.216072 -301.296832)
			)
		)
	)
	(zone
		(layer "In11.Cu")
		(hatch none 0.5)
		(connect_pads
			(clearance 0)
		)
		(min_thickness 0.25)
		(keepout
			(tracks allowed)
			(vias allowed)
			(pads allowed)
			(copperpour allowed)
			(footprints allowed)
		)
		(placement
			(enabled no)
			(sheetname "")
		)
		(fill
			(thermal_gap 0.5)
			(thermal_bridge_width 0.5)
			(island_removal_mode 0)
		)
		(polygon
			(pts
				(xy 421.010842 -202.364848) (xy 421.010842 -202.640438) (xy 420.452042 -202.640438) (xy 420.452042 -202.364848)
			)
		)
	)
	(zone
		(layer "In11.Cu")
		(hatch none 0.5)
		(connect_pads
			(clearance 0)
		)
		(min_thickness 0.25)
		(keepout
			(tracks allowed)
			(vias allowed)
			(pads allowed)
			(copperpour allowed)
			(footprints allowed)
		)
		(placement
			(enabled no)
			(sheetname "")
		)
		(fill
			(thermal_gap 0.5)
			(thermal_bridge_width 0.5)
			(island_removal_mode 0)
		)
		(polygon
			(pts
				(xy 440.19851 -261.864856) (xy 440.19851 -262.140446) (xy 439.63971 -262.140446) (xy 439.63971 -261.864856)
			)
		)
	)
	(zone
		(layer "In11.Cu")
		(hatch none 0.5)
		(connect_pads
			(clearance 0)
		)
		(min_thickness 0.25)
		(keepout
			(tracks allowed)
			(vias allowed)
			(pads allowed)
			(copperpour allowed)
			(footprints allowed)
		)
		(placement
			(enabled no)
			(sheetname "")
		)
		(fill
			(thermal_gap 0.5)
			(thermal_bridge_width 0.5)
			(island_removal_mode 0)
		)
		(polygon
			(pts
				(xy 172.521118 -250.068588) (xy 172.521118 -249.792998) (xy 173.079918 -249.792998) (xy 173.079918 -250.068588)
			)
		)
	)
	(zone
		(layer "In11.Cu")
		(hatch none 0.5)
		(connect_pads
			(clearance 0)
		)
		(min_thickness 0.25)
		(keepout
			(tracks allowed)
			(vias allowed)
			(pads allowed)
			(copperpour allowed)
			(footprints allowed)
		)
		(placement
			(enabled no)
			(sheetname "")
		)
		(fill
			(thermal_gap 0.5)
			(thermal_bridge_width 0.5)
			(island_removal_mode 0)
		)
		(polygon
			(pts
				(xy 176.621186 -307.018436) (xy 176.621186 -306.742846) (xy 177.179986 -306.742846) (xy 177.179986 -307.018436)
			)
		)
	)
	(zone
		(layer "In11.Cu")
		(hatch none 0.5)
		(connect_pads
			(clearance 0)
		)
		(min_thickness 0.25)
		(keepout
			(tracks allowed)
			(vias allowed)
			(pads allowed)
			(copperpour allowed)
			(footprints allowed)
		)
		(placement
			(enabled no)
			(sheetname "")
		)
		(fill
			(thermal_gap 0.5)
			(thermal_bridge_width 0.5)
			(island_removal_mode 0)
		)
		(polygon
			(pts
				(xy 172.521118 -224.568512) (xy 172.521118 -224.292922) (xy 173.079918 -224.292922) (xy 173.079918 -224.568512)
			)
		)
	)
	(zone
		(layer "In11.Cu")
		(hatch none 0.5)
		(connect_pads
			(clearance 0)
		)
		(min_thickness 0.25)
		(keepout
			(tracks not_allowed)
			(vias allowed)
			(pads allowed)
			(copperpour not_allowed)
			(footprints allowed)
		)
		(placement
			(enabled no)
			(sheetname "")
		)
		(fill
			(thermal_gap 0.5)
			(thermal_bridge_width 0.5)
			(island_removal_mode 0)
		)
		(polygon
			(pts
				(arc
					(start 333.142082 -428.960788)
					(mid 333.1644 -429.01467)
					(end 333.218282 -429.036988)
				)
				(arc
					(start 334.158082 -429.036988)
					(mid 334.211964 -429.01467)
					(end 334.234282 -428.960788)
				)
				(arc
					(start 334.234282 -426.419264)
					(mid 334.211964 -426.365382)
					(end 334.158082 -426.343064)
				)
				(arc
					(start 333.218282 -426.343064)
					(mid 333.1644 -426.365382)
					(end 333.142082 -426.419264)
				)
			)
		)
	)
	(zone
		(layer "In11.Cu")
		(hatch none 0.5)
		(connect_pads
			(clearance 0)
		)
		(min_thickness 0.25)
		(keepout
			(tracks allowed)
			(vias allowed)
			(pads allowed)
			(copperpour allowed)
			(footprints allowed)
		)
		(placement
			(enabled no)
			(sheetname "")
		)
		(fill
			(thermal_gap 0.5)
			(thermal_bridge_width 0.5)
			(island_removal_mode 0)
		)
		(polygon
			(pts
				(xy 46.646084 -221.396814) (xy 46.646084 -220.847158) (xy 47.276004 -220.847158) (xy 47.276004 -221.396814)
			)
		)
	)
	(zone
		(layer "In11.Cu")
		(hatch none 0.5)
		(connect_pads
			(clearance 0)
		)
		(min_thickness 0.25)
		(keepout
			(tracks allowed)
			(vias allowed)
			(pads allowed)
			(copperpour allowed)
			(footprints allowed)
		)
		(placement
			(enabled no)
			(sheetname "")
		)
		(fill
			(thermal_gap 0.5)
			(thermal_bridge_width 0.5)
			(island_removal_mode 0)
		)
		(polygon
			(pts
				(xy 421.010842 -276.314662) (xy 421.010842 -276.590252) (xy 420.452042 -276.590252) (xy 420.452042 -276.314662)
			)
		)
	)
	(zone
		(layer "In11.Cu")
		(hatch none 0.5)
		(connect_pads
			(clearance 0)
		)
		(min_thickness 0.25)
		(keepout
			(tracks allowed)
			(vias allowed)
			(pads allowed)
			(copperpour allowed)
			(footprints allowed)
		)
		(placement
			(enabled no)
			(sheetname "")
		)
		(fill
			(thermal_gap 0.5)
			(thermal_bridge_width 0.5)
			(island_removal_mode 0)
		)
		(polygon
			(pts
				(xy 172.521118 -222.86849) (xy 172.521118 -222.5929) (xy 173.079918 -222.5929) (xy 173.079918 -222.86849)
			)
		)
	)
	(zone
		(layer "In11.Cu")
		(hatch none 0.5)
		(connect_pads
			(clearance 0)
		)
		(min_thickness 0.25)
		(keepout
			(tracks allowed)
			(vias allowed)
			(pads allowed)
			(copperpour allowed)
			(footprints allowed)
		)
		(placement
			(enabled no)
			(sheetname "")
		)
		(fill
			(thermal_gap 0.5)
			(thermal_bridge_width 0.5)
			(island_removal_mode 0)
		)
		(polygon
			(pts
				(xy 172.521118 -232.218484) (xy 172.521118 -231.942894) (xy 173.079918 -231.942894) (xy 173.079918 -232.218484)
			)
		)
	)
	(zone
		(layer "In11.Cu")
		(hatch none 0.5)
		(connect_pads
			(clearance 0)
		)
		(min_thickness 0.25)
		(keepout
			(tracks allowed)
			(vias allowed)
			(pads allowed)
			(copperpour allowed)
			(footprints allowed)
		)
		(placement
			(enabled no)
			(sheetname "")
		)
		(fill
			(thermal_gap 0.5)
			(thermal_bridge_width 0.5)
			(island_removal_mode 0)
		)
		(polygon
			(pts
				(xy 451.186042 -279.714706) (xy 451.186042 -279.990296) (xy 450.627242 -279.990296) (xy 450.627242 -279.714706)
			)
		)
	)
	(zone
		(layer "In11.Cu")
		(hatch none 0.5)
		(connect_pads
			(clearance 0)
		)
		(min_thickness 0.25)
		(keepout
			(tracks allowed)
			(vias allowed)
			(pads allowed)
			(copperpour allowed)
			(footprints allowed)
		)
		(placement
			(enabled no)
			(sheetname "")
		)
		(fill
			(thermal_gap 0.5)
			(thermal_bridge_width 0.5)
			(island_removal_mode 0)
		)
		(polygon
			(pts
				(xy 439.572654 -268.768576) (xy 439.572654 -268.492986) (xy 440.131454 -268.492986) (xy 440.131454 -268.768576)
			)
		)
	)
	(zone
		(layer "In11.Cu")
		(hatch none 0.5)
		(connect_pads
			(clearance 0)
		)
		(min_thickness 0.25)
		(keepout
			(tracks allowed)
			(vias allowed)
			(pads allowed)
			(copperpour allowed)
			(footprints allowed)
		)
		(placement
			(enabled no)
			(sheetname "")
		)
		(fill
			(thermal_gap 0.5)
			(thermal_bridge_width 0.5)
			(island_removal_mode 0)
		)
		(polygon
			(pts
				(xy 46.646084 -305.54676) (xy 46.646084 -304.997104) (xy 47.276004 -304.997104) (xy 47.276004 -305.54676)
			)
		)
	)
	(zone
		(layer "In11.Cu")
		(hatch none 0.5)
		(connect_pads
			(clearance 0)
		)
		(min_thickness 0.25)
		(keepout
			(tracks allowed)
			(vias allowed)
			(pads allowed)
			(copperpour allowed)
			(footprints allowed)
		)
		(placement
			(enabled no)
			(sheetname "")
		)
		(fill
			(thermal_gap 0.5)
			(thermal_bridge_width 0.5)
			(island_removal_mode 0)
		)
		(polygon
			(pts
				(xy 202.696318 -235.342938) (xy 203.255118 -235.342938) (xy 203.255118 -235.618528) (xy 202.696318 -235.618528)
				(xy 202.127358 -235.618528) (xy 202.127358 -235.342938)
			)
		)
	)
	(zone
		(layer "In11.Cu")
		(hatch none 0.5)
		(connect_pads
			(clearance 0)
		)
		(min_thickness 0.25)
		(keepout
			(tracks allowed)
			(vias allowed)
			(pads allowed)
			(copperpour allowed)
			(footprints allowed)
		)
		(placement
			(enabled no)
			(sheetname "")
		)
		(fill
			(thermal_gap 0.5)
			(thermal_bridge_width 0.5)
			(island_removal_mode 0)
		)
		(polygon
			(pts
				(xy 332.689962 -291.49675) (xy 332.689708 -285.699454) (xy 332.081886 -285.091632) (xy 332.081886 -284.99943)
				(xy 331.14488 -284.062424) (xy 331.14488 -283.976826) (xy 331.528928 -283.592778) (xy 331.528928 -282.860496)
				(xy 332.411578 -281.977846) (xy 331.281786 -280.848054) (xy 331.281786 -280.737818) (xy 331.97546 -280.044144)
				(xy 331.97546 -280.000456) (xy 330.935076 -278.960072) (xy 330.935076 -278.756364) (xy 330.538582 -278.35987)
				(xy 330.538582 -277.83917) (xy 331.273912 -277.10384) (xy 331.273912 -276.244304) (xy 331.228446 -276.198838)
				(xy 330.992734 -276.198838) (xy 330.9493 -276.155404) (xy 330.9493 -271.342104) (xy 330.81722 -271.210024)
				(xy 330.81722 -260.066536) (xy 330.953618 -259.930138) (xy 331.51191 -259.930138) (xy 331.81671 -260.234938)
				(xy 333.315818 -260.234938) (xy 345.123262 -260.234938) (xy 345.123262 -259.616956) (xy 333.315818 -259.616956)
				(xy 333.315818 -259.587238) (xy 332.08341 -259.587238) (xy 331.687424 -259.191252) (xy 330.845922 -259.191252)
				(xy 330.799186 -259.144516) (xy 330.799186 -255.026414) (xy 330.927202 -254.898398) (xy 333.934308 -254.898398)
				(xy 334.91551 -253.917196) (xy 335.074768 -253.757938) (xy 342.109044 -253.757938) (xy 342.109044 -252.579632)
				(xy 343.123774 -252.579632) (xy 346.986098 -252.579632) (xy 348.949518 -250.616212) (xy 348.949518 -250.456954)
				(xy 348.949518 -249.458734) (xy 348.774258 -249.283474) (xy 346.25661 -249.283474) (xy 346.160598 -249.379486)
				(xy 345.854274 -249.379486) (xy 345.721178 -249.512582) (xy 345.721178 -249.814334) (xy 345.717368 -249.818144)
				(xy 345.717368 -250.115324) (xy 345.164918 -250.667774) (xy 344.949018 -250.883674) (xy 342.255094 -250.883674)
				(xy 342.16594 -250.79452) (xy 342.16594 -249.892566) (xy 342.137492 -249.864118) (xy 336.333592 -249.864118)
				(xy 336.287872 -249.818398) (xy 332.679802 -249.818398) (xy 332.583028 -249.818398) (xy 332.543912 -249.779282)
				(xy 332.543912 -248.966736) (xy 331.584808 -248.966736) (xy 331.54112 -248.923048) (xy 331.54112 -241.091212)
				(xy 331.18298 -240.733072) (xy 331.18298 -240.075466) (xy 331.068934 -239.96142) (xy 330.433934 -239.96142)
				(xy 330.23556 -239.763046) (xy 330.23556 -225.793554) (xy 330.48321 -225.545904) (xy 330.48321 -225.477578)
				(xy 330.143358 -225.137726) (xy 330.143358 -225.02749) (xy 330.683108 -224.48774) (xy 330.683108 -224.318576)
				(xy 330.171806 -223.807274) (xy 330.171806 -223.706182) (xy 330.656184 -223.221804) (xy 330.656184 -222.562928)
				(xy 330.445618 -222.352362) (xy 330.445618 -221.121224) (xy 331.032612 -220.53423) (xy 331.032612 -220.45041)
				(xy 331.672946 -219.810076) (xy 331.672946 -216.906856) (xy 331.714348 -216.865454) (xy 332.688438 -215.891364)
				(xy 332.688438 -210.893406) (xy 351.67824 -210.893152) (xy 351.679764 -291.496496)
			)
		)
	)
	(zone
		(layer "In11.Cu")
		(hatch none 0.5)
		(connect_pads
			(clearance 0)
		)
		(min_thickness 0.25)
		(keepout
			(tracks allowed)
			(vias allowed)
			(pads allowed)
			(copperpour allowed)
			(footprints allowed)
		)
		(placement
			(enabled no)
			(sheetname "")
		)
		(fill
			(thermal_gap 0.5)
			(thermal_bridge_width 0.5)
			(island_removal_mode 0)
		)
		(polygon
			(pts
				(xy 173.070774 -212.564726) (xy 173.070774 -212.840316) (xy 172.511974 -212.840316) (xy 172.511974 -212.564726)
			)
		)
	)
	(zone
		(layer "In11.Cu")
		(hatch none 0.5)
		(connect_pads
			(clearance 0)
		)
		(min_thickness 0.25)
		(keepout
			(tracks allowed)
			(vias allowed)
			(pads allowed)
			(copperpour allowed)
			(footprints allowed)
		)
		(placement
			(enabled no)
			(sheetname "")
		)
		(fill
			(thermal_gap 0.5)
			(thermal_bridge_width 0.5)
			(island_removal_mode 0)
		)
		(polygon
			(pts
				(xy 203.245974 -232.964736) (xy 203.245974 -233.240326) (xy 202.687174 -233.240326) (xy 202.687174 -232.964736)
			)
		)
	)
	(zone
		(layer "In11.Cu")
		(hatch none 0.5)
		(connect_pads
			(clearance 0)
		)
		(min_thickness 0.25)
		(keepout
			(tracks allowed)
			(vias allowed)
			(pads allowed)
			(copperpour allowed)
			(footprints allowed)
		)
		(placement
			(enabled no)
			(sheetname "")
		)
		(fill
			(thermal_gap 0.5)
			(thermal_bridge_width 0.5)
			(island_removal_mode 0)
		)
		(polygon
			(pts
				(xy 298.71162 -260.496812) (xy 298.71162 -259.947156) (xy 299.34154 -259.947156) (xy 299.34154 -260.496812)
			)
		)
	)
	(zone
		(layer "In11.Cu")
		(hatch none 0.5)
		(connect_pads
			(clearance 0)
		)
		(min_thickness 0.25)
		(keepout
			(tracks allowed)
			(vias allowed)
			(pads allowed)
			(copperpour allowed)
			(footprints allowed)
		)
		(placement
			(enabled no)
			(sheetname "")
		)
		(fill
			(thermal_gap 0.5)
			(thermal_bridge_width 0.5)
			(island_removal_mode 0)
		)
		(polygon
			(pts
				(xy 157.957774 -227.014786) (xy 157.957774 -227.290376) (xy 157.398974 -227.290376) (xy 157.398974 -227.014786)
			)
		)
	)
	(zone
		(layer "In11.Cu")
		(hatch none 0.5)
		(connect_pads
			(clearance 0)
		)
		(min_thickness 0.25)
		(keepout
			(tracks allowed)
			(vias allowed)
			(pads allowed)
			(copperpour allowed)
			(footprints allowed)
		)
		(placement
			(enabled no)
			(sheetname "")
		)
		(fill
			(thermal_gap 0.5)
			(thermal_bridge_width 0.5)
			(island_removal_mode 0)
		)
		(polygon
			(pts
				(xy 177.170842 -283.964634) (xy 177.170842 -284.240224) (xy 176.612042 -284.240224) (xy 176.612042 -283.964634)
			)
		)
	)
	(zone
		(layer "In11.Cu")
		(hatch none 0.5)
		(connect_pads
			(clearance 0)
		)
		(min_thickness 0.25)
		(keepout
			(tracks allowed)
			(vias allowed)
			(pads allowed)
			(copperpour allowed)
			(footprints allowed)
		)
		(placement
			(enabled no)
			(sheetname "")
		)
		(fill
			(thermal_gap 0.5)
			(thermal_bridge_width 0.5)
			(island_removal_mode 0)
		)
		(polygon
			(pts
				(xy 202.696318 -281.518614) (xy 202.696318 -281.243024) (xy 203.255118 -281.243024) (xy 203.255118 -281.518614)
			)
		)
	)
	(zone
		(layer "In11.Cu")
		(hatch none 0.5)
		(connect_pads
			(clearance 0)
		)
		(min_thickness 0.25)
		(keepout
			(tracks allowed)
			(vias allowed)
			(pads allowed)
			(copperpour allowed)
			(footprints allowed)
		)
		(placement
			(enabled no)
			(sheetname "")
		)
		(fill
			(thermal_gap 0.5)
			(thermal_bridge_width 0.5)
			(island_removal_mode 0)
		)
		(polygon
			(pts
				(xy 268.51102 -200.14692) (xy 268.51102 -199.597264) (xy 269.14094 -199.597264) (xy 269.14094 -200.14692)
			)
		)
	)
	(zone
		(layer "In11.Cu")
		(hatch none 0.5)
		(connect_pads
			(clearance 0)
		)
		(min_thickness 0.25)
		(keepout
			(tracks allowed)
			(vias allowed)
			(pads allowed)
			(copperpour allowed)
			(footprints allowed)
		)
		(placement
			(enabled no)
			(sheetname "")
		)
		(fill
			(thermal_gap 0.5)
			(thermal_bridge_width 0.5)
			(island_removal_mode 0)
		)
		(polygon
			(pts
				(xy 294.586152 -210.346798) (xy 294.586152 -209.797142) (xy 295.216072 -209.797142) (xy 295.216072 -210.346798)
			)
		)
	)
	(zone
		(layer "In11.Cu")
		(hatch none 0.5)
		(connect_pads
			(clearance 0)
		)
		(min_thickness 0.25)
		(keepout
			(tracks allowed)
			(vias allowed)
			(pads allowed)
			(copperpour allowed)
			(footprints allowed)
		)
		(placement
			(enabled no)
			(sheetname "")
		)
		(fill
			(thermal_gap 0.5)
			(thermal_bridge_width 0.5)
			(island_removal_mode 0)
		)
		(polygon
			(pts
				(xy 421.010842 -271.21485) (xy 421.010842 -271.49044) (xy 420.452042 -271.49044) (xy 420.452042 -271.21485)
			)
		)
	)
	(zone
		(layer "In11.Cu")
		(hatch none 0.5)
		(connect_pads
			(clearance 0)
		)
		(min_thickness 0.25)
		(keepout
			(tracks allowed)
			(vias allowed)
			(pads allowed)
			(copperpour allowed)
			(footprints allowed)
		)
		(placement
			(enabled no)
			(sheetname "")
		)
		(fill
			(thermal_gap 0.5)
			(thermal_bridge_width 0.5)
			(island_removal_mode 0)
		)
		(polygon
			(pts
				(xy 436.098442 -261.014718) (xy 436.098442 -261.290308) (xy 435.539642 -261.290308) (xy 435.539642 -261.014718)
			)
		)
	)
	(zone
		(layer "In11.Cu")
		(hatch none 0.5)
		(connect_pads
			(clearance 0)
		)
		(min_thickness 0.25)
		(keepout
			(tracks allowed)
			(vias allowed)
			(pads allowed)
			(copperpour allowed)
			(footprints allowed)
		)
		(placement
			(enabled no)
			(sheetname "")
		)
		(fill
			(thermal_gap 0.5)
			(thermal_bridge_width 0.5)
			(island_removal_mode 0)
		)
		(polygon
			(pts
				(xy 203.245974 -249.964702) (xy 203.245974 -250.240292) (xy 202.687174 -250.240292) (xy 202.687174 -249.964702)
			)
		)
	)
	(zone
		(layer "In11.Cu")
		(hatch none 0.5)
		(connect_pads
			(clearance 0)
		)
		(min_thickness 0.25)
		(keepout
			(tracks allowed)
			(vias allowed)
			(pads allowed)
			(copperpour allowed)
			(footprints allowed)
		)
		(placement
			(enabled no)
			(sheetname "")
		)
		(fill
			(thermal_gap 0.5)
			(thermal_bridge_width 0.5)
			(island_removal_mode 0)
		)
		(polygon
			(pts
				(xy 203.245974 -251.664724) (xy 203.245974 -251.940314) (xy 202.687174 -251.940314) (xy 202.687174 -251.664724)
			)
		)
	)
	(zone
		(layer "In11.Cu")
		(hatch none 0.5)
		(connect_pads
			(clearance 0)
		)
		(min_thickness 0.25)
		(keepout
			(tracks allowed)
			(vias allowed)
			(pads allowed)
			(copperpour allowed)
			(footprints allowed)
		)
		(placement
			(enabled no)
			(sheetname "")
		)
		(fill
			(thermal_gap 0.5)
			(thermal_bridge_width 0.5)
			(island_removal_mode 0)
		)
		(polygon
			(pts
				(xy 49.99736 -358.358948) (xy 49.99736 -357.492808) (xy 51.47564 -357.492808) (xy 51.47564 -358.358948)
			)
		)
	)
	(zone
		(layer "In11.Cu")
		(hatch none 0.5)
		(connect_pads
			(clearance 0)
		)
		(min_thickness 0.25)
		(keepout
			(tracks allowed)
			(vias allowed)
			(pads allowed)
			(copperpour allowed)
			(footprints allowed)
		)
		(placement
			(enabled no)
			(sheetname "")
		)
		(fill
			(thermal_gap 0.5)
			(thermal_bridge_width 0.5)
			(island_removal_mode 0)
		)
		(polygon
			(pts
				(xy 173.070774 -310.314848) (xy 173.070774 -310.590438) (xy 172.511974 -310.590438) (xy 172.511974 -310.314848)
			)
		)
	)
	(zone
		(layer "In11.Cu")
		(hatch none 0.5)
		(connect_pads
			(clearance 0)
		)
		(min_thickness 0.25)
		(keepout
			(tracks allowed)
			(vias allowed)
			(pads allowed)
			(copperpour allowed)
			(footprints allowed)
		)
		(placement
			(enabled no)
			(sheetname "")
		)
		(fill
			(thermal_gap 0.5)
			(thermal_bridge_width 0.5)
			(island_removal_mode 0)
		)
		(polygon
			(pts
				(xy 298.68622 -212.896958) (xy 298.68622 -212.347302) (xy 299.31614 -212.347302) (xy 299.31614 -212.896958)
			)
		)
	)
	(zone
		(layer "In11.Cu")
		(hatch none 0.5)
		(connect_pads
			(clearance 0)
		)
		(min_thickness 0.25)
		(keepout
			(tracks allowed)
			(vias allowed)
			(pads allowed)
			(copperpour allowed)
			(footprints allowed)
		)
		(placement
			(enabled no)
			(sheetname "")
		)
		(fill
			(thermal_gap 0.5)
			(thermal_bridge_width 0.5)
			(island_removal_mode 0)
		)
		(polygon
			(pts
				(xy 451.186042 -266.114784) (xy 451.186042 -266.390374) (xy 450.627242 -266.390374) (xy 450.5706 -266.390374)
				(xy 450.5706 -266.779248) (xy 449.996052 -266.779248) (xy 449.996052 -265.887454) (xy 451.186042 -265.887454)
			)
		)
	)
	(zone
		(layer "In11.Cu")
		(hatch none 0.5)
		(connect_pads
			(clearance 0)
		)
		(min_thickness 0.25)
		(keepout
			(tracks allowed)
			(vias allowed)
			(pads allowed)
			(copperpour allowed)
			(footprints allowed)
		)
		(placement
			(enabled no)
			(sheetname "")
		)
		(fill
			(thermal_gap 0.5)
			(thermal_bridge_width 0.5)
			(island_removal_mode 0)
		)
		(polygon
			(pts
				(xy 450.636386 -282.092908) (xy 451.195186 -282.092908) (xy 451.195186 -282.368498) (xy 450.636386 -282.368498)
				(xy 450.340984 -282.368498) (xy 450.340984 -282.883356) (xy 449.711572 -282.883356) (xy 449.711572 -282.092908)
				(xy 450.340984 -282.092908)
			)
		)
	)
	(zone
		(layer "In11.Cu")
		(hatch none 0.5)
		(connect_pads
			(clearance 0)
		)
		(min_thickness 0.25)
		(keepout
			(tracks allowed)
			(vias allowed)
			(pads allowed)
			(copperpour allowed)
			(footprints allowed)
		)
		(placement
			(enabled no)
			(sheetname "")
		)
		(fill
			(thermal_gap 0.5)
			(thermal_bridge_width 0.5)
			(island_removal_mode 0)
		)
		(polygon
			(pts
				(xy 420.461186 -251.76861) (xy 420.461186 -251.49302) (xy 421.019986 -251.49302) (xy 421.019986 -251.76861)
			)
		)
	)
	(zone
		(layer "In11.Cu")
		(hatch none 0.5)
		(connect_pads
			(clearance 0)
		)
		(min_thickness 0.25)
		(keepout
			(tracks allowed)
			(vias allowed)
			(pads allowed)
			(copperpour allowed)
			(footprints allowed)
		)
		(placement
			(enabled no)
			(sheetname "")
		)
		(fill
			(thermal_gap 0.5)
			(thermal_bridge_width 0.5)
			(island_removal_mode 0)
		)
		(polygon
			(pts
				(xy 192.258442 -307.764688) (xy 192.258442 -308.040278) (xy 191.699642 -308.040278) (xy 191.699642 -307.764688)
			)
		)
	)
	(zone
		(layer "In11.Cu")
		(hatch none 0.5)
		(connect_pads
			(clearance 0)
		)
		(min_thickness 0.25)
		(keepout
			(tracks allowed)
			(vias allowed)
			(pads allowed)
			(copperpour allowed)
			(footprints allowed)
		)
		(placement
			(enabled no)
			(sheetname "")
		)
		(fill
			(thermal_gap 0.5)
			(thermal_bridge_width 0.5)
			(island_removal_mode 0)
		)
		(polygon
			(pts
				(xy 203.245974 -248.26468) (xy 203.245974 -248.54027) (xy 202.687174 -248.54027) (xy 202.687174 -248.26468)
			)
		)
	)
	(zone
		(layer "In11.Cu")
		(hatch none 0.5)
		(connect_pads
			(clearance 0)
		)
		(min_thickness 0.25)
		(keepout
			(tracks allowed)
			(vias allowed)
			(pads allowed)
			(copperpour allowed)
			(footprints allowed)
		)
		(placement
			(enabled no)
			(sheetname "")
		)
		(fill
			(thermal_gap 0.5)
			(thermal_bridge_width 0.5)
			(island_removal_mode 0)
		)
		(polygon
			(pts
				(xy 421.010842 -297.56481) (xy 421.010842 -297.8404) (xy 420.452042 -297.8404) (xy 420.452042 -297.56481)
			)
		)
	)
	(zone
		(layer "In11.Cu")
		(hatch none 0.5)
		(connect_pads
			(clearance 0)
		)
		(min_thickness 0.25)
		(keepout
			(tracks allowed)
			(vias allowed)
			(pads allowed)
			(copperpour allowed)
			(footprints allowed)
		)
		(placement
			(enabled no)
			(sheetname "")
		)
		(fill
			(thermal_gap 0.5)
			(thermal_bridge_width 0.5)
			(island_removal_mode 0)
		)
		(polygon
			(pts
				(xy 203.245974 -228.714808) (xy 203.245974 -228.990398) (xy 202.687174 -228.990398) (xy 202.531218 -228.990398)
				(xy 202.531218 -227.692966) (xy 203.245974 -227.692966)
			)
		)
	)
	(zone
		(layer "In11.Cu")
		(hatch none 0.5)
		(connect_pads
			(clearance 0)
		)
		(min_thickness 0.25)
		(keepout
			(tracks allowed)
			(vias allowed)
			(pads allowed)
			(copperpour allowed)
			(footprints allowed)
		)
		(placement
			(enabled no)
			(sheetname "")
		)
		(fill
			(thermal_gap 0.5)
			(thermal_bridge_width 0.5)
			(island_removal_mode 0)
		)
		(polygon
			(pts
				(xy 410.02331 -225.314764) (xy 410.02331 -225.590354) (xy 409.46451 -225.590354) (xy 409.46451 -225.314764)
			)
		)
	)
	(zone
		(layer "In11.Cu")
		(hatch none 0.5)
		(connect_pads
			(clearance 0)
		)
		(min_thickness 0.25)
		(keepout
			(tracks not_allowed)
			(vias allowed)
			(pads allowed)
			(copperpour not_allowed)
			(footprints allowed)
		)
		(placement
			(enabled no)
			(sheetname "")
		)
		(fill
			(thermal_gap 0.5)
			(thermal_bridge_width 0.5)
			(island_removal_mode 0)
		)
		(polygon
			(pts
				(arc
					(start 89.142062 -428.960788)
					(mid 89.16438 -429.01467)
					(end 89.218262 -429.036988)
				)
				(arc
					(start 90.158062 -429.036988)
					(mid 90.211944 -429.01467)
					(end 90.234262 -428.960788)
				)
				(arc
					(start 90.234262 -426.419264)
					(mid 90.211944 -426.365382)
					(end 90.158062 -426.343064)
				)
				(arc
					(start 89.218262 -426.343064)
					(mid 89.16438 -426.365382)
					(end 89.142062 -426.419264)
				)
			)
		)
	)
	(zone
		(layer "In11.Cu")
		(hatch none 0.5)
		(connect_pads
			(clearance 0)
		)
		(min_thickness 0.25)
		(keepout
			(tracks allowed)
			(vias allowed)
			(pads allowed)
			(copperpour allowed)
			(footprints allowed)
		)
		(placement
			(enabled no)
			(sheetname "")
		)
		(fill
			(thermal_gap 0.5)
			(thermal_bridge_width 0.5)
			(island_removal_mode 0)
		)
		(polygon
			(pts
				(xy 451.186042 -292.464744) (xy 451.186042 -292.740334) (xy 450.627242 -292.740334) (xy 450.627242 -292.464744)
			)
		)
	)
	(zone
		(layer "In11.Cu")
		(hatch none 0.5)
		(connect_pads
			(clearance 0)
		)
		(min_thickness 0.25)
		(keepout
			(tracks allowed)
			(vias allowed)
			(pads allowed)
			(copperpour allowed)
			(footprints allowed)
		)
		(placement
			(enabled no)
			(sheetname "")
		)
		(fill
			(thermal_gap 0.5)
			(thermal_bridge_width 0.5)
			(island_removal_mode 0)
		)
		(polygon
			(pts
				(xy 294.586152 -303.846738) (xy 294.586152 -303.297082) (xy 295.216072 -303.297082) (xy 295.216072 -303.846738)
			)
		)
	)
	(zone
		(layer "In11.Cu")
		(hatch none 0.5)
		(connect_pads
			(clearance 0)
		)
		(min_thickness 0.25)
		(keepout
			(tracks allowed)
			(vias allowed)
			(pads allowed)
			(copperpour allowed)
			(footprints allowed)
		)
		(placement
			(enabled no)
			(sheetname "")
		)
		(fill
			(thermal_gap 0.5)
			(thermal_bridge_width 0.5)
			(island_removal_mode 0)
		)
		(polygon
			(pts
				(xy 173.070774 -308.614826) (xy 173.070774 -308.890416) (xy 172.511974 -308.890416) (xy 172.511974 -308.614826)
			)
		)
	)
	(zone
		(layer "In11.Cu")
		(hatch none 0.5)
		(connect_pads
			(clearance 0)
		)
		(min_thickness 0.25)
		(keepout
			(tracks allowed)
			(vias allowed)
			(pads allowed)
			(copperpour allowed)
			(footprints allowed)
		)
		(placement
			(enabled no)
			(sheetname "")
		)
		(fill
			(thermal_gap 0.5)
			(thermal_bridge_width 0.5)
			(island_removal_mode 0)
		)
		(polygon
			(pts
				(xy 50.771552 -265.596878) (xy 50.771552 -265.047222) (xy 51.401472 -265.047222) (xy 51.401472 -265.596878)
			)
		)
	)
	(zone
		(layer "In11.Cu")
		(hatch none 0.5)
		(connect_pads
			(clearance 0)
		)
		(min_thickness 0.25)
		(keepout
			(tracks allowed)
			(vias allowed)
			(pads allowed)
			(copperpour allowed)
			(footprints allowed)
		)
		(placement
			(enabled no)
			(sheetname "")
		)
		(fill
			(thermal_gap 0.5)
			(thermal_bridge_width 0.5)
			(island_removal_mode 0)
		)
		(polygon
			(pts
				(xy 298.68622 -251.996956) (xy 298.68622 -251.4473) (xy 299.31614 -251.4473) (xy 299.31614 -251.996956)
			)
		)
	)
	(zone
		(layer "In11.Cu")
		(hatch none 0.5)
		(connect_pads
			(clearance 0)
		)
		(min_thickness 0.25)
		(keepout
			(tracks allowed)
			(vias allowed)
			(pads allowed)
			(copperpour allowed)
			(footprints allowed)
		)
		(placement
			(enabled no)
			(sheetname "")
		)
		(fill
			(thermal_gap 0.5)
			(thermal_bridge_width 0.5)
			(island_removal_mode 0)
		)
		(polygon
			(pts
				(xy 391.152126 -243.80825) (xy 397.156686 -243.80825) (xy 397.718026 -244.36959) (xy 397.718026 -245.61927)
				(xy 397.651986 -245.68531) (xy 391.119106 -245.68531) (xy 390.832086 -245.39829) (xy 390.832086 -244.12829)
			)
		)
	)
	(zone
		(layer "In11.Cu")
		(hatch none 0.5)
		(connect_pads
			(clearance 0)
		)
		(min_thickness 0.25)
		(keepout
			(tracks allowed)
			(vias allowed)
			(pads allowed)
			(copperpour allowed)
			(footprints allowed)
		)
		(placement
			(enabled no)
			(sheetname "")
		)
		(fill
			(thermal_gap 0.5)
			(thermal_bridge_width 0.5)
			(island_removal_mode 0)
		)
		(polygon
			(pts
				(xy 187.608718 -212.668612) (xy 187.608718 -212.393022) (xy 188.167518 -212.393022) (xy 188.167518 -212.668612)
			)
		)
	)
	(zone
		(layer "In11.Cu")
		(hatch none 0.5)
		(connect_pads
			(clearance 0)
		)
		(min_thickness 0.25)
		(keepout
			(tracks allowed)
			(vias allowed)
			(pads allowed)
			(copperpour allowed)
			(footprints allowed)
		)
		(placement
			(enabled no)
			(sheetname "")
		)
		(fill
			(thermal_gap 0.5)
			(thermal_bridge_width 0.5)
			(island_removal_mode 0)
		)
		(polygon
			(pts
				(xy 202.696318 -202.46848) (xy 202.696318 -202.19289) (xy 203.255118 -202.19289) (xy 203.255118 -202.46848)
			)
		)
	)
	(zone
		(layer "In11.Cu")
		(hatch none 0.5)
		(connect_pads
			(clearance 0)
		)
		(min_thickness 0.25)
		(keepout
			(tracks allowed)
			(vias allowed)
			(pads allowed)
			(copperpour allowed)
			(footprints allowed)
		)
		(placement
			(enabled no)
			(sheetname "")
		)
		(fill
			(thermal_gap 0.5)
			(thermal_bridge_width 0.5)
			(island_removal_mode 0)
		)
		(polygon
			(pts
				(xy 450.636386 -261.968488) (xy 450.636386 -261.692898) (xy 451.195186 -261.692898) (xy 451.195186 -261.968488)
			)
		)
	)
	(zone
		(layer "In11.Cu")
		(hatch none 0.5)
		(connect_pads
			(clearance 0)
		)
		(min_thickness 0.25)
		(keepout
			(tracks allowed)
			(vias allowed)
			(pads allowed)
			(copperpour allowed)
			(footprints allowed)
		)
		(placement
			(enabled no)
			(sheetname "")
		)
		(fill
			(thermal_gap 0.5)
			(thermal_bridge_width 0.5)
			(island_removal_mode 0)
		)
		(polygon
			(pts
				(xy 20.624292 -286.000698) (xy 20.624292 -285.45028) (xy 21.183092 -285.45028) (xy 21.183092 -286.000698)
			)
		)
	)
	(zone
		(layer "In11.Cu")
		(hatch none 0.5)
		(connect_pads
			(clearance 0)
		)
		(min_thickness 0.25)
		(keepout
			(tracks allowed)
			(vias allowed)
			(pads allowed)
			(copperpour allowed)
			(footprints allowed)
		)
		(placement
			(enabled no)
			(sheetname "")
		)
		(fill
			(thermal_gap 0.5)
			(thermal_bridge_width 0.5)
			(island_removal_mode 0)
		)
		(polygon
			(pts
				(xy 424.561254 -212.668612) (xy 424.561254 -212.393022) (xy 425.120054 -212.393022) (xy 425.120054 -212.668612)
			)
		)
	)
	(zone
		(layer "In11.Cu")
		(hatch none 0.5)
		(connect_pads
			(clearance 0)
		)
		(min_thickness 0.25)
		(keepout
			(tracks allowed)
			(vias allowed)
			(pads allowed)
			(copperpour allowed)
			(footprints allowed)
		)
		(placement
			(enabled no)
			(sheetname "")
		)
		(fill
			(thermal_gap 0.5)
			(thermal_bridge_width 0.5)
			(island_removal_mode 0)
		)
		(polygon
			(pts
				(xy 134.02056 -347.762068) (xy 134.02056 -345.646248) (xy 138.39698 -345.646248) (xy 138.39698 -347.762068)
			)
		)
	)
	(zone
		(layer "In11.Cu")
		(hatch none 0.5)
		(connect_pads
			(clearance 0)
		)
		(min_thickness 0.25)
		(keepout
			(tracks allowed)
			(vias allowed)
			(pads allowed)
			(copperpour allowed)
			(footprints allowed)
		)
		(placement
			(enabled no)
			(sheetname "")
		)
		(fill
			(thermal_gap 0.5)
			(thermal_bridge_width 0.5)
			(island_removal_mode 0)
		)
		(polygon
			(pts
				(xy 173.070774 -278.014684) (xy 173.070774 -278.290274) (xy 172.511974 -278.290274) (xy 172.511974 -278.014684)
			)
		)
	)
	(zone
		(layer "In11.Cu")
		(hatch none 0.5)
		(connect_pads
			(clearance 0)
		)
		(min_thickness 0.25)
		(keepout
			(tracks allowed)
			(vias allowed)
			(pads allowed)
			(copperpour allowed)
			(footprints allowed)
		)
		(placement
			(enabled no)
			(sheetname "")
		)
		(fill
			(thermal_gap 0.5)
			(thermal_bridge_width 0.5)
			(island_removal_mode 0)
		)
		(polygon
			(pts
				(xy 424.561254 -264.518394) (xy 424.561254 -264.242804) (xy 425.120054 -264.242804) (xy 425.120054 -264.518394)
			)
		)
	)
	(zone
		(layer "In11.Cu")
		(hatch none 0.5)
		(connect_pads
			(clearance 0)
		)
		(min_thickness 0.25)
		(keepout
			(tracks allowed)
			(vias allowed)
			(pads allowed)
			(copperpour allowed)
			(footprints allowed)
		)
		(placement
			(enabled no)
			(sheetname "")
		)
		(fill
			(thermal_gap 0.5)
			(thermal_bridge_width 0.5)
			(island_removal_mode 0)
		)
		(polygon
			(pts
				(xy 420.461186 -197.368414) (xy 420.461186 -197.092824) (xy 421.019986 -197.092824) (xy 421.019986 -197.368414)
			)
		)
	)
	(zone
		(layer "In11.Cu")
		(hatch none 0.5)
		(connect_pads
			(clearance 0)
		)
		(min_thickness 0.25)
		(keepout
			(tracks allowed)
			(vias allowed)
			(pads allowed)
			(copperpour allowed)
			(footprints allowed)
		)
		(placement
			(enabled no)
			(sheetname "")
		)
		(fill
			(thermal_gap 0.5)
			(thermal_bridge_width 0.5)
			(island_removal_mode 0)
		)
		(polygon
			(pts
				(xy 421.010842 -232.964736) (xy 421.010842 -233.240326) (xy 420.452042 -233.240326) (xy 420.452042 -232.964736)
			)
		)
	)
	(zone
		(layer "In11.Cu")
		(hatch none 0.5)
		(connect_pads
			(clearance 0)
		)
		(min_thickness 0.25)
		(keepout
			(tracks allowed)
			(vias allowed)
			(pads allowed)
			(copperpour allowed)
			(footprints allowed)
		)
		(placement
			(enabled no)
			(sheetname "")
		)
		(fill
			(thermal_gap 0.5)
			(thermal_bridge_width 0.5)
			(island_removal_mode 0)
		)
		(polygon
			(pts
				(xy 451.186042 -228.714808) (xy 451.186042 -228.990398) (xy 450.627242 -228.990398) (xy 450.471286 -228.990398)
				(xy 450.471286 -227.692966) (xy 451.186042 -227.692966)
			)
		)
	)
	(zone
		(layer "In11.Cu")
		(hatch none 0.5)
		(connect_pads
			(clearance 0)
		)
		(min_thickness 0.25)
		(keepout
			(tracks allowed)
			(vias allowed)
			(pads allowed)
			(copperpour allowed)
			(footprints allowed)
		)
		(placement
			(enabled no)
			(sheetname "")
		)
		(fill
			(thermal_gap 0.5)
			(thermal_bridge_width 0.5)
			(island_removal_mode 0)
		)
		(polygon
			(pts
				(xy 176.621186 -197.368414) (xy 176.621186 -197.092824) (xy 177.179986 -197.092824) (xy 177.179986 -197.368414)
			)
		)
	)
	(zone
		(layer "In11.Cu")
		(hatch none 0.5)
		(connect_pads
			(clearance 0)
		)
		(min_thickness 0.25)
		(keepout
			(tracks allowed)
			(vias allowed)
			(pads allowed)
			(copperpour allowed)
			(footprints allowed)
		)
		(placement
			(enabled no)
			(sheetname "")
		)
		(fill
			(thermal_gap 0.5)
			(thermal_bridge_width 0.5)
			(island_removal_mode 0)
		)
		(polygon
			(pts
				(xy 202.696318 -204.168502) (xy 202.696318 -203.892912) (xy 203.255118 -203.892912) (xy 203.255118 -204.168502)
			)
		)
	)
	(zone
		(layer "In11.Cu")
		(hatch none 0.5)
		(connect_pads
			(clearance 0)
		)
		(min_thickness 0.25)
		(keepout
			(tracks allowed)
			(vias allowed)
			(pads allowed)
			(copperpour allowed)
			(footprints allowed)
		)
		(placement
			(enabled no)
			(sheetname "")
		)
		(fill
			(thermal_gap 0.5)
			(thermal_bridge_width 0.5)
			(island_removal_mode 0)
		)
		(polygon
			(pts
				(xy 202.696318 -205.868524) (xy 202.696318 -205.592934) (xy 203.255118 -205.592934) (xy 203.255118 -205.868524)
			)
		)
	)
	(zone
		(layer "In11.Cu")
		(hatch none 0.5)
		(connect_pads
			(clearance 0)
		)
		(min_thickness 0.25)
		(keepout
			(tracks not_allowed)
			(vias allowed)
			(pads allowed)
			(copperpour not_allowed)
			(footprints allowed)
		)
		(placement
			(enabled no)
			(sheetname "")
		)
		(fill
			(thermal_gap 0.5)
			(thermal_bridge_width 0.5)
			(island_removal_mode 0)
		)
		(polygon
			(pts
				(arc
					(start 139.242038 -428.960788)
					(mid 139.264356 -429.01467)
					(end 139.318238 -429.036988)
				)
				(arc
					(start 140.258038 -429.036988)
					(mid 140.31192 -429.01467)
					(end 140.334238 -428.960788)
				)
				(arc
					(start 140.334238 -426.419264)
					(mid 140.31192 -426.365382)
					(end 140.258038 -426.343064)
				)
				(arc
					(start 139.318238 -426.343064)
					(mid 139.264356 -426.365382)
					(end 139.242038 -426.419264)
				)
			)
		)
	)
	(zone
		(layer "In11.Cu")
		(hatch none 0.5)
		(connect_pads
			(clearance 0)
		)
		(min_thickness 0.25)
		(keepout
			(tracks allowed)
			(vias allowed)
			(pads allowed)
			(copperpour allowed)
			(footprints allowed)
		)
		(placement
			(enabled no)
			(sheetname "")
		)
		(fill
			(thermal_gap 0.5)
			(thermal_bridge_width 0.5)
			(island_removal_mode 0)
		)
		(polygon
			(pts
				(xy 20.570952 -240.94694) (xy 20.570952 -240.397284) (xy 21.200872 -240.397284) (xy 21.200872 -240.94694)
			)
		)
	)
	(zone
		(layer "In11.Cu")
		(hatch none 0.5)
		(connect_pads
			(clearance 0)
		)
		(min_thickness 0.25)
		(keepout
			(tracks allowed)
			(vias allowed)
			(pads allowed)
			(copperpour allowed)
			(footprints allowed)
		)
		(placement
			(enabled no)
			(sheetname "")
		)
		(fill
			(thermal_gap 0.5)
			(thermal_bridge_width 0.5)
			(island_removal_mode 0)
		)
		(polygon
			(pts
				(xy 50.746152 -206.946754) (xy 50.746152 -206.397098) (xy 51.376072 -206.397098) (xy 51.376072 -206.946754)
			)
		)
	)
	(zone
		(layer "In11.Cu")
		(hatch none 0.5)
		(connect_pads
			(clearance 0)
		)
		(min_thickness 0.25)
		(keepout
			(tracks allowed)
			(vias allowed)
			(pads allowed)
			(copperpour allowed)
			(footprints allowed)
		)
		(placement
			(enabled no)
			(sheetname "")
		)
		(fill
			(thermal_gap 0.5)
			(thermal_bridge_width 0.5)
			(island_removal_mode 0)
		)
		(polygon
			(pts
				(xy 173.070774 -306.914804) (xy 173.070774 -307.190394) (xy 172.511974 -307.190394) (xy 172.511974 -306.914804)
			)
		)
	)
	(zone
		(layer "In11.Cu")
		(hatch none 0.5)
		(connect_pads
			(clearance 0)
		)
		(min_thickness 0.25)
		(keepout
			(tracks allowed)
			(vias allowed)
			(pads allowed)
			(copperpour allowed)
			(footprints allowed)
		)
		(placement
			(enabled no)
			(sheetname "")
		)
		(fill
			(thermal_gap 0.5)
			(thermal_bridge_width 0.5)
			(island_removal_mode 0)
		)
		(polygon
			(pts
				(xy 176.621186 -305.318414) (xy 176.621186 -305.042824) (xy 177.179986 -305.042824) (xy 177.179986 -305.318414)
			)
		)
	)
	(zone
		(layer "In11.Cu")
		(hatch none 0.5)
		(connect_pads
			(clearance 0)
		)
		(min_thickness 0.25)
		(keepout
			(tracks allowed)
			(vias allowed)
			(pads allowed)
			(copperpour allowed)
			(footprints allowed)
		)
		(placement
			(enabled no)
			(sheetname "")
		)
		(fill
			(thermal_gap 0.5)
			(thermal_bridge_width 0.5)
			(island_removal_mode 0)
		)
		(polygon
			(pts
				(xy 450.636386 -202.46848) (xy 450.636386 -202.19289) (xy 451.195186 -202.19289) (xy 451.195186 -202.46848)
			)
		)
	)
	(zone
		(layer "In11.Cu")
		(hatch none 0.5)
		(connect_pads
			(clearance 0)
		)
		(min_thickness 0.25)
		(keepout
			(tracks allowed)
			(vias allowed)
			(pads allowed)
			(copperpour allowed)
			(footprints allowed)
		)
		(placement
			(enabled no)
			(sheetname "")
		)
		(fill
			(thermal_gap 0.5)
			(thermal_bridge_width 0.5)
			(island_removal_mode 0)
		)
		(polygon
			(pts
				(xy 420.461186 -314.668408) (xy 420.461186 -314.392818) (xy 421.019986 -314.392818) (xy 421.019986 -314.668408)
			)
		)
	)
	(zone
		(layer "In11.Cu")
		(hatch none 0.5)
		(connect_pads
			(clearance 0)
		)
		(min_thickness 0.25)
		(keepout
			(tracks allowed)
			(vias allowed)
			(pads allowed)
			(copperpour allowed)
			(footprints allowed)
		)
		(placement
			(enabled no)
			(sheetname "")
		)
		(fill
			(thermal_gap 0.5)
			(thermal_bridge_width 0.5)
			(island_removal_mode 0)
		)
		(polygon
			(pts
				(xy 450.636386 -227.968556) (xy 450.636386 -227.692966) (xy 451.195186 -227.692966) (xy 451.195186 -227.968556)
			)
		)
	)
	(zone
		(layer "In11.Cu")
		(hatch none 0.5)
		(connect_pads
			(clearance 0)
		)
		(min_thickness 0.25)
		(keepout
			(tracks allowed)
			(vias allowed)
			(pads allowed)
			(copperpour allowed)
			(footprints allowed)
		)
		(placement
			(enabled no)
			(sheetname "")
		)
		(fill
			(thermal_gap 0.5)
			(thermal_bridge_width 0.5)
			(island_removal_mode 0)
		)
		(polygon
			(pts
				(xy 294.586152 -261.34695) (xy 294.586152 -260.797294) (xy 295.216072 -260.797294) (xy 295.216072 -261.34695)
			)
		)
	)
	(zone
		(layer "In11.Cu")
		(hatch none 0.5)
		(connect_pads
			(clearance 0)
		)
		(min_thickness 0.25)
		(keepout
			(tracks allowed)
			(vias allowed)
			(pads allowed)
			(copperpour allowed)
			(footprints allowed)
		)
		(placement
			(enabled no)
			(sheetname "")
		)
		(fill
			(thermal_gap 0.5)
			(thermal_bridge_width 0.5)
			(island_removal_mode 0)
		)
		(polygon
			(pts
				(xy 177.170842 -282.264612) (xy 177.170842 -282.540202) (xy 176.612042 -282.540202) (xy 176.612042 -282.264612)
			)
		)
	)
	(zone
		(layer "In11.Cu")
		(hatch none 0.5)
		(connect_pads
			(clearance 0)
		)
		(min_thickness 0.25)
		(keepout
			(tracks allowed)
			(vias allowed)
			(pads allowed)
			(copperpour allowed)
			(footprints allowed)
		)
		(placement
			(enabled no)
			(sheetname "")
		)
		(fill
			(thermal_gap 0.5)
			(thermal_bridge_width 0.5)
			(island_removal_mode 0)
		)
		(polygon
			(pts
				(xy 451.186042 -230.41483) (xy 451.186042 -230.69042) (xy 450.627242 -230.69042) (xy 450.627242 -230.41483)
			)
		)
	)
	(zone
		(layer "In11.Cu")
		(hatch none 0.5)
		(connect_pads
			(clearance 0)
		)
		(min_thickness 0.25)
		(keepout
			(tracks allowed)
			(vias allowed)
			(pads allowed)
			(copperpour allowed)
			(footprints allowed)
		)
		(placement
			(enabled no)
			(sheetname "")
		)
		(fill
			(thermal_gap 0.5)
			(thermal_bridge_width 0.5)
			(island_removal_mode 0)
		)
		(polygon
			(pts
				(xy 420.461186 -199.068436) (xy 420.461186 -198.792846) (xy 421.019986 -198.792846) (xy 421.019986 -199.068436)
			)
		)
	)
	(zone
		(layer "In11.Cu")
		(hatch none 0.5)
		(connect_pads
			(clearance 0)
		)
		(min_thickness 0.25)
		(keepout
			(tracks allowed)
			(vias allowed)
			(pads allowed)
			(copperpour allowed)
			(footprints allowed)
		)
		(placement
			(enabled no)
			(sheetname "")
		)
		(fill
			(thermal_gap 0.5)
			(thermal_bridge_width 0.5)
			(island_removal_mode 0)
		)
		(polygon
			(pts
				(xy 421.010842 -229.564692) (xy 421.010842 -229.840282) (xy 420.452042 -229.840282) (xy 420.452042 -229.564692)
			)
		)
	)
	(zone
		(layer "In11.Cu")
		(hatch none 0.5)
		(connect_pads
			(clearance 0)
		)
		(min_thickness 0.25)
		(keepout
			(tracks allowed)
			(vias allowed)
			(pads allowed)
			(copperpour allowed)
			(footprints allowed)
		)
		(placement
			(enabled no)
			(sheetname "")
		)
		(fill
			(thermal_gap 0.5)
			(thermal_bridge_width 0.5)
			(island_removal_mode 0)
		)
		(polygon
			(pts
				(xy 425.11091 -239.764824) (xy 425.11091 -240.040414) (xy 424.55211 -240.040414) (xy 424.55211 -239.764824)
			)
		)
	)
	(zone
		(layer "In11.Cu")
		(hatch none 0.5)
		(connect_pads
			(clearance 0)
		)
		(min_thickness 0.25)
		(keepout
			(tracks allowed)
			(vias allowed)
			(pads allowed)
			(copperpour allowed)
			(footprints allowed)
		)
		(placement
			(enabled no)
			(sheetname "")
		)
		(fill
			(thermal_gap 0.5)
			(thermal_bridge_width 0.5)
			(island_removal_mode 0)
		)
		(polygon
			(pts
				(xy 424.561254 -240.718594) (xy 424.561254 -240.443004) (xy 425.120054 -240.443004) (xy 425.120054 -240.718594)
			)
		)
	)
	(zone
		(layer "In11.Cu")
		(hatch none 0.5)
		(connect_pads
			(clearance 0)
		)
		(min_thickness 0.25)
		(keepout
			(tracks allowed)
			(vias allowed)
			(pads allowed)
			(copperpour allowed)
			(footprints allowed)
		)
		(placement
			(enabled no)
			(sheetname "")
		)
		(fill
			(thermal_gap 0.5)
			(thermal_bridge_width 0.5)
			(island_removal_mode 0)
		)
		(polygon
			(pts
				(xy 184.164986 -267.068554) (xy 184.164986 -266.792964) (xy 184.723786 -266.792964) (xy 184.723786 -267.068554)
			)
		)
	)
	(zone
		(layer "In11.Cu")
		(hatch none 0.5)
		(connect_pads
			(clearance 0)
		)
		(min_thickness 0.25)
		(keepout
			(tracks allowed)
			(vias allowed)
			(pads allowed)
			(copperpour allowed)
			(footprints allowed)
		)
		(placement
			(enabled no)
			(sheetname "")
		)
		(fill
			(thermal_gap 0.5)
			(thermal_bridge_width 0.5)
			(island_removal_mode 0)
		)
		(polygon
			(pts
				(xy 440.19851 -209.164682) (xy 440.19851 -209.440272) (xy 439.63971 -209.440272) (xy 439.63971 -209.164682)
			)
		)
	)
	(zone
		(layer "In11.Cu")
		(hatch none 0.5)
		(connect_pads
			(clearance 0)
		)
		(min_thickness 0.25)
		(keepout
			(tracks allowed)
			(vias allowed)
			(pads allowed)
			(copperpour allowed)
			(footprints allowed)
		)
		(placement
			(enabled no)
			(sheetname "")
		)
		(fill
			(thermal_gap 0.5)
			(thermal_bridge_width 0.5)
			(island_removal_mode 0)
		)
		(polygon
			(pts
				(xy 35.696144 -269.019528) (xy 35.696144 -268.437868) (xy 36.254944 -268.437868) (xy 36.254944 -269.019528)
			)
		)
	)
	(zone
		(layer "In11.Cu")
		(hatch none 0.5)
		(connect_pads
			(clearance 0)
		)
		(min_thickness 0.25)
		(keepout
			(tracks allowed)
			(vias allowed)
			(pads allowed)
			(copperpour allowed)
			(footprints allowed)
		)
		(placement
			(enabled no)
			(sheetname "")
		)
		(fill
			(thermal_gap 0.5)
			(thermal_bridge_width 0.5)
			(island_removal_mode 0)
		)
		(polygon
			(pts
				(xy 176.621186 -204.168502) (xy 176.621186 -203.892912) (xy 177.179986 -203.892912) (xy 177.179986 -204.168502)
			)
		)
	)
	(zone
		(layer "In11.Cu")
		(hatch none 0.5)
		(connect_pads
			(clearance 0)
		)
		(min_thickness 0.25)
		(keepout
			(tracks allowed)
			(vias allowed)
			(pads allowed)
			(copperpour allowed)
			(footprints allowed)
		)
		(placement
			(enabled no)
			(sheetname "")
		)
		(fill
			(thermal_gap 0.5)
			(thermal_bridge_width 0.5)
			(island_removal_mode 0)
		)
		(polygon
			(pts
				(xy 50.746152 -195.896738) (xy 50.746152 -195.347082) (xy 51.376072 -195.347082) (xy 51.376072 -195.896738)
			)
		)
	)
	(zone
		(layer "In11.Cu")
		(hatch none 0.5)
		(connect_pads
			(clearance 0)
		)
		(min_thickness 0.25)
		(keepout
			(tracks allowed)
			(vias allowed)
			(pads allowed)
			(copperpour allowed)
			(footprints allowed)
		)
		(placement
			(enabled no)
			(sheetname "")
		)
		(fill
			(thermal_gap 0.5)
			(thermal_bridge_width 0.5)
			(island_removal_mode 0)
		)
		(polygon
			(pts
				(xy 46.646084 -204.396848) (xy 46.646084 -203.847192) (xy 47.276004 -203.847192) (xy 47.276004 -204.396848)
			)
		)
	)
	(zone
		(layer "In11.Cu")
		(hatch none 0.5)
		(connect_pads
			(clearance 0)
		)
		(min_thickness 0.25)
		(keepout
			(tracks allowed)
			(vias allowed)
			(pads allowed)
			(copperpour allowed)
			(footprints allowed)
		)
		(placement
			(enabled no)
			(sheetname "")
		)
		(fill
			(thermal_gap 0.5)
			(thermal_bridge_width 0.5)
			(island_removal_mode 0)
		)
		(polygon
			(pts
				(xy 173.070774 -221.064836) (xy 173.070774 -221.340426) (xy 172.511974 -221.340426) (xy 172.511974 -221.064836)
			)
		)
	)
	(zone
		(layer "In11.Cu")
		(hatch none 0.5)
		(connect_pads
			(clearance 0)
		)
		(min_thickness 0.25)
		(keepout
			(tracks allowed)
			(vias allowed)
			(pads allowed)
			(copperpour allowed)
			(footprints allowed)
		)
		(placement
			(enabled no)
			(sheetname "")
		)
		(fill
			(thermal_gap 0.5)
			(thermal_bridge_width 0.5)
			(island_removal_mode 0)
		)
		(polygon
			(pts
				(xy 207.346042 -266.964668) (xy 207.346042 -267.240258) (xy 206.787242 -267.240258) (xy 206.787242 -266.964668)
			)
		)
	)
	(zone
		(layer "In11.Cu")
		(hatch none 0.5)
		(connect_pads
			(clearance 0)
		)
		(min_thickness 0.25)
		(keepout
			(tracks allowed)
			(vias allowed)
			(pads allowed)
			(copperpour allowed)
			(footprints allowed)
		)
		(placement
			(enabled no)
			(sheetname "")
		)
		(fill
			(thermal_gap 0.5)
			(thermal_bridge_width 0.5)
			(island_removal_mode 0)
		)
		(polygon
			(pts
				(xy 298.71162 -274.947126) (xy 298.71162 -274.39747) (xy 299.34154 -274.39747) (xy 299.34154 -274.947126)
			)
		)
	)
	(zone
		(layer "In11.Cu")
		(hatch none 0.5)
		(connect_pads
			(clearance 0)
		)
		(min_thickness 0.25)
		(keepout
			(tracks allowed)
			(vias allowed)
			(pads allowed)
			(copperpour allowed)
			(footprints allowed)
		)
		(placement
			(enabled no)
			(sheetname "")
		)
		(fill
			(thermal_gap 0.5)
			(thermal_bridge_width 0.5)
			(island_removal_mode 0)
		)
		(polygon
			(pts
				(xy 202.696318 -265.368532) (xy 202.696318 -265.092942) (xy 203.255118 -265.092942) (xy 203.255118 -265.368532)
			)
		)
	)
	(zone
		(layer "In11.Cu")
		(hatch none 0.5)
		(connect_pads
			(clearance 0)
		)
		(min_thickness 0.25)
		(keepout
			(tracks allowed)
			(vias allowed)
			(pads allowed)
			(copperpour allowed)
			(footprints allowed)
		)
		(placement
			(enabled no)
			(sheetname "")
		)
		(fill
			(thermal_gap 0.5)
			(thermal_bridge_width 0.5)
			(island_removal_mode 0)
		)
		(polygon
			(pts
				(xy 420.461186 -210.118452) (xy 420.461186 -209.842862) (xy 421.019986 -209.842862) (xy 421.019986 -210.118452)
			)
		)
	)
	(zone
		(layer "In11.Cu")
		(hatch none 0.5)
		(connect_pads
			(clearance 0)
		)
		(min_thickness 0.25)
		(keepout
			(tracks allowed)
			(vias allowed)
			(pads allowed)
			(copperpour allowed)
			(footprints allowed)
		)
		(placement
			(enabled no)
			(sheetname "")
		)
		(fill
			(thermal_gap 0.5)
			(thermal_bridge_width 0.5)
			(island_removal_mode 0)
		)
		(polygon
			(pts
				(xy 298.71162 -274.096734) (xy 298.71162 -273.547078) (xy 299.34154 -273.547078) (xy 299.34154 -274.096734)
			)
		)
	)
	(zone
		(layer "In11.Cu")
		(hatch none 0.5)
		(connect_pads
			(clearance 0)
		)
		(min_thickness 0.25)
		(keepout
			(tracks allowed)
			(vias allowed)
			(pads allowed)
			(copperpour allowed)
			(footprints allowed)
		)
		(placement
			(enabled no)
			(sheetname "")
		)
		(fill
			(thermal_gap 0.5)
			(thermal_bridge_width 0.5)
			(island_removal_mode 0)
		)
		(polygon
			(pts
				(xy 40.30218 -358.404668) (xy 40.30218 -357.205788) (xy 42.17416 -357.205788) (xy 42.17416 -358.404668)
			)
		)
	)
	(zone
		(layer "In11.Cu")
		(hatch none 0.5)
		(connect_pads
			(clearance 0)
		)
		(min_thickness 0.25)
		(keepout
			(tracks allowed)
			(vias allowed)
			(pads allowed)
			(copperpour allowed)
			(footprints allowed)
		)
		(placement
			(enabled no)
			(sheetname "")
		)
		(fill
			(thermal_gap 0.5)
			(thermal_bridge_width 0.5)
			(island_removal_mode 0)
		)
		(polygon
			(pts
				(xy 177.170842 -210.01482) (xy 177.170842 -210.29041) (xy 176.612042 -210.29041) (xy 176.612042 -210.01482)
			)
		)
	)
	(zone
		(layer "In11.Cu")
		(hatch none 0.5)
		(connect_pads
			(clearance 0)
		)
		(min_thickness 0.25)
		(keepout
			(tracks allowed)
			(vias allowed)
			(pads allowed)
			(copperpour allowed)
			(footprints allowed)
		)
		(placement
			(enabled no)
			(sheetname "")
		)
		(fill
			(thermal_gap 0.5)
			(thermal_bridge_width 0.5)
			(island_removal_mode 0)
		)
		(polygon
			(pts
				(xy 177.170842 -227.014786) (xy 177.170842 -227.290376) (xy 176.612042 -227.290376) (xy 176.612042 -227.014786)
			)
		)
	)
	(zone
		(layer "In11.Cu")
		(hatch none 0.5)
		(connect_pads
			(clearance 0)
		)
		(min_thickness 0.25)
		(keepout
			(tracks not_allowed)
			(vias allowed)
			(pads allowed)
			(copperpour not_allowed)
			(footprints allowed)
		)
		(placement
			(enabled no)
			(sheetname "")
		)
		(fill
			(thermal_gap 0.5)
			(thermal_bridge_width 0.5)
			(island_removal_mode 0)
		)
		(polygon
			(pts
				(arc
					(start 152.242012 -428.960788)
					(mid 152.26433 -429.01467)
					(end 152.318212 -429.036988)
				)
				(arc
					(start 153.258012 -429.036988)
					(mid 153.311894 -429.01467)
					(end 153.334212 -428.960788)
				)
				(arc
					(start 153.334212 -426.419264)
					(mid 153.311894 -426.365382)
					(end 153.258012 -426.343064)
				)
				(arc
					(start 152.318212 -426.343064)
					(mid 152.26433 -426.365382)
					(end 152.242012 -426.419264)
				)
			)
		)
	)
	(zone
		(layer "In11.Cu")
		(hatch none 0.5)
		(connect_pads
			(clearance 0)
		)
		(min_thickness 0.25)
		(keepout
			(tracks allowed)
			(vias allowed)
			(pads allowed)
			(copperpour allowed)
			(footprints allowed)
		)
		(placement
			(enabled no)
			(sheetname "")
		)
		(fill
			(thermal_gap 0.5)
			(thermal_bridge_width 0.5)
			(island_removal_mode 0)
		)
		(polygon
			(pts
				(xy 450.636386 -247.518428) (xy 450.636386 -247.242838) (xy 451.195186 -247.242838) (xy 451.195186 -247.518428)
			)
		)
	)
	(zone
		(layer "In11.Cu")
		(hatch none 0.5)
		(connect_pads
			(clearance 0)
		)
		(min_thickness 0.25)
		(keepout
			(tracks allowed)
			(vias allowed)
			(pads allowed)
			(copperpour allowed)
			(footprints allowed)
		)
		(placement
			(enabled no)
			(sheetname "")
		)
		(fill
			(thermal_gap 0.5)
			(thermal_bridge_width 0.5)
			(island_removal_mode 0)
		)
		(polygon
			(pts
				(xy 180.064918 -246.668544) (xy 180.064918 -246.392954) (xy 180.623718 -246.392954) (xy 180.623718 -246.668544)
			)
		)
	)
	(zone
		(layer "In11.Cu")
		(hatch none 0.5)
		(connect_pads
			(clearance 0)
		)
		(min_thickness 0.25)
		(keepout
			(tracks allowed)
			(vias allowed)
			(pads allowed)
			(copperpour allowed)
			(footprints allowed)
		)
		(placement
			(enabled no)
			(sheetname "")
		)
		(fill
			(thermal_gap 0.5)
			(thermal_bridge_width 0.5)
			(island_removal_mode 0)
		)
		(polygon
			(pts
				(xy 268.56436 -306.400708) (xy 268.56436 -305.85029) (xy 269.12316 -305.85029) (xy 269.12316 -306.400708)
			)
		)
	)
	(zone
		(layer "In11.Cu")
		(hatch none 0.5)
		(connect_pads
			(clearance 0)
		)
		(min_thickness 0.25)
		(keepout
			(tracks allowed)
			(vias allowed)
			(pads allowed)
			(copperpour allowed)
			(footprints allowed)
		)
		(placement
			(enabled no)
			(sheetname "")
		)
		(fill
			(thermal_gap 0.5)
			(thermal_bridge_width 0.5)
			(island_removal_mode 0)
		)
		(polygon
			(pts
				(xy 298.68622 -208.646776) (xy 298.68622 -208.09712) (xy 299.31614 -208.09712) (xy 299.31614 -208.646776)
			)
		)
	)
	(zone
		(layer "In11.Cu")
		(hatch none 0.5)
		(connect_pads
			(clearance 0)
		)
		(min_thickness 0.25)
		(keepout
			(tracks allowed)
			(vias allowed)
			(pads allowed)
			(copperpour allowed)
			(footprints allowed)
		)
		(placement
			(enabled no)
			(sheetname "")
		)
		(fill
			(thermal_gap 0.5)
			(thermal_bridge_width 0.5)
			(island_removal_mode 0)
		)
		(polygon
			(pts
				(xy 20.61845 -231.592374) (xy 20.61845 -231.052116) (xy 21.186394 -231.052116) (xy 21.486876 -231.052116)
				(xy 21.591016 -231.156256) (xy 21.591016 -231.421686) (xy 21.420328 -231.592374) (xy 21.17725 -231.592374)
			)
		)
	)
	(zone
		(layer "In11.Cu")
		(hatch none 0.5)
		(connect_pads
			(clearance 0)
		)
		(min_thickness 0.25)
		(keepout
			(tracks allowed)
			(vias allowed)
			(pads allowed)
			(copperpour allowed)
			(footprints allowed)
		)
		(placement
			(enabled no)
			(sheetname "")
		)
		(fill
			(thermal_gap 0.5)
			(thermal_bridge_width 0.5)
			(island_removal_mode 0)
		)
		(polygon
			(pts
				(xy 173.070774 -276.314662) (xy 173.070774 -276.590252) (xy 172.511974 -276.590252) (xy 172.511974 -276.314662)
			)
		)
	)
	(zone
		(layer "In11.Cu")
		(hatch none 0.5)
		(connect_pads
			(clearance 0)
		)
		(min_thickness 0.25)
		(keepout
			(tracks allowed)
			(vias allowed)
			(pads allowed)
			(copperpour allowed)
			(footprints allowed)
		)
		(placement
			(enabled no)
			(sheetname "")
		)
		(fill
			(thermal_gap 0.5)
			(thermal_bridge_width 0.5)
			(island_removal_mode 0)
		)
		(polygon
			(pts
				(xy 203.245974 -264.414762) (xy 203.245974 -264.690352) (xy 202.687174 -264.690352) (xy 202.687174 -264.414762)
			)
		)
	)
	(zone
		(layer "In11.Cu")
		(hatch none 0.5)
		(connect_pads
			(clearance 0)
		)
		(min_thickness 0.25)
		(keepout
			(tracks allowed)
			(vias allowed)
			(pads allowed)
			(copperpour allowed)
			(footprints allowed)
		)
		(placement
			(enabled no)
			(sheetname "")
		)
		(fill
			(thermal_gap 0.5)
			(thermal_bridge_width 0.5)
			(island_removal_mode 0)
		)
		(polygon
			(pts
				(xy 16.524224 -268.150594) (xy 16.524224 -267.600176) (xy 17.083024 -267.600176) (xy 17.083024 -268.150594)
			)
		)
	)
	(zone
		(layer "In11.Cu")
		(hatch none 0.5)
		(connect_pads
			(clearance 0)
		)
		(min_thickness 0.25)
		(keepout
			(tracks allowed)
			(vias allowed)
			(pads allowed)
			(copperpour allowed)
			(footprints allowed)
		)
		(placement
			(enabled no)
			(sheetname "")
		)
		(fill
			(thermal_gap 0.5)
			(thermal_bridge_width 0.5)
			(island_removal_mode 0)
		)
		(polygon
			(pts
				(xy 203.245974 -304.364644) (xy 203.245974 -304.640234) (xy 202.687174 -304.640234) (xy 202.687174 -304.364644)
			)
		)
	)
	(zone
		(layer "In11.Cu")
		(hatch none 0.5)
		(connect_pads
			(clearance 0)
		)
		(min_thickness 0.25)
		(keepout
			(tracks allowed)
			(vias allowed)
			(pads allowed)
			(copperpour allowed)
			(footprints allowed)
		)
		(placement
			(enabled no)
			(sheetname "")
		)
		(fill
			(thermal_gap 0.5)
			(thermal_bridge_width 0.5)
			(island_removal_mode 0)
		)
		(polygon
			(pts
				(xy 176.621186 -301.91837) (xy 176.621186 -301.64278) (xy 177.179986 -301.64278) (xy 177.179986 -301.91837)
			)
		)
	)
	(zone
		(layer "In11.Cu")
		(hatch none 0.5)
		(connect_pads
			(clearance 0)
		)
		(min_thickness 0.25)
		(keepout
			(tracks allowed)
			(vias allowed)
			(pads allowed)
			(copperpour allowed)
			(footprints allowed)
		)
		(placement
			(enabled no)
			(sheetname "")
		)
		(fill
			(thermal_gap 0.5)
			(thermal_bridge_width 0.5)
			(island_removal_mode 0)
		)
		(polygon
			(pts
				(xy 46.646084 -251.146818) (xy 46.646084 -250.597162) (xy 47.276004 -250.597162) (xy 47.276004 -251.146818)
			)
		)
	)
	(zone
		(layer "In11.Cu")
		(hatch none 0.5)
		(connect_pads
			(clearance 0)
		)
		(min_thickness 0.25)
		(keepout
			(tracks allowed)
			(vias allowed)
			(pads allowed)
			(copperpour allowed)
			(footprints allowed)
		)
		(placement
			(enabled no)
			(sheetname "")
		)
		(fill
			(thermal_gap 0.5)
			(thermal_bridge_width 0.5)
			(island_removal_mode 0)
		)
		(polygon
			(pts
				(xy 425.11091 -263.564624) (xy 425.11091 -263.840214) (xy 424.55211 -263.840214) (xy 424.55211 -263.564624)
			)
		)
	)
	(zone
		(layer "In11.Cu")
		(hatch none 0.5)
		(connect_pads
			(clearance 0)
		)
		(min_thickness 0.25)
		(keepout
			(tracks allowed)
			(vias allowed)
			(pads allowed)
			(copperpour allowed)
			(footprints allowed)
		)
		(placement
			(enabled no)
			(sheetname "")
		)
		(fill
			(thermal_gap 0.5)
			(thermal_bridge_width 0.5)
			(island_removal_mode 0)
		)
		(polygon
			(pts
				(xy 20.570952 -229.896924) (xy 20.570952 -229.347268) (xy 21.200872 -229.347268) (xy 21.200872 -229.896924)
			)
		)
	)
	(zone
		(layer "In11.Cu")
		(hatch none 0.5)
		(connect_pads
			(clearance 0)
		)
		(min_thickness 0.25)
		(keepout
			(tracks allowed)
			(vias allowed)
			(pads allowed)
			(copperpour allowed)
			(footprints allowed)
		)
		(placement
			(enabled no)
			(sheetname "")
		)
		(fill
			(thermal_gap 0.5)
			(thermal_bridge_width 0.5)
			(island_removal_mode 0)
		)
		(polygon
			(pts
				(xy 451.186042 -218.514676) (xy 451.186042 -218.790266) (xy 450.627242 -218.790266) (xy 450.627242 -218.514676)
			)
		)
	)
	(zone
		(layer "In11.Cu")
		(hatch none 0.5)
		(connect_pads
			(clearance 0)
		)
		(min_thickness 0.25)
		(keepout
			(tracks allowed)
			(vias allowed)
			(pads allowed)
			(copperpour allowed)
			(footprints allowed)
		)
		(placement
			(enabled no)
			(sheetname "")
		)
		(fill
			(thermal_gap 0.5)
			(thermal_bridge_width 0.5)
			(island_removal_mode 0)
		)
		(polygon
			(pts
				(xy 173.070774 -297.56481) (xy 173.070774 -297.8404) (xy 172.511974 -297.8404) (xy 172.511974 -297.56481)
			)
		)
	)
	(zone
		(layer "In11.Cu")
		(hatch none 0.5)
		(connect_pads
			(clearance 0)
		)
		(min_thickness 0.25)
		(keepout
			(tracks allowed)
			(vias allowed)
			(pads allowed)
			(copperpour allowed)
			(footprints allowed)
		)
		(placement
			(enabled no)
			(sheetname "")
		)
		(fill
			(thermal_gap 0.5)
			(thermal_bridge_width 0.5)
			(island_removal_mode 0)
		)
		(polygon
			(pts
				(xy 176.621186 -222.018606) (xy 176.621186 -221.743016) (xy 177.179986 -221.743016) (xy 177.179986 -222.018606)
			)
		)
	)
	(zone
		(layer "In11.Cu")
		(hatch none 0.5)
		(connect_pads
			(clearance 0)
		)
		(min_thickness 0.25)
		(keepout
			(tracks allowed)
			(vias allowed)
			(pads allowed)
			(copperpour allowed)
			(footprints allowed)
		)
		(placement
			(enabled no)
			(sheetname "")
		)
		(fill
			(thermal_gap 0.5)
			(thermal_bridge_width 0.5)
			(island_removal_mode 0)
		)
		(polygon
			(pts
				(xy 177.170842 -265.264646) (xy 177.170842 -265.540236) (xy 176.612042 -265.540236) (xy 176.612042 -265.264646)
			)
		)
	)
	(zone
		(layer "In11.Cu")
		(hatch none 0.5)
		(connect_pads
			(clearance 0)
		)
		(min_thickness 0.25)
		(keepout
			(tracks allowed)
			(vias allowed)
			(pads allowed)
			(copperpour allowed)
			(footprints allowed)
		)
		(placement
			(enabled no)
			(sheetname "")
		)
		(fill
			(thermal_gap 0.5)
			(thermal_bridge_width 0.5)
			(island_removal_mode 0)
		)
		(polygon
			(pts
				(xy 177.170842 -251.664724) (xy 177.170842 -251.940314) (xy 176.612042 -251.940314) (xy 176.612042 -251.664724)
			)
		)
	)
	(zone
		(layer "In11.Cu")
		(hatch none 0.5)
		(connect_pads
			(clearance 0)
		)
		(min_thickness 0.25)
		(keepout
			(tracks allowed)
			(vias allowed)
			(pads allowed)
			(copperpour allowed)
			(footprints allowed)
		)
		(placement
			(enabled no)
			(sheetname "")
		)
		(fill
			(thermal_gap 0.5)
			(thermal_bridge_width 0.5)
			(island_removal_mode 0)
		)
		(polygon
			(pts
				(xy 50.746152 -228.196902) (xy 50.746152 -227.647246) (xy 51.376072 -227.647246) (xy 51.376072 -228.196902)
			)
		)
	)
	(zone
		(layer "In11.Cu")
		(hatch none 0.5)
		(connect_pads
			(clearance 0)
		)
		(min_thickness 0.25)
		(keepout
			(tracks allowed)
			(vias allowed)
			(pads allowed)
			(copperpour allowed)
			(footprints allowed)
		)
		(placement
			(enabled no)
			(sheetname "")
		)
		(fill
			(thermal_gap 0.5)
			(thermal_bridge_width 0.5)
			(island_removal_mode 0)
		)
		(polygon
			(pts
				(xy 173.070774 -290.764722) (xy 173.070774 -291.040312) (xy 172.511974 -291.040312) (xy 172.511974 -290.764722)
			)
		)
	)
	(zone
		(layer "In11.Cu")
		(hatch none 0.5)
		(connect_pads
			(clearance 0)
		)
		(min_thickness 0.25)
		(keepout
			(tracks allowed)
			(vias allowed)
			(pads allowed)
			(copperpour allowed)
			(footprints allowed)
		)
		(placement
			(enabled no)
			(sheetname "")
		)
		(fill
			(thermal_gap 0.5)
			(thermal_bridge_width 0.5)
			(island_removal_mode 0)
		)
		(polygon
			(pts
				(xy 177.72888 -358.099868) (xy 177.72888 -357.132128) (xy 178.8922 -357.132128) (xy 178.8922 -358.099868)
			)
		)
	)
	(zone
		(layer "In11.Cu")
		(hatch none 0.5)
		(connect_pads
			(clearance 0)
		)
		(min_thickness 0.25)
		(keepout
			(tracks allowed)
			(vias allowed)
			(pads allowed)
			(copperpour allowed)
			(footprints allowed)
		)
		(placement
			(enabled no)
			(sheetname "")
		)
		(fill
			(thermal_gap 0.5)
			(thermal_bridge_width 0.5)
			(island_removal_mode 0)
		)
		(polygon
			(pts
				(xy 202.696318 -227.118418) (xy 202.696318 -226.842828) (xy 203.255118 -226.842828) (xy 203.255118 -227.118418)
			)
		)
	)
	(zone
		(layer "In11.Cu")
		(hatch none 0.5)
		(connect_pads
			(clearance 0)
		)
		(min_thickness 0.25)
		(keepout
			(tracks allowed)
			(vias allowed)
			(pads allowed)
			(copperpour allowed)
			(footprints allowed)
		)
		(placement
			(enabled no)
			(sheetname "")
		)
		(fill
			(thermal_gap 0.5)
			(thermal_bridge_width 0.5)
			(island_removal_mode 0)
		)
		(polygon
			(pts
				(xy 176.621186 -249.21845) (xy 176.621186 -248.94286) (xy 177.179986 -248.94286) (xy 177.179986 -249.21845)
			)
		)
	)
	(zone
		(layer "In11.Cu")
		(hatch none 0.5)
		(connect_pads
			(clearance 0)
		)
		(min_thickness 0.25)
		(keepout
			(tracks allowed)
			(vias allowed)
			(pads allowed)
			(copperpour allowed)
			(footprints allowed)
		)
		(placement
			(enabled no)
			(sheetname "")
		)
		(fill
			(thermal_gap 0.5)
			(thermal_bridge_width 0.5)
			(island_removal_mode 0)
		)
		(polygon
			(pts
				(xy 76.58862 -350.744028) (xy 76.58862 -349.235268) (xy 77.44206 -349.235268) (xy 77.44206 -350.744028)
			)
		)
	)
	(zone
		(layer "In11.Cu")
		(hatch none 0.5)
		(connect_pads
			(clearance 0)
		)
		(min_thickness 0.25)
		(keepout
			(tracks allowed)
			(vias allowed)
			(pads allowed)
			(copperpour allowed)
			(footprints allowed)
		)
		(placement
			(enabled no)
			(sheetname "")
		)
		(fill
			(thermal_gap 0.5)
			(thermal_bridge_width 0.5)
			(island_removal_mode 0)
		)
		(polygon
			(pts
				(xy 425.11091 -219.364814) (xy 425.11091 -219.640404) (xy 424.55211 -219.640404) (xy 424.55211 -219.364814)
			)
		)
	)
	(zone
		(layer "In11.Cu")
		(hatch none 0.5)
		(connect_pads
			(clearance 0)
		)
		(min_thickness 0.25)
		(keepout
			(tracks allowed)
			(vias allowed)
			(pads allowed)
			(copperpour allowed)
			(footprints allowed)
		)
		(placement
			(enabled no)
			(sheetname "")
		)
		(fill
			(thermal_gap 0.5)
			(thermal_bridge_width 0.5)
			(island_removal_mode 0)
		)
		(polygon
			(pts
				(xy 268.558518 -262.192262) (xy 268.558518 -261.652004) (xy 269.126462 -261.652004) (xy 269.426944 -261.652004)
				(xy 269.531084 -261.756144) (xy 269.531084 -262.021574) (xy 269.360396 -262.192262) (xy 269.117318 -262.192262)
			)
		)
	)
	(zone
		(layer "In11.Cu")
		(hatch none 0.5)
		(connect_pads
			(clearance 0)
		)
		(min_thickness 0.25)
		(keepout
			(tracks allowed)
			(vias allowed)
			(pads allowed)
			(copperpour allowed)
			(footprints allowed)
		)
		(placement
			(enabled no)
			(sheetname "")
		)
		(fill
			(thermal_gap 0.5)
			(thermal_bridge_width 0.5)
			(island_removal_mode 0)
		)
		(polygon
			(pts
				(xy 450.636386 -227.118418) (xy 450.636386 -226.842828) (xy 451.195186 -226.842828) (xy 451.195186 -227.118418)
			)
		)
	)
	(zone
		(layer "In11.Cu")
		(hatch none 0.5)
		(connect_pads
			(clearance 0)
		)
		(min_thickness 0.25)
		(keepout
			(tracks allowed)
			(vias allowed)
			(pads allowed)
			(copperpour allowed)
			(footprints allowed)
		)
		(placement
			(enabled no)
			(sheetname "")
		)
		(fill
			(thermal_gap 0.5)
			(thermal_bridge_width 0.5)
			(island_removal_mode 0)
		)
		(polygon
			(pts
				(xy 177.170842 -216.814654) (xy 177.170842 -217.090244) (xy 176.612042 -217.090244) (xy 176.612042 -216.814654)
			)
		)
	)
	(zone
		(layer "In11.Cu")
		(hatch none 0.5)
		(connect_pads
			(clearance 0)
		)
		(min_thickness 0.25)
		(keepout
			(tracks allowed)
			(vias allowed)
			(pads allowed)
			(copperpour allowed)
			(footprints allowed)
		)
		(placement
			(enabled no)
			(sheetname "")
		)
		(fill
			(thermal_gap 0.5)
			(thermal_bridge_width 0.5)
			(island_removal_mode 0)
		)
		(polygon
			(pts
				(xy 424.561254 -291.718492) (xy 424.561254 -291.442902) (xy 425.120054 -291.442902) (xy 425.120054 -291.718492)
			)
		)
	)
	(zone
		(layer "In11.Cu")
		(hatch none 0.5)
		(connect_pads
			(clearance 0)
		)
		(min_thickness 0.25)
		(keepout
			(tracks allowed)
			(vias allowed)
			(pads allowed)
			(copperpour allowed)
			(footprints allowed)
		)
		(placement
			(enabled no)
			(sheetname "")
		)
		(fill
			(thermal_gap 0.5)
			(thermal_bridge_width 0.5)
			(island_removal_mode 0)
		)
		(polygon
			(pts
				(xy 46.646084 -207.796892) (xy 46.646084 -207.247236) (xy 47.276004 -207.247236) (xy 47.276004 -207.796892)
			)
		)
	)
	(zone
		(layer "In11.Cu")
		(hatch none 0.5)
		(connect_pads
			(clearance 0)
		)
		(min_thickness 0.25)
		(keepout
			(tracks allowed)
			(vias allowed)
			(pads allowed)
			(copperpour allowed)
			(footprints allowed)
		)
		(placement
			(enabled no)
			(sheetname "")
		)
		(fill
			(thermal_gap 0.5)
			(thermal_bridge_width 0.5)
			(island_removal_mode 0)
		)
		(polygon
			(pts
				(xy 294.586152 -310.646826) (xy 294.586152 -310.09717) (xy 295.216072 -310.09717) (xy 295.216072 -310.646826)
			)
		)
	)
	(zone
		(layer "In11.Cu")
		(hatch none 0.5)
		(connect_pads
			(clearance 0)
		)
		(min_thickness 0.25)
		(keepout
			(tracks allowed)
			(vias allowed)
			(pads allowed)
			(copperpour allowed)
			(footprints allowed)
		)
		(placement
			(enabled no)
			(sheetname "")
		)
		(fill
			(thermal_gap 0.5)
			(thermal_bridge_width 0.5)
			(island_removal_mode 0)
		)
		(polygon
			(pts
				(xy 177.170842 -203.214732) (xy 177.170842 -203.490322) (xy 176.612042 -203.490322) (xy 176.612042 -203.214732)
			)
		)
	)
	(zone
		(layer "In11.Cu")
		(hatch none 0.5)
		(connect_pads
			(clearance 0)
		)
		(min_thickness 0.25)
		(keepout
			(tracks allowed)
			(vias allowed)
			(pads allowed)
			(copperpour allowed)
			(footprints allowed)
		)
		(placement
			(enabled no)
			(sheetname "")
		)
		(fill
			(thermal_gap 0.5)
			(thermal_bridge_width 0.5)
			(island_removal_mode 0)
		)
		(polygon
			(pts
				(xy 298.68622 -199.296782) (xy 298.68622 -198.747126) (xy 299.31614 -198.747126) (xy 299.31614 -199.296782)
			)
		)
	)
	(zone
		(layer "In11.Cu")
		(hatch none 0.5)
		(connect_pads
			(clearance 0)
		)
		(min_thickness 0.25)
		(keepout
			(tracks allowed)
			(vias allowed)
			(pads allowed)
			(copperpour allowed)
			(footprints allowed)
		)
		(placement
			(enabled no)
			(sheetname "")
		)
		(fill
			(thermal_gap 0.5)
			(thermal_bridge_width 0.5)
			(island_removal_mode 0)
		)
		(polygon
			(pts
				(xy 424.561254 -300.218348) (xy 424.561254 -299.942758) (xy 425.120054 -299.942758) (xy 425.120054 -300.218348)
			)
		)
	)
	(zone
		(layer "In11.Cu")
		(hatch none 0.5)
		(connect_pads
			(clearance 0)
		)
		(min_thickness 0.25)
		(keepout
			(tracks allowed)
			(vias allowed)
			(pads allowed)
			(copperpour allowed)
			(footprints allowed)
		)
		(placement
			(enabled no)
			(sheetname "")
		)
		(fill
			(thermal_gap 0.5)
			(thermal_bridge_width 0.5)
			(island_removal_mode 0)
		)
		(polygon
			(pts
				(xy 50.771552 -312.346848) (xy 50.771552 -311.797192) (xy 51.401472 -311.797192) (xy 51.401472 -312.346848)
			)
		)
	)
	(zone
		(layer "In11.Cu")
		(hatch none 0.5)
		(connect_pads
			(clearance 0)
		)
		(min_thickness 0.25)
		(keepout
			(tracks allowed)
			(vias allowed)
			(pads allowed)
			(copperpour allowed)
			(footprints allowed)
		)
		(placement
			(enabled no)
			(sheetname "")
		)
		(fill
			(thermal_gap 0.5)
			(thermal_bridge_width 0.5)
			(island_removal_mode 0)
		)
		(polygon
			(pts
				(xy 50.771552 -272.396966) (xy 50.771552 -271.84731) (xy 51.401472 -271.84731) (xy 51.401472 -272.396966)
			)
		)
	)
	(zone
		(layer "In11.Cu")
		(hatch none 0.5)
		(connect_pads
			(clearance 0)
		)
		(min_thickness 0.25)
		(keepout
			(tracks allowed)
			(vias allowed)
			(pads allowed)
			(copperpour allowed)
			(footprints allowed)
		)
		(placement
			(enabled no)
			(sheetname "")
		)
		(fill
			(thermal_gap 0.5)
			(thermal_bridge_width 0.5)
			(island_removal_mode 0)
		)
		(polygon
			(pts
				(xy 450.636386 -302.492918) (xy 451.195186 -302.492918) (xy 451.195186 -302.768508) (xy 451.195186 -303.07661)
				(xy 450.562726 -303.07661) (xy 450.562726 -302.492918)
			)
		)
	)
	(zone
		(layer "In11.Cu")
		(hatch none 0.5)
		(connect_pads
			(clearance 0)
		)
		(min_thickness 0.25)
		(keepout
			(tracks allowed)
			(vias allowed)
			(pads allowed)
			(copperpour allowed)
			(footprints allowed)
		)
		(placement
			(enabled no)
			(sheetname "")
		)
		(fill
			(thermal_gap 0.5)
			(thermal_bridge_width 0.5)
			(island_removal_mode 0)
		)
		(polygon
			(pts
				(xy 294.586152 -263.046972) (xy 294.586152 -262.497316) (xy 295.216072 -262.497316) (xy 295.216072 -263.046972)
			)
		)
	)
	(zone
		(layer "In11.Cu")
		(hatch none 0.5)
		(connect_pads
			(clearance 0)
		)
		(min_thickness 0.25)
		(keepout
			(tracks allowed)
			(vias allowed)
			(pads allowed)
			(copperpour allowed)
			(footprints allowed)
		)
		(placement
			(enabled no)
			(sheetname "")
		)
		(fill
			(thermal_gap 0.5)
			(thermal_bridge_width 0.5)
			(island_removal_mode 0)
		)
		(polygon
			(pts
				(xy 421.010842 -290.764722) (xy 421.010842 -291.040312) (xy 420.452042 -291.040312) (xy 420.452042 -290.764722)
			)
		)
	)
	(zone
		(layer "In11.Cu")
		(hatch none 0.5)
		(connect_pads
			(clearance 0)
		)
		(min_thickness 0.25)
		(keepout
			(tracks allowed)
			(vias allowed)
			(pads allowed)
			(copperpour allowed)
			(footprints allowed)
		)
		(placement
			(enabled no)
			(sheetname "")
		)
		(fill
			(thermal_gap 0.5)
			(thermal_bridge_width 0.5)
			(island_removal_mode 0)
		)
		(polygon
			(pts
				(xy 50.746152 -285.996888) (xy 50.746152 -285.447232) (xy 51.376072 -285.447232) (xy 51.376072 -285.996888)
			)
		)
	)
	(zone
		(layer "In11.Cu")
		(hatch none 0.5)
		(connect_pads
			(clearance 0)
		)
		(min_thickness 0.25)
		(keepout
			(tracks allowed)
			(vias allowed)
			(pads allowed)
			(copperpour allowed)
			(footprints allowed)
		)
		(placement
			(enabled no)
			(sheetname "")
		)
		(fill
			(thermal_gap 0.5)
			(thermal_bridge_width 0.5)
			(island_removal_mode 0)
		)
		(polygon
			(pts
				(xy 20.624292 -292.800786) (xy 20.624292 -292.250368) (xy 21.183092 -292.250368) (xy 21.183092 -292.800786)
			)
		)
	)
	(zone
		(layer "In11.Cu")
		(hatch none 0.5)
		(connect_pads
			(clearance 0)
		)
		(min_thickness 0.25)
		(keepout
			(tracks allowed)
			(vias allowed)
			(pads allowed)
			(copperpour allowed)
			(footprints allowed)
		)
		(placement
			(enabled no)
			(sheetname "")
		)
		(fill
			(thermal_gap 0.5)
			(thermal_bridge_width 0.5)
			(island_removal_mode 0)
		)
		(polygon
			(pts
				(xy 451.186042 -204.914754) (xy 451.186042 -205.190344) (xy 450.627242 -205.190344) (xy 450.627242 -204.914754)
			)
		)
	)
	(zone
		(layer "In11.Cu")
		(hatch none 0.5)
		(connect_pads
			(clearance 0)
		)
		(min_thickness 0.25)
		(keepout
			(tracks allowed)
			(vias allowed)
			(pads allowed)
			(copperpour allowed)
			(footprints allowed)
		)
		(placement
			(enabled no)
			(sheetname "")
		)
		(fill
			(thermal_gap 0.5)
			(thermal_bridge_width 0.5)
			(island_removal_mode 0)
		)
		(polygon
			(pts
				(xy 202.696318 -242.418616) (xy 202.696318 -242.143026) (xy 203.255118 -242.143026) (xy 203.255118 -242.418616)
			)
		)
	)
	(zone
		(layer "In11.Cu")
		(hatch none 0.5)
		(connect_pads
			(clearance 0)
		)
		(min_thickness 0.25)
		(keepout
			(tracks allowed)
			(vias allowed)
			(pads allowed)
			(copperpour allowed)
			(footprints allowed)
		)
		(placement
			(enabled no)
			(sheetname "")
		)
		(fill
			(thermal_gap 0.5)
			(thermal_bridge_width 0.5)
			(island_removal_mode 0)
		)
		(polygon
			(pts
				(xy 202.696318 -227.968556) (xy 202.696318 -227.692966) (xy 203.255118 -227.692966) (xy 203.255118 -227.968556)
			)
		)
	)
	(zone
		(layer "In11.Cu")
		(hatch none 0.5)
		(connect_pads
			(clearance 0)
		)
		(min_thickness 0.25)
		(keepout
			(tracks allowed)
			(vias allowed)
			(pads allowed)
			(copperpour allowed)
			(footprints allowed)
		)
		(placement
			(enabled no)
			(sheetname "")
		)
		(fill
			(thermal_gap 0.5)
			(thermal_bridge_width 0.5)
			(island_removal_mode 0)
		)
		(polygon
			(pts
				(xy 421.010842 -205.764638) (xy 421.010842 -206.040228) (xy 420.452042 -206.040228) (xy 420.452042 -205.764638)
			)
		)
	)
	(zone
		(layer "In11.Cu")
		(hatch none 0.5)
		(connect_pads
			(clearance 0)
		)
		(min_thickness 0.25)
		(keepout
			(tracks allowed)
			(vias allowed)
			(pads allowed)
			(copperpour allowed)
			(footprints allowed)
		)
		(placement
			(enabled no)
			(sheetname "")
		)
		(fill
			(thermal_gap 0.5)
			(thermal_bridge_width 0.5)
			(island_removal_mode 0)
		)
		(polygon
			(pts
				(xy 294.586152 -237.546896) (xy 294.586152 -236.99724) (xy 295.216072 -236.99724) (xy 295.216072 -237.546896)
			)
		)
	)
	(zone
		(layer "In11.Cu")
		(hatch none 0.5)
		(connect_pads
			(clearance 0)
		)
		(min_thickness 0.25)
		(keepout
			(tracks allowed)
			(vias allowed)
			(pads allowed)
			(copperpour allowed)
			(footprints allowed)
		)
		(placement
			(enabled no)
			(sheetname "")
		)
		(fill
			(thermal_gap 0.5)
			(thermal_bridge_width 0.5)
			(island_removal_mode 0)
		)
		(polygon
			(pts
				(xy 173.070774 -232.964736) (xy 173.070774 -233.240326) (xy 172.511974 -233.240326) (xy 172.511974 -232.964736)
			)
		)
	)
	(zone
		(layer "In11.Cu")
		(hatch none 0.5)
		(connect_pads
			(clearance 0)
		)
		(min_thickness 0.25)
		(keepout
			(tracks allowed)
			(vias allowed)
			(pads allowed)
			(copperpour allowed)
			(footprints allowed)
		)
		(placement
			(enabled no)
			(sheetname "")
		)
		(fill
			(thermal_gap 0.5)
			(thermal_bridge_width 0.5)
			(island_removal_mode 0)
		)
		(polygon
			(pts
				(xy 432.65471 -260.164834) (xy 432.65471 -260.440424) (xy 432.09591 -260.440424) (xy 432.09591 -260.164834)
			)
		)
	)
	(zone
		(layer "In11.Cu")
		(hatch none 0.5)
		(connect_pads
			(clearance 0)
		)
		(min_thickness 0.25)
		(keepout
			(tracks allowed)
			(vias allowed)
			(pads allowed)
			(copperpour allowed)
			(footprints allowed)
		)
		(placement
			(enabled no)
			(sheetname "")
		)
		(fill
			(thermal_gap 0.5)
			(thermal_bridge_width 0.5)
			(island_removal_mode 0)
		)
		(polygon
			(pts
				(xy 50.771552 -297.046904) (xy 50.771552 -296.497248) (xy 51.401472 -296.497248) (xy 51.401472 -297.046904)
			)
		)
	)
	(zone
		(layer "In11.Cu")
		(hatch none 0.5)
		(connect_pads
			(clearance 0)
		)
		(min_thickness 0.25)
		(keepout
			(tracks allowed)
			(vias allowed)
			(pads allowed)
			(copperpour allowed)
			(footprints allowed)
		)
		(placement
			(enabled no)
			(sheetname "")
		)
		(fill
			(thermal_gap 0.5)
			(thermal_bridge_width 0.5)
			(island_removal_mode 0)
		)
		(polygon
			(pts
				(xy 173.070774 -301.814738) (xy 173.070774 -302.090328) (xy 172.511974 -302.090328) (xy 172.511974 -301.814738)
			)
		)
	)
	(zone
		(layer "In11.Cu")
		(hatch none 0.5)
		(connect_pads
			(clearance 0)
		)
		(min_thickness 0.25)
		(keepout
			(tracks allowed)
			(vias allowed)
			(pads allowed)
			(copperpour allowed)
			(footprints allowed)
		)
		(placement
			(enabled no)
			(sheetname "")
		)
		(fill
			(thermal_gap 0.5)
			(thermal_bridge_width 0.5)
			(island_removal_mode 0)
		)
		(polygon
			(pts
				(xy 173.070774 -286.514794) (xy 173.070774 -286.790384) (xy 172.511974 -286.790384) (xy 172.511974 -286.514794)
			)
		)
	)
	(zone
		(layer "In11.Cu")
		(hatch none 0.5)
		(connect_pads
			(clearance 0)
		)
		(min_thickness 0.25)
		(keepout
			(tracks allowed)
			(vias allowed)
			(pads allowed)
			(copperpour allowed)
			(footprints allowed)
		)
		(placement
			(enabled no)
			(sheetname "")
		)
		(fill
			(thermal_gap 0.5)
			(thermal_bridge_width 0.5)
			(island_removal_mode 0)
		)
		(polygon
			(pts
				(xy 46.646084 -237.546896) (xy 46.646084 -236.99724) (xy 47.276004 -236.99724) (xy 47.276004 -237.546896)
			)
		)
	)
	(zone
		(layer "In11.Cu")
		(hatch none 0.5)
		(connect_pads
			(clearance 0)
		)
		(min_thickness 0.25)
		(keepout
			(tracks allowed)
			(vias allowed)
			(pads allowed)
			(copperpour allowed)
			(footprints allowed)
		)
		(placement
			(enabled no)
			(sheetname "")
		)
		(fill
			(thermal_gap 0.5)
			(thermal_bridge_width 0.5)
			(island_removal_mode 0)
		)
		(polygon
			(pts
				(xy 424.561254 -262.818626) (xy 424.561254 -262.543036) (xy 425.120054 -262.543036) (xy 425.120054 -262.818626)
			)
		)
	)
	(zone
		(layer "In11.Cu")
		(hatch none 0.5)
		(connect_pads
			(clearance 0)
		)
		(min_thickness 0.25)
		(keepout
			(tracks allowed)
			(vias allowed)
			(pads allowed)
			(copperpour allowed)
			(footprints allowed)
		)
		(placement
			(enabled no)
			(sheetname "")
		)
		(fill
			(thermal_gap 0.5)
			(thermal_bridge_width 0.5)
			(island_removal_mode 0)
		)
		(polygon
			(pts
				(xy 173.070774 -295.864788) (xy 173.070774 -296.140378) (xy 172.511974 -296.140378) (xy 172.511974 -295.864788)
			)
		)
	)
	(zone
		(layer "In11.Cu")
		(hatch none 0.5)
		(connect_pads
			(clearance 0)
		)
		(min_thickness 0.25)
		(keepout
			(tracks allowed)
			(vias allowed)
			(pads allowed)
			(copperpour allowed)
			(footprints allowed)
		)
		(placement
			(enabled no)
			(sheetname "")
		)
		(fill
			(thermal_gap 0.5)
			(thermal_bridge_width 0.5)
			(island_removal_mode 0)
		)
		(polygon
			(pts
				(xy 268.56436 -265.579352) (xy 268.56436 -265.042142) (xy 269.12316 -265.042142) (xy 269.12316 -265.579352)
			)
		)
	)
	(zone
		(layer "In11.Cu")
		(hatch none 0.5)
		(connect_pads
			(clearance 0)
		)
		(min_thickness 0.25)
		(keepout
			(tracks allowed)
			(vias allowed)
			(pads allowed)
			(copperpour allowed)
			(footprints allowed)
		)
		(placement
			(enabled no)
			(sheetname "")
		)
		(fill
			(thermal_gap 0.5)
			(thermal_bridge_width 0.5)
			(island_removal_mode 0)
		)
		(polygon
			(pts
				(xy 424.561254 -234.76839) (xy 424.561254 -234.4928) (xy 425.120054 -234.4928) (xy 425.120054 -234.76839)
			)
		)
	)
	(zone
		(layer "In11.Cu")
		(hatch none 0.5)
		(connect_pads
			(clearance 0)
		)
		(min_thickness 0.25)
		(keepout
			(tracks allowed)
			(vias allowed)
			(pads allowed)
			(copperpour allowed)
			(footprints allowed)
		)
		(placement
			(enabled no)
			(sheetname "")
		)
		(fill
			(thermal_gap 0.5)
			(thermal_bridge_width 0.5)
			(island_removal_mode 0)
		)
		(polygon
			(pts
				(xy 451.186042 -203.214732) (xy 451.186042 -203.490322) (xy 450.627242 -203.490322) (xy 450.627242 -203.214732)
			)
		)
	)
	(zone
		(layer "In11.Cu")
		(hatch none 0.5)
		(connect_pads
			(clearance 0)
		)
		(min_thickness 0.25)
		(keepout
			(tracks allowed)
			(vias allowed)
			(pads allowed)
			(copperpour allowed)
			(footprints allowed)
		)
		(placement
			(enabled no)
			(sheetname "")
		)
		(fill
			(thermal_gap 0.5)
			(thermal_bridge_width 0.5)
			(island_removal_mode 0)
		)
		(polygon
			(pts
				(xy 176.621186 -273.018504) (xy 176.621186 -272.742914) (xy 177.179986 -272.742914) (xy 177.179986 -273.018504)
			)
		)
	)
	(zone
		(layer "In11.Cu")
		(hatch none 0.5)
		(connect_pads
			(clearance 0)
		)
		(min_thickness 0.25)
		(keepout
			(tracks allowed)
			(vias allowed)
			(pads allowed)
			(copperpour allowed)
			(footprints allowed)
		)
		(placement
			(enabled no)
			(sheetname "")
		)
		(fill
			(thermal_gap 0.5)
			(thermal_bridge_width 0.5)
			(island_removal_mode 0)
		)
		(polygon
			(pts
				(xy 298.68622 -229.896924) (xy 298.68622 -229.347268) (xy 299.31614 -229.347268) (xy 299.31614 -229.896924)
			)
		)
	)
	(zone
		(layer "In11.Cu")
		(hatch none 0.5)
		(connect_pads
			(clearance 0)
		)
		(min_thickness 0.25)
		(keepout
			(tracks allowed)
			(vias allowed)
			(pads allowed)
			(copperpour allowed)
			(footprints allowed)
		)
		(placement
			(enabled no)
			(sheetname "")
		)
		(fill
			(thermal_gap 0.5)
			(thermal_bridge_width 0.5)
			(island_removal_mode 0)
		)
		(polygon
			(pts
				(xy 203.245974 -197.264782) (xy 203.245974 -197.540372) (xy 202.687174 -197.540372) (xy 202.687174 -197.264782)
			)
		)
	)
	(zone
		(layer "In11.Cu")
		(hatch none 0.5)
		(connect_pads
			(clearance 0)
		)
		(min_thickness 0.25)
		(keepout
			(tracks allowed)
			(vias allowed)
			(pads allowed)
			(copperpour allowed)
			(footprints allowed)
		)
		(placement
			(enabled no)
			(sheetname "")
		)
		(fill
			(thermal_gap 0.5)
			(thermal_bridge_width 0.5)
			(island_removal_mode 0)
		)
		(polygon
			(pts
				(xy 435.548786 -308.718458) (xy 435.548786 -308.442868) (xy 436.107586 -308.442868) (xy 436.107586 -308.718458)
			)
		)
	)
	(zone
		(layer "In11.Cu")
		(hatch none 0.5)
		(connect_pads
			(clearance 0)
		)
		(min_thickness 0.25)
		(keepout
			(tracks allowed)
			(vias allowed)
			(pads allowed)
			(copperpour allowed)
			(footprints allowed)
		)
		(placement
			(enabled no)
			(sheetname "")
		)
		(fill
			(thermal_gap 0.5)
			(thermal_bridge_width 0.5)
			(island_removal_mode 0)
		)
		(polygon
			(pts
				(xy 176.621186 -266.218416) (xy 176.621186 -265.942826) (xy 177.179986 -265.942826) (xy 177.179986 -266.218416)
			)
		)
	)
	(zone
		(layer "In11.Cu")
		(hatch none 0.5)
		(connect_pads
			(clearance 0)
		)
		(min_thickness 0.25)
		(keepout
			(tracks allowed)
			(vias allowed)
			(pads allowed)
			(copperpour allowed)
			(footprints allowed)
		)
		(placement
			(enabled no)
			(sheetname "")
		)
		(fill
			(thermal_gap 0.5)
			(thermal_bridge_width 0.5)
			(island_removal_mode 0)
		)
		(polygon
			(pts
				(xy 420.384986 -261.118604) (xy 420.384986 -260.843014) (xy 420.943786 -260.843014) (xy 420.943786 -261.118604)
			)
		)
	)
	(zone
		(layer "In11.Cu")
		(hatch none 0.5)
		(connect_pads
			(clearance 0)
		)
		(min_thickness 0.25)
		(keepout
			(tracks allowed)
			(vias allowed)
			(pads allowed)
			(copperpour allowed)
			(footprints allowed)
		)
		(placement
			(enabled no)
			(sheetname "")
		)
		(fill
			(thermal_gap 0.5)
			(thermal_bridge_width 0.5)
			(island_removal_mode 0)
		)
		(polygon
			(pts
				(xy 421.010842 -303.51476) (xy 421.010842 -303.79035) (xy 420.452042 -303.79035) (xy 420.452042 -303.51476)
			)
		)
	)
	(zone
		(layer "In11.Cu")
		(hatch none 0.5)
		(connect_pads
			(clearance 0)
		)
		(min_thickness 0.25)
		(keepout
			(tracks allowed)
			(vias allowed)
			(pads allowed)
			(copperpour allowed)
			(footprints allowed)
		)
		(placement
			(enabled no)
			(sheetname "")
		)
		(fill
			(thermal_gap 0.5)
			(thermal_bridge_width 0.5)
			(island_removal_mode 0)
		)
		(polygon
			(pts
				(xy 421.010842 -250.81484) (xy 421.010842 -251.09043) (xy 420.452042 -251.09043) (xy 420.452042 -250.81484)
			)
		)
	)
	(zone
		(layer "In11.Cu")
		(hatch none 0.5)
		(connect_pads
			(clearance 0)
		)
		(min_thickness 0.25)
		(keepout
			(tracks allowed)
			(vias allowed)
			(pads allowed)
			(copperpour allowed)
			(footprints allowed)
		)
		(placement
			(enabled no)
			(sheetname "")
		)
		(fill
			(thermal_gap 0.5)
			(thermal_bridge_width 0.5)
			(island_removal_mode 0)
		)
		(polygon
			(pts
				(xy 50.771552 -274.947126) (xy 50.771552 -274.39747) (xy 51.401472 -274.39747) (xy 51.401472 -274.947126)
			)
		)
	)
	(zone
		(layer "In11.Cu")
		(hatch none 0.5)
		(connect_pads
			(clearance 0)
		)
		(min_thickness 0.25)
		(keepout
			(tracks allowed)
			(vias allowed)
			(pads allowed)
			(copperpour allowed)
			(footprints allowed)
		)
		(placement
			(enabled no)
			(sheetname "")
		)
		(fill
			(thermal_gap 0.5)
			(thermal_bridge_width 0.5)
			(island_removal_mode 0)
		)
		(polygon
			(pts
				(xy 450.636386 -268.768576) (xy 450.636386 -268.492986) (xy 451.195186 -268.492986) (xy 451.195186 -268.768576)
			)
		)
	)
	(zone
		(layer "In11.Cu")
		(hatch none 0.5)
		(connect_pads
			(clearance 0)
		)
		(min_thickness 0.25)
		(keepout
			(tracks allowed)
			(vias allowed)
			(pads allowed)
			(copperpour allowed)
			(footprints allowed)
		)
		(placement
			(enabled no)
			(sheetname "")
		)
		(fill
			(thermal_gap 0.5)
			(thermal_bridge_width 0.5)
			(island_removal_mode 0)
		)
		(polygon
			(pts
				(xy 46.646084 -252.84684) (xy 46.646084 -252.297184) (xy 47.276004 -252.297184) (xy 47.276004 -252.84684)
			)
		)
	)
	(zone
		(layer "In11.Cu")
		(hatch none 0.5)
		(connect_pads
			(clearance 0)
		)
		(min_thickness 0.25)
		(keepout
			(tracks allowed)
			(vias allowed)
			(pads allowed)
			(copperpour allowed)
			(footprints allowed)
		)
		(placement
			(enabled no)
			(sheetname "")
		)
		(fill
			(thermal_gap 0.5)
			(thermal_bridge_width 0.5)
			(island_removal_mode 0)
		)
		(polygon
			(pts
				(xy 420.461186 -267.068554) (xy 420.461186 -266.792964) (xy 421.019986 -266.792964) (xy 421.019986 -267.068554)
			)
		)
	)
	(zone
		(layer "In11.Cu")
		(hatch none 0.5)
		(connect_pads
			(clearance 0)
		)
		(min_thickness 0.25)
		(keepout
			(tracks allowed)
			(vias allowed)
			(pads allowed)
			(copperpour allowed)
			(footprints allowed)
		)
		(placement
			(enabled no)
			(sheetname "")
		)
		(fill
			(thermal_gap 0.5)
			(thermal_bridge_width 0.5)
			(island_removal_mode 0)
		)
		(polygon
			(pts
				(xy 298.68622 -222.246952) (xy 298.68622 -221.697296) (xy 299.31614 -221.697296) (xy 299.31614 -222.246952)
			)
		)
	)
	(zone
		(layer "In11.Cu")
		(hatch none 0.5)
		(connect_pads
			(clearance 0)
		)
		(min_thickness 0.25)
		(keepout
			(tracks allowed)
			(vias allowed)
			(pads allowed)
			(copperpour allowed)
			(footprints allowed)
		)
		(placement
			(enabled no)
			(sheetname "")
		)
		(fill
			(thermal_gap 0.5)
			(thermal_bridge_width 0.5)
			(island_removal_mode 0)
		)
		(polygon
			(pts
				(xy 421.010842 -306.914804) (xy 421.010842 -307.190394) (xy 420.452042 -307.190394) (xy 420.452042 -306.914804)
			)
		)
	)
	(zone
		(layer "In11.Cu")
		(hatch none 0.5)
		(connect_pads
			(clearance 0)
		)
		(min_thickness 0.25)
		(keepout
			(tracks allowed)
			(vias allowed)
			(pads allowed)
			(copperpour allowed)
			(footprints allowed)
		)
		(placement
			(enabled no)
			(sheetname "")
		)
		(fill
			(thermal_gap 0.5)
			(thermal_bridge_width 0.5)
			(island_removal_mode 0)
		)
		(polygon
			(pts
				(xy 268.563598 -252.001782) (xy 268.563598 -251.43333) (xy 269.089378 -251.43333) (xy 269.089378 -252.001782)
			)
		)
	)
	(zone
		(layer "In11.Cu")
		(hatch none 0.5)
		(connect_pads
			(clearance 0)
		)
		(min_thickness 0.25)
		(keepout
			(tracks allowed)
			(vias allowed)
			(pads allowed)
			(copperpour allowed)
			(footprints allowed)
		)
		(placement
			(enabled no)
			(sheetname "")
		)
		(fill
			(thermal_gap 0.5)
			(thermal_bridge_width 0.5)
			(island_removal_mode 0)
		)
		(polygon
			(pts
				(xy 425.11091 -295.864788) (xy 425.11091 -296.140378) (xy 424.55211 -296.140378) (xy 424.55211 -295.864788)
			)
		)
	)
	(zone
		(layer "In11.Cu")
		(hatch none 0.5)
		(connect_pads
			(clearance 0)
		)
		(min_thickness 0.25)
		(keepout
			(tracks allowed)
			(vias allowed)
			(pads allowed)
			(copperpour allowed)
			(footprints allowed)
		)
		(placement
			(enabled no)
			(sheetname "")
		)
		(fill
			(thermal_gap 0.5)
			(thermal_bridge_width 0.5)
			(island_removal_mode 0)
		)
		(polygon
			(pts
				(xy 20.61845 -222.24238) (xy 20.61845 -221.702122) (xy 21.186394 -221.702122) (xy 21.486876 -221.702122)
				(xy 21.591016 -221.806262) (xy 21.591016 -222.071692) (xy 21.420328 -222.24238) (xy 21.17725 -222.24238)
			)
		)
	)
	(zone
		(layer "In11.Cu")
		(hatch none 0.5)
		(connect_pads
			(clearance 0)
		)
		(min_thickness 0.25)
		(keepout
			(tracks allowed)
			(vias allowed)
			(pads allowed)
			(copperpour allowed)
			(footprints allowed)
		)
		(placement
			(enabled no)
			(sheetname "")
		)
		(fill
			(thermal_gap 0.5)
			(thermal_bridge_width 0.5)
			(island_removal_mode 0)
		)
		(polygon
			(pts
				(xy 294.586152 -288.546794) (xy 294.586152 -287.997138) (xy 295.216072 -287.997138) (xy 295.216072 -288.546794)
			)
		)
	)
	(zone
		(layer "In11.Cu")
		(hatch none 0.5)
		(connect_pads
			(clearance 0)
		)
		(min_thickness 0.25)
		(keepout
			(tracks allowed)
			(vias allowed)
			(pads allowed)
			(copperpour allowed)
			(footprints allowed)
		)
		(placement
			(enabled no)
			(sheetname "")
		)
		(fill
			(thermal_gap 0.5)
			(thermal_bridge_width 0.5)
			(island_removal_mode 0)
		)
		(polygon
			(pts
				(xy 203.245974 -267.814806) (xy 203.245974 -268.090396) (xy 202.687174 -268.090396) (xy 202.128882 -268.090396)
				(xy 202.128882 -267.599414) (xy 203.245974 -267.599414)
			)
		)
	)
	(zone
		(layer "In11.Cu")
		(hatch none 0.5)
		(connect_pads
			(clearance 0)
		)
		(min_thickness 0.25)
		(keepout
			(tracks allowed)
			(vias allowed)
			(pads allowed)
			(copperpour allowed)
			(footprints allowed)
		)
		(placement
			(enabled no)
			(sheetname "")
		)
		(fill
			(thermal_gap 0.5)
			(thermal_bridge_width 0.5)
			(island_removal_mode 0)
		)
		(polygon
			(pts
				(xy 203.245974 -246.564658) (xy 203.245974 -246.840248) (xy 202.687174 -246.840248) (xy 202.687174 -246.564658)
			)
		)
	)
	(zone
		(layer "In11.Cu")
		(hatch none 0.5)
		(connect_pads
			(clearance 0)
		)
		(min_thickness 0.25)
		(keepout
			(tracks allowed)
			(vias allowed)
			(pads allowed)
			(copperpour allowed)
			(footprints allowed)
		)
		(placement
			(enabled no)
			(sheetname "")
		)
		(fill
			(thermal_gap 0.5)
			(thermal_bridge_width 0.5)
			(island_removal_mode 0)
		)
		(polygon
			(pts
				(xy 203.245974 -278.014684) (xy 203.245974 -278.290274) (xy 202.687174 -278.290274) (xy 202.687174 -278.014684)
			)
		)
	)
	(zone
		(layer "In11.Cu")
		(hatch none 0.5)
		(connect_pads
			(clearance 0)
		)
		(min_thickness 0.25)
		(keepout
			(tracks allowed)
			(vias allowed)
			(pads allowed)
			(copperpour allowed)
			(footprints allowed)
		)
		(placement
			(enabled no)
			(sheetname "")
		)
		(fill
			(thermal_gap 0.5)
			(thermal_bridge_width 0.5)
			(island_removal_mode 0)
		)
		(polygon
			(pts
				(xy 176.621186 -290.01847) (xy 176.621186 -289.74288) (xy 177.179986 -289.74288) (xy 177.179986 -290.01847)
			)
		)
	)
	(zone
		(layer "In11.Cu")
		(hatch none 0.5)
		(connect_pads
			(clearance 0)
		)
		(min_thickness 0.25)
		(keepout
			(tracks allowed)
			(vias allowed)
			(pads allowed)
			(copperpour allowed)
			(footprints allowed)
		)
		(placement
			(enabled no)
			(sheetname "")
		)
		(fill
			(thermal_gap 0.5)
			(thermal_bridge_width 0.5)
			(island_removal_mode 0)
		)
		(polygon
			(pts
				(xy 424.561254 -310.41848) (xy 424.561254 -310.14289) (xy 425.120054 -310.14289) (xy 425.120054 -310.41848)
			)
		)
	)
	(zone
		(layer "In11.Cu")
		(hatch none 0.5)
		(connect_pads
			(clearance 0)
		)
		(min_thickness 0.25)
		(keepout
			(tracks allowed)
			(vias allowed)
			(pads allowed)
			(copperpour allowed)
			(footprints allowed)
		)
		(placement
			(enabled no)
			(sheetname "")
		)
		(fill
			(thermal_gap 0.5)
			(thermal_bridge_width 0.5)
			(island_removal_mode 0)
		)
		(polygon
			(pts
				(xy 450.636386 -295.69283) (xy 451.195186 -295.69283) (xy 451.195186 -295.96842) (xy 451.195186 -296.207942)
				(xy 450.315838 -296.207942) (xy 450.315838 -295.69283)
			)
		)
	)
	(zone
		(layer "In11.Cu")
		(hatch none 0.5)
		(connect_pads
			(clearance 0)
		)
		(min_thickness 0.25)
		(keepout
			(tracks allowed)
			(vias allowed)
			(pads allowed)
			(copperpour allowed)
			(footprints allowed)
		)
		(placement
			(enabled no)
			(sheetname "")
		)
		(fill
			(thermal_gap 0.5)
			(thermal_bridge_width 0.5)
			(island_removal_mode 0)
		)
		(polygon
			(pts
				(xy 177.170842 -194.714622) (xy 177.170842 -194.990212) (xy 176.612042 -194.990212) (xy 176.612042 -194.714622)
			)
		)
	)
	(zone
		(layer "In11.Cu")
		(hatch none 0.5)
		(connect_pads
			(clearance 0)
		)
		(min_thickness 0.25)
		(keepout
			(tracks allowed)
			(vias allowed)
			(pads allowed)
			(copperpour allowed)
			(footprints allowed)
		)
		(placement
			(enabled no)
			(sheetname "")
		)
		(fill
			(thermal_gap 0.5)
			(thermal_bridge_width 0.5)
			(island_removal_mode 0)
		)
		(polygon
			(pts
				(xy 50.771552 -311.496964) (xy 50.771552 -310.947308) (xy 51.401472 -310.947308) (xy 51.401472 -311.496964)
			)
		)
	)
	(zone
		(layer "In11.Cu")
		(hatch none 0.5)
		(connect_pads
			(clearance 0)
		)
		(min_thickness 0.25)
		(keepout
			(tracks allowed)
			(vias allowed)
			(pads allowed)
			(copperpour allowed)
			(footprints allowed)
		)
		(placement
			(enabled no)
			(sheetname "")
		)
		(fill
			(thermal_gap 0.5)
			(thermal_bridge_width 0.5)
			(island_removal_mode 0)
		)
		(polygon
			(pts
				(xy 294.586152 -234.146852) (xy 294.586152 -233.597196) (xy 295.216072 -233.597196) (xy 295.216072 -234.146852)
			)
		)
	)
	(zone
		(layer "In11.Cu")
		(hatch none 0.5)
		(connect_pads
			(clearance 0)
		)
		(min_thickness 0.25)
		(keepout
			(tracks allowed)
			(vias allowed)
			(pads allowed)
			(copperpour allowed)
			(footprints allowed)
		)
		(placement
			(enabled no)
			(sheetname "")
		)
		(fill
			(thermal_gap 0.5)
			(thermal_bridge_width 0.5)
			(island_removal_mode 0)
		)
		(polygon
			(pts
				(xy 298.68622 -285.996888) (xy 298.68622 -285.447232) (xy 299.31614 -285.447232) (xy 299.31614 -285.996888)
			)
		)
	)
	(zone
		(layer "In11.Cu")
		(hatch none 0.5)
		(connect_pads
			(clearance 0)
		)
		(min_thickness 0.25)
		(keepout
			(tracks allowed)
			(vias allowed)
			(pads allowed)
			(copperpour allowed)
			(footprints allowed)
		)
		(placement
			(enabled no)
			(sheetname "")
		)
		(fill
			(thermal_gap 0.5)
			(thermal_bridge_width 0.5)
			(island_removal_mode 0)
		)
		(polygon
			(pts
				(xy 294.586152 -290.246816) (xy 294.586152 -289.69716) (xy 295.216072 -289.69716) (xy 295.216072 -290.246816)
			)
		)
	)
	(zone
		(layer "In11.Cu")
		(hatch none 0.5)
		(connect_pads
			(clearance 0)
		)
		(min_thickness 0.25)
		(keepout
			(tracks allowed)
			(vias allowed)
			(pads allowed)
			(copperpour allowed)
			(footprints allowed)
		)
		(placement
			(enabled no)
			(sheetname "")
		)
		(fill
			(thermal_gap 0.5)
			(thermal_bridge_width 0.5)
			(island_removal_mode 0)
		)
		(polygon
			(pts
				(xy 50.771552 -302.997108) (xy 50.771552 -302.447452) (xy 51.401472 -302.447452) (xy 51.401472 -302.997108)
			)
		)
	)
	(zone
		(layer "In11.Cu")
		(hatch none 0.5)
		(connect_pads
			(clearance 0)
		)
		(min_thickness 0.25)
		(keepout
			(tracks allowed)
			(vias allowed)
			(pads allowed)
			(copperpour allowed)
			(footprints allowed)
		)
		(placement
			(enabled no)
			(sheetname "")
		)
		(fill
			(thermal_gap 0.5)
			(thermal_bridge_width 0.5)
			(island_removal_mode 0)
		)
		(polygon
			(pts
				(xy 450.636386 -278.968454) (xy 450.636386 -278.692864) (xy 451.195186 -278.692864) (xy 451.195186 -278.968454)
			)
		)
	)
	(zone
		(layer "In11.Cu")
		(hatch none 0.5)
		(connect_pads
			(clearance 0)
		)
		(min_thickness 0.25)
		(keepout
			(tracks allowed)
			(vias allowed)
			(pads allowed)
			(copperpour allowed)
			(footprints allowed)
		)
		(placement
			(enabled no)
			(sheetname "")
		)
		(fill
			(thermal_gap 0.5)
			(thermal_bridge_width 0.5)
			(island_removal_mode 0)
		)
		(polygon
			(pts
				(xy 421.010842 -198.114666) (xy 421.010842 -198.390256) (xy 420.452042 -198.390256) (xy 420.452042 -198.114666)
			)
		)
	)
	(zone
		(layer "In11.Cu")
		(hatch none 0.5)
		(connect_pads
			(clearance 0)
		)
		(min_thickness 0.25)
		(keepout
			(tracks allowed)
			(vias allowed)
			(pads allowed)
			(copperpour allowed)
			(footprints allowed)
		)
		(placement
			(enabled no)
			(sheetname "")
		)
		(fill
			(thermal_gap 0.5)
			(thermal_bridge_width 0.5)
			(island_removal_mode 0)
		)
		(polygon
			(pts
				(xy 450.636386 -267.068554) (xy 450.636386 -266.792964) (xy 451.195186 -266.792964) (xy 451.195186 -267.068554)
			)
		)
	)
	(zone
		(layer "In11.Cu")
		(hatch none 0.5)
		(connect_pads
			(clearance 0)
		)
		(min_thickness 0.25)
		(keepout
			(tracks allowed)
			(vias allowed)
			(pads allowed)
			(copperpour allowed)
			(footprints allowed)
		)
		(placement
			(enabled no)
			(sheetname "")
		)
		(fill
			(thermal_gap 0.5)
			(thermal_bridge_width 0.5)
			(island_removal_mode 0)
		)
		(polygon
			(pts
				(xy 421.010842 -209.164682) (xy 421.010842 -209.440272) (xy 420.452042 -209.440272) (xy 420.452042 -209.164682)
			)
		)
	)
	(zone
		(layer "In11.Cu")
		(hatch none 0.5)
		(connect_pads
			(clearance 0)
		)
		(min_thickness 0.25)
		(keepout
			(tracks not_allowed)
			(vias allowed)
			(pads allowed)
			(copperpour not_allowed)
			(footprints allowed)
		)
		(placement
			(enabled no)
			(sheetname "")
		)
		(fill
			(thermal_gap 0.5)
			(thermal_bridge_width 0.5)
			(island_removal_mode 0)
		)
		(polygon
			(pts
				(arc
					(start 81.142078 -428.960788)
					(mid 81.164396 -429.01467)
					(end 81.218278 -429.036988)
				)
				(arc
					(start 82.158078 -429.036988)
					(mid 82.21196 -429.01467)
					(end 82.234278 -428.960788)
				)
				(arc
					(start 82.234278 -426.419264)
					(mid 82.21196 -426.365382)
					(end 82.158078 -426.343064)
				)
				(arc
					(start 81.218278 -426.343064)
					(mid 81.164396 -426.365382)
					(end 81.142078 -426.419264)
				)
			)
		)
	)
	(zone
		(layer "In11.Cu")
		(hatch none 0.5)
		(connect_pads
			(clearance 0)
		)
		(min_thickness 0.25)
		(keepout
			(tracks allowed)
			(vias allowed)
			(pads allowed)
			(copperpour allowed)
			(footprints allowed)
		)
		(placement
			(enabled no)
			(sheetname "")
		)
		(fill
			(thermal_gap 0.5)
			(thermal_bridge_width 0.5)
			(island_removal_mode 0)
		)
		(polygon
			(pts
				(xy 421.010842 -288.214816) (xy 421.010842 -288.490406) (xy 420.452042 -288.490406) (xy 420.452042 -288.214816)
			)
		)
	)
	(zone
		(layer "In11.Cu")
		(hatch none 0.5)
		(connect_pads
			(clearance 0)
		)
		(min_thickness 0.25)
		(keepout
			(tracks allowed)
			(vias allowed)
			(pads allowed)
			(copperpour allowed)
			(footprints allowed)
		)
		(placement
			(enabled no)
			(sheetname "")
		)
		(fill
			(thermal_gap 0.5)
			(thermal_bridge_width 0.5)
			(island_removal_mode 0)
		)
		(polygon
			(pts
				(xy 173.070774 -202.364848) (xy 173.070774 -202.640438) (xy 172.511974 -202.640438) (xy 172.511974 -202.364848)
			)
		)
	)
	(zone
		(layer "In11.Cu")
		(hatch none 0.5)
		(connect_pads
			(clearance 0)
		)
		(min_thickness 0.25)
		(keepout
			(tracks allowed)
			(vias allowed)
			(pads allowed)
			(copperpour allowed)
			(footprints allowed)
		)
		(placement
			(enabled no)
			(sheetname "")
		)
		(fill
			(thermal_gap 0.5)
			(thermal_bridge_width 0.5)
			(island_removal_mode 0)
		)
		(polygon
			(pts
				(xy 203.245974 -262.71474) (xy 203.245974 -262.99033) (xy 202.687174 -262.99033) (xy 202.687174 -262.71474)
			)
		)
	)
	(zone
		(layer "In11.Cu")
		(hatch none 0.5)
		(connect_pads
			(clearance 0)
		)
		(min_thickness 0.25)
		(keepout
			(tracks allowed)
			(vias allowed)
			(pads allowed)
			(copperpour allowed)
			(footprints allowed)
		)
		(placement
			(enabled no)
			(sheetname "")
		)
		(fill
			(thermal_gap 0.5)
			(thermal_bridge_width 0.5)
			(island_removal_mode 0)
		)
		(polygon
			(pts
				(xy 421.010842 -214.264748) (xy 421.010842 -214.540338) (xy 420.452042 -214.540338) (xy 420.452042 -214.264748)
			)
		)
	)
	(zone
		(layer "In11.Cu")
		(hatch none 0.5)
		(connect_pads
			(clearance 0)
		)
		(min_thickness 0.25)
		(keepout
			(tracks allowed)
			(vias allowed)
			(pads allowed)
			(copperpour allowed)
			(footprints allowed)
		)
		(placement
			(enabled no)
			(sheetname "")
		)
		(fill
			(thermal_gap 0.5)
			(thermal_bridge_width 0.5)
			(island_removal_mode 0)
		)
		(polygon
			(pts
				(xy 420.461186 -208.41843) (xy 420.461186 -208.14284) (xy 421.019986 -208.14284) (xy 421.019986 -208.41843)
			)
		)
	)
	(zone
		(layer "In11.Cu")
		(hatch none 0.5)
		(connect_pads
			(clearance 0)
		)
		(min_thickness 0.25)
		(keepout
			(tracks allowed)
			(vias allowed)
			(pads allowed)
			(copperpour allowed)
			(footprints allowed)
		)
		(placement
			(enabled no)
			(sheetname "")
		)
		(fill
			(thermal_gap 0.5)
			(thermal_bridge_width 0.5)
			(island_removal_mode 0)
		)
		(polygon
			(pts
				(xy 50.771552 -306.396898) (xy 50.771552 -305.847242) (xy 51.401472 -305.847242) (xy 51.401472 -306.396898)
			)
		)
	)
	(zone
		(layer "In11.Cu")
		(hatch none 0.5)
		(connect_pads
			(clearance 0)
		)
		(min_thickness 0.25)
		(keepout
			(tracks allowed)
			(vias allowed)
			(pads allowed)
			(copperpour allowed)
			(footprints allowed)
		)
		(placement
			(enabled no)
			(sheetname "")
		)
		(fill
			(thermal_gap 0.5)
			(thermal_bridge_width 0.5)
			(island_removal_mode 0)
		)
		(polygon
			(pts
				(xy 173.070774 -283.964634) (xy 173.070774 -284.240224) (xy 172.511974 -284.240224) (xy 172.511974 -283.964634)
			)
		)
	)
	(zone
		(layer "In11.Cu")
		(hatch none 0.5)
		(connect_pads
			(clearance 0)
		)
		(min_thickness 0.25)
		(keepout
			(tracks allowed)
			(vias allowed)
			(pads allowed)
			(copperpour allowed)
			(footprints allowed)
		)
		(placement
			(enabled no)
			(sheetname "")
		)
		(fill
			(thermal_gap 0.5)
			(thermal_bridge_width 0.5)
			(island_removal_mode 0)
		)
		(polygon
			(pts
				(xy 298.68622 -206.946754) (xy 298.68622 -206.397098) (xy 299.31614 -206.397098) (xy 299.31614 -206.946754)
			)
		)
	)
	(zone
		(layer "In11.Cu")
		(hatch none 0.5)
		(connect_pads
			(clearance 0)
		)
		(min_thickness 0.25)
		(keepout
			(tracks allowed)
			(vias allowed)
			(pads allowed)
			(copperpour allowed)
			(footprints allowed)
		)
		(placement
			(enabled no)
			(sheetname "")
		)
		(fill
			(thermal_gap 0.5)
			(thermal_bridge_width 0.5)
			(island_removal_mode 0)
		)
		(polygon
			(pts
				(xy 177.170842 -295.864788) (xy 177.170842 -296.140378) (xy 176.612042 -296.140378) (xy 176.612042 -295.864788)
			)
		)
	)
	(zone
		(layer "In11.Cu")
		(hatch none 0.5)
		(connect_pads
			(clearance 0)
		)
		(min_thickness 0.25)
		(keepout
			(tracks allowed)
			(vias allowed)
			(pads allowed)
			(copperpour allowed)
			(footprints allowed)
		)
		(placement
			(enabled no)
			(sheetname "")
		)
		(fill
			(thermal_gap 0.5)
			(thermal_bridge_width 0.5)
			(island_removal_mode 0)
		)
		(polygon
			(pts
				(xy 177.170842 -213.41461) (xy 177.170842 -213.6902) (xy 176.612042 -213.6902) (xy 176.612042 -213.41461)
			)
		)
	)
	(zone
		(layer "In11.Cu")
		(hatch none 0.5)
		(connect_pads
			(clearance 0)
		)
		(min_thickness 0.25)
		(keepout
			(tracks allowed)
			(vias allowed)
			(pads allowed)
			(copperpour allowed)
			(footprints allowed)
		)
		(placement
			(enabled no)
			(sheetname "")
		)
		(fill
			(thermal_gap 0.5)
			(thermal_bridge_width 0.5)
			(island_removal_mode 0)
		)
		(polygon
			(pts
				(xy 192.258442 -209.164682) (xy 192.258442 -209.440272) (xy 191.699642 -209.440272) (xy 191.699642 -209.164682)
			)
		)
	)
	(zone
		(layer "In11.Cu")
		(hatch none 0.5)
		(connect_pads
			(clearance 0)
		)
		(min_thickness 0.25)
		(keepout
			(tracks allowed)
			(vias allowed)
			(pads allowed)
			(copperpour allowed)
			(footprints allowed)
		)
		(placement
			(enabled no)
			(sheetname "")
		)
		(fill
			(thermal_gap 0.5)
			(thermal_bridge_width 0.5)
			(island_removal_mode 0)
		)
		(polygon
			(pts
				(xy 177.170842 -299.264578) (xy 177.170842 -299.540168) (xy 176.612042 -299.540168) (xy 176.612042 -299.264578)
			)
		)
	)
	(zone
		(layer "In11.Cu")
		(hatch none 0.5)
		(connect_pads
			(clearance 0)
		)
		(min_thickness 0.25)
		(keepout
			(tracks allowed)
			(vias allowed)
			(pads allowed)
			(copperpour allowed)
			(footprints allowed)
		)
		(placement
			(enabled no)
			(sheetname "")
		)
		(fill
			(thermal_gap 0.5)
			(thermal_bridge_width 0.5)
			(island_removal_mode 0)
		)
		(polygon
			(pts
				(xy 172.521118 -275.56841) (xy 172.521118 -275.29282) (xy 173.079918 -275.29282) (xy 173.079918 -275.56841)
			)
		)
	)
	(zone
		(layer "In11.Cu")
		(hatch none 0.5)
		(connect_pads
			(clearance 0)
		)
		(min_thickness 0.25)
		(keepout
			(tracks allowed)
			(vias allowed)
			(pads allowed)
			(copperpour allowed)
			(footprints allowed)
		)
		(placement
			(enabled no)
			(sheetname "")
		)
		(fill
			(thermal_gap 0.5)
			(thermal_bridge_width 0.5)
			(island_removal_mode 0)
		)
		(polygon
			(pts
				(xy 172.521118 -293.418514) (xy 172.521118 -293.142924) (xy 173.079918 -293.142924) (xy 173.079918 -293.418514)
			)
		)
	)
	(zone
		(layer "In11.Cu")
		(hatch none 0.5)
		(connect_pads
			(clearance 0)
		)
		(min_thickness 0.25)
		(keepout
			(tracks allowed)
			(vias allowed)
			(pads allowed)
			(copperpour allowed)
			(footprints allowed)
		)
		(placement
			(enabled no)
			(sheetname "")
		)
		(fill
			(thermal_gap 0.5)
			(thermal_bridge_width 0.5)
			(island_removal_mode 0)
		)
		(polygon
			(pts
				(xy 177.170842 -258.464812) (xy 177.170842 -258.740402) (xy 176.612042 -258.740402) (xy 176.612042 -258.464812)
			)
		)
	)
	(zone
		(layer "In11.Cu")
		(hatch none 0.5)
		(connect_pads
			(clearance 0)
		)
		(min_thickness 0.25)
		(keepout
			(tracks allowed)
			(vias allowed)
			(pads allowed)
			(copperpour allowed)
			(footprints allowed)
		)
		(placement
			(enabled no)
			(sheetname "")
		)
		(fill
			(thermal_gap 0.5)
			(thermal_bridge_width 0.5)
			(island_removal_mode 0)
		)
		(polygon
			(pts
				(xy 264.464292 -266.450572) (xy 264.464292 -265.900154) (xy 265.023092 -265.900154) (xy 265.023092 -266.450572)
			)
		)
	)
	(zone
		(layer "In11.Cu")
		(hatch none 0.5)
		(connect_pads
			(clearance 0)
		)
		(min_thickness 0.25)
		(keepout
			(tracks allowed)
			(vias allowed)
			(pads allowed)
			(copperpour allowed)
			(footprints allowed)
		)
		(placement
			(enabled no)
			(sheetname "")
		)
		(fill
			(thermal_gap 0.5)
			(thermal_bridge_width 0.5)
			(island_removal_mode 0)
		)
		(polygon
			(pts
				(xy 176.621186 -227.968556) (xy 176.621186 -227.692966) (xy 177.179986 -227.692966) (xy 177.179986 -227.968556)
			)
		)
	)
	(zone
		(layer "In11.Cu")
		(hatch none 0.5)
		(connect_pads
			(clearance 0)
		)
		(min_thickness 0.25)
		(keepout
			(tracks allowed)
			(vias allowed)
			(pads allowed)
			(copperpour allowed)
			(footprints allowed)
		)
		(placement
			(enabled no)
			(sheetname "")
		)
		(fill
			(thermal_gap 0.5)
			(thermal_bridge_width 0.5)
			(island_removal_mode 0)
		)
		(polygon
			(pts
				(xy 383.747518 -250.250198) (xy 381.916686 -252.08103) (xy 372.661434 -252.08103) (xy 372.661434 -252.919738)
				(xy 372.462806 -253.118366) (xy 372.462806 -253.966726) (xy 372.528846 -254.032766) (xy 372.937786 -254.032766)
				(xy 373.076978 -253.893574) (xy 373.19331 -253.893574) (xy 373.19331 -253.83363) (xy 373.19331 -253.708154)
				(xy 373.204486 -253.696978) (xy 373.476012 -253.696978) (xy 373.672608 -253.893574) (xy 385.118864 -253.89332)
				(xy 385.122674 -253.896876) (xy 388.129018 -253.896876) (xy 388.132574 -253.896876) (xy 388.28853 -254.052832)
				(xy 388.28853 -258.515104) (xy 389.932672 -260.158992) (xy 394.53185 -260.158992) (xy 394.626084 -260.158992)
				(xy 394.664946 -260.12013) (xy 395.018006 -260.12013) (xy 396.333726 -261.43585) (xy 397.103346 -261.43585)
				(xy 398.121886 -260.41731) (xy 398.121886 -258.59359) (xy 398.447006 -258.26847) (xy 398.447006 -256.551938)
				(xy 398.121886 -256.226818) (xy 397.947134 -256.052066) (xy 397.81099 -255.915922) (xy 397.142716 -255.915922)
				(xy 396.28064 -255.053846) (xy 396.10665 -254.879856) (xy 396.10665 -254.514858) (xy 396.009114 -254.417322)
				(xy 396.009114 -254.156718) (xy 395.950186 -254.09779) (xy 395.701774 -254.09779) (xy 395.178026 -254.621538)
				(xy 395.164564 -254.621538) (xy 395.031214 -254.488188) (xy 395.031214 -254.324358) (xy 394.94206 -254.235204)
				(xy 394.94206 -253.932944) (xy 396.121636 -252.753368) (xy 396.121636 -250.884182) (xy 395.098778 -249.861578)
				(xy 398.068546 -246.89181) (xy 398.068546 -246.28475) (xy 397.744188 -245.960392) (xy 396.764764 -245.960392)
				(xy 389.043164 -245.960392) (xy 388.879588 -246.123968) (xy 386.46989 -246.123968) (xy 386.32892 -246.264938)
				(xy 386.32892 -246.652288) (xy 386.12318 -246.858028) (xy 386.12318 -249.697748) (xy 385.938776 -249.882152)
				(xy 385.822444 -249.882152) (xy 385.454398 -250.250198) (xy 385.300474 -250.404122) (xy 384.858768 -250.404122)
				(xy 384.704844 -250.250198)
			)
		)
	)
	(zone
		(layer "In11.Cu")
		(hatch none 0.5)
		(connect_pads
			(clearance 0)
		)
		(min_thickness 0.25)
		(keepout
			(tracks allowed)
			(vias allowed)
			(pads allowed)
			(copperpour allowed)
			(footprints allowed)
		)
		(placement
			(enabled no)
			(sheetname "")
		)
		(fill
			(thermal_gap 0.5)
			(thermal_bridge_width 0.5)
			(island_removal_mode 0)
		)
		(polygon
			(pts
				(xy 294.586152 -285.14675) (xy 294.586152 -284.597094) (xy 295.216072 -284.597094) (xy 295.216072 -285.14675)
			)
		)
	)
	(zone
		(layer "In11.Cu")
		(hatch none 0.5)
		(connect_pads
			(clearance 0)
		)
		(min_thickness 0.25)
		(keepout
			(tracks allowed)
			(vias allowed)
			(pads allowed)
			(copperpour allowed)
			(footprints allowed)
		)
		(placement
			(enabled no)
			(sheetname "")
		)
		(fill
			(thermal_gap 0.5)
			(thermal_bridge_width 0.5)
			(island_removal_mode 0)
		)
		(polygon
			(pts
				(xy 450.636386 -307.018436) (xy 450.636386 -306.742846) (xy 451.195186 -306.742846) (xy 451.195186 -307.018436)
			)
		)
	)
	(zone
		(layer "In11.Cu")
		(hatch none 0.5)
		(connect_pads
			(clearance 0)
		)
		(min_thickness 0.25)
		(keepout
			(tracks allowed)
			(vias allowed)
			(pads allowed)
			(copperpour allowed)
			(footprints allowed)
		)
		(placement
			(enabled no)
			(sheetname "")
		)
		(fill
			(thermal_gap 0.5)
			(thermal_bridge_width 0.5)
			(island_removal_mode 0)
		)
		(polygon
			(pts
				(xy 172.521118 -295.118536) (xy 172.521118 -294.842946) (xy 173.079918 -294.842946) (xy 173.079918 -295.118536)
			)
		)
	)
	(zone
		(layer "In11.Cu")
		(hatch none 0.5)
		(connect_pads
			(clearance 0)
		)
		(min_thickness 0.25)
		(keepout
			(tracks allowed)
			(vias allowed)
			(pads allowed)
			(copperpour allowed)
			(footprints allowed)
		)
		(placement
			(enabled no)
			(sheetname "")
		)
		(fill
			(thermal_gap 0.5)
			(thermal_bridge_width 0.5)
			(island_removal_mode 0)
		)
		(polygon
			(pts
				(xy 424.561254 -202.46848) (xy 424.561254 -202.19289) (xy 425.120054 -202.19289) (xy 425.120054 -202.46848)
			)
		)
	)
	(zone
		(layer "In11.Cu")
		(hatch none 0.5)
		(connect_pads
			(clearance 0)
		)
		(min_thickness 0.25)
		(keepout
			(tracks allowed)
			(vias allowed)
			(pads allowed)
			(copperpour allowed)
			(footprints allowed)
		)
		(placement
			(enabled no)
			(sheetname "")
		)
		(fill
			(thermal_gap 0.5)
			(thermal_bridge_width 0.5)
			(island_removal_mode 0)
		)
		(polygon
			(pts
				(xy 20.624292 -289.400742) (xy 20.624292 -288.850324) (xy 21.183092 -288.850324) (xy 21.183092 -289.400742)
			)
		)
	)
	(zone
		(layer "In11.Cu")
		(hatch none 0.5)
		(connect_pads
			(clearance 0)
		)
		(min_thickness 0.25)
		(keepout
			(tracks allowed)
			(vias allowed)
			(pads allowed)
			(copperpour allowed)
			(footprints allowed)
		)
		(placement
			(enabled no)
			(sheetname "")
		)
		(fill
			(thermal_gap 0.5)
			(thermal_bridge_width 0.5)
			(island_removal_mode 0)
		)
		(polygon
			(pts
				(xy 450.636386 -252.618494) (xy 450.636386 -252.342904) (xy 451.195186 -252.342904) (xy 451.195186 -252.618494)
			)
		)
	)
	(zone
		(layer "In11.Cu")
		(hatch none 0.5)
		(connect_pads
			(clearance 0)
		)
		(min_thickness 0.25)
		(keepout
			(tracks allowed)
			(vias allowed)
			(pads allowed)
			(copperpour allowed)
			(footprints allowed)
		)
		(placement
			(enabled no)
			(sheetname "")
		)
		(fill
			(thermal_gap 0.5)
			(thermal_bridge_width 0.5)
			(island_removal_mode 0)
		)
		(polygon
			(pts
				(xy 202.696318 -285.768542) (xy 202.696318 -285.492952) (xy 203.255118 -285.492952) (xy 203.255118 -285.768542)
			)
		)
	)
	(zone
		(layer "In11.Cu")
		(hatch none 0.5)
		(connect_pads
			(clearance 0)
		)
		(min_thickness 0.25)
		(keepout
			(tracks allowed)
			(vias allowed)
			(pads allowed)
			(copperpour allowed)
			(footprints allowed)
		)
		(placement
			(enabled no)
			(sheetname "")
		)
		(fill
			(thermal_gap 0.5)
			(thermal_bridge_width 0.5)
			(island_removal_mode 0)
		)
		(polygon
			(pts
				(xy 110.95609 -365.32693) (xy 110.95609 -356.305866) (xy 114.713512 -356.305866) (xy 114.713512 -365.32693)
			)
		)
	)
	(zone
		(layer "In11.Cu")
		(hatch none 0.5)
		(connect_pads
			(clearance 0)
		)
		(min_thickness 0.25)
		(keepout
			(tracks allowed)
			(vias allowed)
			(pads allowed)
			(copperpour allowed)
			(footprints allowed)
		)
		(placement
			(enabled no)
			(sheetname "")
		)
		(fill
			(thermal_gap 0.5)
			(thermal_bridge_width 0.5)
			(island_removal_mode 0)
		)
		(polygon
			(pts
				(xy 46.646084 -290.246816) (xy 46.646084 -289.69716) (xy 47.276004 -289.69716) (xy 47.276004 -290.246816)
			)
		)
	)
	(zone
		(layer "In11.Cu")
		(hatch none 0.5)
		(connect_pads
			(clearance 0)
		)
		(min_thickness 0.25)
		(keepout
			(tracks allowed)
			(vias allowed)
			(pads allowed)
			(copperpour allowed)
			(footprints allowed)
		)
		(placement
			(enabled no)
			(sheetname "")
		)
		(fill
			(thermal_gap 0.5)
			(thermal_bridge_width 0.5)
			(island_removal_mode 0)
		)
		(polygon
			(pts
				(xy 172.994574 -261.864602) (xy 172.994574 -262.140192) (xy 172.435774 -262.140192) (xy 172.435774 -261.864602)
			)
		)
	)
	(zone
		(layer "In11.Cu")
		(hatch none 0.5)
		(connect_pads
			(clearance 0)
		)
		(min_thickness 0.25)
		(keepout
			(tracks allowed)
			(vias allowed)
			(pads allowed)
			(copperpour allowed)
			(footprints allowed)
		)
		(placement
			(enabled no)
			(sheetname "")
		)
		(fill
			(thermal_gap 0.5)
			(thermal_bridge_width 0.5)
			(island_removal_mode 0)
		)
		(polygon
			(pts
				(xy 176.621186 -233.068622) (xy 176.621186 -232.793032) (xy 177.179986 -232.793032) (xy 177.179986 -233.068622)
			)
		)
	)
	(zone
		(layer "In11.Cu")
		(hatch none 0.5)
		(connect_pads
			(clearance 0)
		)
		(min_thickness 0.25)
		(keepout
			(tracks allowed)
			(vias allowed)
			(pads allowed)
			(copperpour allowed)
			(footprints allowed)
		)
		(placement
			(enabled no)
			(sheetname "")
		)
		(fill
			(thermal_gap 0.5)
			(thermal_bridge_width 0.5)
			(island_removal_mode 0)
		)
		(polygon
			(pts
				(xy 172.521118 -296.818558) (xy 172.521118 -296.542968) (xy 173.079918 -296.542968) (xy 173.079918 -296.818558)
			)
		)
	)
	(zone
		(layer "In11.Cu")
		(hatch none 0.5)
		(connect_pads
			(clearance 0)
		)
		(min_thickness 0.25)
		(keepout
			(tracks allowed)
			(vias allowed)
			(pads allowed)
			(copperpour allowed)
			(footprints allowed)
		)
		(placement
			(enabled no)
			(sheetname "")
		)
		(fill
			(thermal_gap 0.5)
			(thermal_bridge_width 0.5)
			(island_removal_mode 0)
		)
		(polygon
			(pts
				(xy 20.61845 -262.192262) (xy 20.61845 -261.652004) (xy 21.186394 -261.652004) (xy 21.486876 -261.652004)
				(xy 21.591016 -261.756144) (xy 21.591016 -262.021574) (xy 21.420328 -262.192262) (xy 21.17725 -262.192262)
			)
		)
	)
	(zone
		(layer "In11.Cu")
		(hatch none 0.5)
		(connect_pads
			(clearance 0)
		)
		(min_thickness 0.25)
		(keepout
			(tracks allowed)
			(vias allowed)
			(pads allowed)
			(copperpour allowed)
			(footprints allowed)
		)
		(placement
			(enabled no)
			(sheetname "")
		)
		(fill
			(thermal_gap 0.5)
			(thermal_bridge_width 0.5)
			(island_removal_mode 0)
		)
		(polygon
			(pts
				(xy 425.11091 -206.614776) (xy 425.11091 -206.890366) (xy 424.55211 -206.890366) (xy 424.55211 -206.614776)
			)
		)
	)
	(zone
		(layer "In11.Cu")
		(hatch none 0.5)
		(connect_pads
			(clearance 0)
		)
		(min_thickness 0.25)
		(keepout
			(tracks allowed)
			(vias allowed)
			(pads allowed)
			(copperpour allowed)
			(footprints allowed)
		)
		(placement
			(enabled no)
			(sheetname "")
		)
		(fill
			(thermal_gap 0.5)
			(thermal_bridge_width 0.5)
			(island_removal_mode 0)
		)
		(polygon
			(pts
				(xy 268.51102 -239.246918) (xy 268.51102 -238.697262) (xy 269.14094 -238.697262) (xy 269.14094 -239.246918)
			)
		)
	)
	(zone
		(layer "In11.Cu")
		(hatch none 0.5)
		(connect_pads
			(clearance 0)
		)
		(min_thickness 0.25)
		(keepout
			(tracks allowed)
			(vias allowed)
			(pads allowed)
			(copperpour allowed)
			(footprints allowed)
		)
		(placement
			(enabled no)
			(sheetname "")
		)
		(fill
			(thermal_gap 0.5)
			(thermal_bridge_width 0.5)
			(island_removal_mode 0)
		)
		(polygon
			(pts
				(xy 451.186042 -232.964736) (xy 451.186042 -233.240326) (xy 450.627242 -233.240326) (xy 450.627242 -232.964736)
			)
		)
	)
	(zone
		(layer "In11.Cu")
		(hatch none 0.5)
		(connect_pads
			(clearance 0)
		)
		(min_thickness 0.25)
		(keepout
			(tracks allowed)
			(vias allowed)
			(pads allowed)
			(copperpour allowed)
			(footprints allowed)
		)
		(placement
			(enabled no)
			(sheetname "")
		)
		(fill
			(thermal_gap 0.5)
			(thermal_bridge_width 0.5)
			(island_removal_mode 0)
		)
		(polygon
			(pts
				(xy 177.170842 -239.764824) (xy 177.170842 -240.040414) (xy 176.612042 -240.040414) (xy 176.612042 -239.764824)
			)
		)
	)
	(zone
		(layer "In11.Cu")
		(hatch none 0.5)
		(connect_pads
			(clearance 0)
		)
		(min_thickness 0.25)
		(keepout
			(tracks allowed)
			(vias allowed)
			(pads allowed)
			(copperpour allowed)
			(footprints allowed)
		)
		(placement
			(enabled no)
			(sheetname "")
		)
		(fill
			(thermal_gap 0.5)
			(thermal_bridge_width 0.5)
			(island_removal_mode 0)
		)
		(polygon
			(pts
				(xy 50.771552 -267.2969) (xy 50.771552 -266.747244) (xy 51.401472 -266.747244) (xy 51.401472 -267.2969)
			)
		)
	)
	(zone
		(layer "In11.Cu")
		(hatch none 0.5)
		(connect_pads
			(clearance 0)
		)
		(min_thickness 0.25)
		(keepout
			(tracks allowed)
			(vias allowed)
			(pads allowed)
			(copperpour allowed)
			(footprints allowed)
		)
		(placement
			(enabled no)
			(sheetname "")
		)
		(fill
			(thermal_gap 0.5)
			(thermal_bridge_width 0.5)
			(island_removal_mode 0)
		)
		(polygon
			(pts
				(xy 298.71162 -291.096954) (xy 298.71162 -290.547298) (xy 299.34154 -290.547298) (xy 299.34154 -291.096954)
			)
		)
	)
	(zone
		(layer "In11.Cu")
		(hatch none 0.5)
		(connect_pads
			(clearance 0)
		)
		(min_thickness 0.25)
		(keepout
			(tracks allowed)
			(vias allowed)
			(pads allowed)
			(copperpour allowed)
			(footprints allowed)
		)
		(placement
			(enabled no)
			(sheetname "")
		)
		(fill
			(thermal_gap 0.5)
			(thermal_bridge_width 0.5)
			(island_removal_mode 0)
		)
		(polygon
			(pts
				(xy 173.070774 -237.214664) (xy 173.070774 -237.490254) (xy 172.511974 -237.490254) (xy 172.511974 -237.214664)
			)
		)
	)
	(zone
		(layer "In11.Cu")
		(hatch none 0.5)
		(connect_pads
			(clearance 0)
		)
		(min_thickness 0.25)
		(keepout
			(tracks allowed)
			(vias allowed)
			(pads allowed)
			(copperpour allowed)
			(footprints allowed)
		)
		(placement
			(enabled no)
			(sheetname "")
		)
		(fill
			(thermal_gap 0.5)
			(thermal_bridge_width 0.5)
			(island_removal_mode 0)
		)
		(polygon
			(pts
				(xy 202.696318 -302.492918) (xy 203.255118 -302.492918) (xy 203.255118 -302.768508) (xy 203.255118 -303.07661)
				(xy 202.622658 -303.07661) (xy 202.622658 -302.492918)
			)
		)
	)
	(zone
		(layer "In11.Cu")
		(hatch none 0.5)
		(connect_pads
			(clearance 0)
		)
		(min_thickness 0.25)
		(keepout
			(tracks not_allowed)
			(vias allowed)
			(pads allowed)
			(copperpour not_allowed)
			(footprints allowed)
		)
		(placement
			(enabled no)
			(sheetname "")
		)
		(fill
			(thermal_gap 0.5)
			(thermal_bridge_width 0.5)
			(island_removal_mode 0)
		)
		(polygon
			(pts
				(arc
					(start 400.242024 -428.960788)
					(mid 400.264342 -429.01467)
					(end 400.318224 -429.036988)
				)
				(arc
					(start 401.258024 -429.036988)
					(mid 401.311906 -429.01467)
					(end 401.334224 -428.960788)
				)
				(arc
					(start 401.334224 -426.419264)
					(mid 401.311906 -426.365382)
					(end 401.258024 -426.343064)
				)
				(arc
					(start 400.318224 -426.343064)
					(mid 400.264342 -426.365382)
					(end 400.242024 -426.419264)
				)
			)
		)
	)
	(zone
		(layer "In11.Cu")
		(hatch none 0.5)
		(connect_pads
			(clearance 0)
		)
		(min_thickness 0.25)
		(keepout
			(tracks allowed)
			(vias allowed)
			(pads allowed)
			(copperpour allowed)
			(footprints allowed)
		)
		(placement
			(enabled no)
			(sheetname "")
		)
		(fill
			(thermal_gap 0.5)
			(thermal_bridge_width 0.5)
			(island_removal_mode 0)
		)
		(polygon
			(pts
				(xy 177.170842 -196.414644) (xy 177.170842 -196.690234) (xy 176.612042 -196.690234) (xy 176.612042 -196.414644)
			)
		)
	)
	(zone
		(layer "In11.Cu")
		(hatch none 0.5)
		(connect_pads
			(clearance 0)
		)
		(min_thickness 0.25)
		(keepout
			(tracks allowed)
			(vias allowed)
			(pads allowed)
			(copperpour allowed)
			(footprints allowed)
		)
		(placement
			(enabled no)
			(sheetname "")
		)
		(fill
			(thermal_gap 0.5)
			(thermal_bridge_width 0.5)
			(island_removal_mode 0)
		)
		(polygon
			(pts
				(xy 298.68622 -195.896738) (xy 298.68622 -195.347082) (xy 299.31614 -195.347082) (xy 299.31614 -195.896738)
			)
		)
	)
	(zone
		(layer "In11.Cu")
		(hatch none 0.5)
		(connect_pads
			(clearance 0)
		)
		(min_thickness 0.25)
		(keepout
			(tracks allowed)
			(vias allowed)
			(pads allowed)
			(copperpour allowed)
			(footprints allowed)
		)
		(placement
			(enabled no)
			(sheetname "")
		)
		(fill
			(thermal_gap 0.5)
			(thermal_bridge_width 0.5)
			(island_removal_mode 0)
		)
		(polygon
			(pts
				(xy 50.771552 -291.096954) (xy 50.771552 -290.547298) (xy 51.401472 -290.547298) (xy 51.401472 -291.096954)
			)
		)
	)
	(zone
		(layer "In11.Cu")
		(hatch none 0.5)
		(connect_pads
			(clearance 0)
		)
		(min_thickness 0.25)
		(keepout
			(tracks allowed)
			(vias allowed)
			(pads allowed)
			(copperpour allowed)
			(footprints allowed)
		)
		(placement
			(enabled no)
			(sheetname "")
		)
		(fill
			(thermal_gap 0.5)
			(thermal_bridge_width 0.5)
			(island_removal_mode 0)
		)
		(polygon
			(pts
				(xy 405.897842 -227.014786) (xy 405.897842 -227.290376) (xy 405.339042 -227.290376) (xy 405.339042 -227.014786)
			)
		)
	)
	(zone
		(layer "In11.Cu")
		(hatch none 0.5)
		(connect_pads
			(clearance 0)
		)
		(min_thickness 0.25)
		(keepout
			(tracks allowed)
			(vias allowed)
			(pads allowed)
			(copperpour allowed)
			(footprints allowed)
		)
		(placement
			(enabled no)
			(sheetname "")
		)
		(fill
			(thermal_gap 0.5)
			(thermal_bridge_width 0.5)
			(island_removal_mode 0)
		)
		(polygon
			(pts
				(xy 421.010842 -207.46466) (xy 421.010842 -207.74025) (xy 420.452042 -207.74025) (xy 420.452042 -207.46466)
			)
		)
	)
	(zone
		(layer "In11.Cu")
		(hatch none 0.5)
		(connect_pads
			(clearance 0)
		)
		(min_thickness 0.25)
		(keepout
			(tracks allowed)
			(vias allowed)
			(pads allowed)
			(copperpour allowed)
			(footprints allowed)
		)
		(placement
			(enabled no)
			(sheetname "")
		)
		(fill
			(thermal_gap 0.5)
			(thermal_bridge_width 0.5)
			(island_removal_mode 0)
		)
		(polygon
			(pts
				(xy 432.105054 -259.418582) (xy 432.105054 -259.142992) (xy 432.663854 -259.142992) (xy 432.663854 -259.418582)
			)
		)
	)
	(zone
		(layer "In11.Cu")
		(hatch none 0.5)
		(connect_pads
			(clearance 0)
		)
		(min_thickness 0.25)
		(keepout
			(tracks allowed)
			(vias allowed)
			(pads allowed)
			(copperpour allowed)
			(footprints allowed)
		)
		(placement
			(enabled no)
			(sheetname "")
		)
		(fill
			(thermal_gap 0.5)
			(thermal_bridge_width 0.5)
			(island_removal_mode 0)
		)
		(polygon
			(pts
				(xy 294.586152 -299.59681) (xy 294.586152 -299.047154) (xy 295.216072 -299.047154) (xy 295.216072 -299.59681)
			)
		)
	)
	(zone
		(layer "In11.Cu")
		(hatch none 0.5)
		(connect_pads
			(clearance 0)
		)
		(min_thickness 0.25)
		(keepout
			(tracks allowed)
			(vias allowed)
			(pads allowed)
			(copperpour allowed)
			(footprints allowed)
		)
		(placement
			(enabled no)
			(sheetname "")
		)
		(fill
			(thermal_gap 0.5)
			(thermal_bridge_width 0.5)
			(island_removal_mode 0)
		)
		(polygon
			(pts
				(xy 46.646084 -228.196902) (xy 46.646084 -227.647246) (xy 47.276004 -227.647246) (xy 47.276004 -228.196902)
			)
		)
	)
	(zone
		(layer "In11.Cu")
		(hatch none 0.5)
		(connect_pads
			(clearance 0)
		)
		(min_thickness 0.25)
		(keepout
			(tracks allowed)
			(vias allowed)
			(pads allowed)
			(copperpour allowed)
			(footprints allowed)
		)
		(placement
			(enabled no)
			(sheetname "")
		)
		(fill
			(thermal_gap 0.5)
			(thermal_bridge_width 0.5)
			(island_removal_mode 0)
		)
		(polygon
			(pts
				(xy 424.561254 -210.96859) (xy 424.561254 -210.693) (xy 425.120054 -210.693) (xy 425.120054 -210.96859)
			)
		)
	)
	(zone
		(layer "In11.Cu")
		(hatch none 0.5)
		(connect_pads
			(clearance 0)
		)
		(min_thickness 0.25)
		(keepout
			(tracks allowed)
			(vias allowed)
			(pads allowed)
			(copperpour allowed)
			(footprints allowed)
		)
		(placement
			(enabled no)
			(sheetname "")
		)
		(fill
			(thermal_gap 0.5)
			(thermal_bridge_width 0.5)
			(island_removal_mode 0)
		)
		(polygon
			(pts
				(xy 46.646084 -308.946804) (xy 46.646084 -308.397148) (xy 47.276004 -308.397148) (xy 47.276004 -308.946804)
			)
		)
	)
	(zone
		(layer "In11.Cu")
		(hatch none 0.5)
		(connect_pads
			(clearance 0)
		)
		(min_thickness 0.25)
		(keepout
			(tracks allowed)
			(vias allowed)
			(pads allowed)
			(copperpour allowed)
			(footprints allowed)
		)
		(placement
			(enabled no)
			(sheetname "")
		)
		(fill
			(thermal_gap 0.5)
			(thermal_bridge_width 0.5)
			(island_removal_mode 0)
		)
		(polygon
			(pts
				(xy 425.11091 -228.714808) (xy 425.11091 -228.990398) (xy 424.55211 -228.990398) (xy 424.55211 -228.714808)
			)
		)
	)
	(zone
		(layer "In11.Cu")
		(hatch none 0.5)
		(connect_pads
			(clearance 0)
		)
		(min_thickness 0.25)
		(keepout
			(tracks allowed)
			(vias allowed)
			(pads allowed)
			(copperpour allowed)
			(footprints allowed)
		)
		(placement
			(enabled no)
			(sheetname "")
		)
		(fill
			(thermal_gap 0.5)
			(thermal_bridge_width 0.5)
			(island_removal_mode 0)
		)
		(polygon
			(pts
				(xy 50.746152 -216.296748) (xy 50.746152 -215.747092) (xy 51.376072 -215.747092) (xy 51.376072 -216.296748)
			)
		)
	)
	(zone
		(layer "In11.Cu")
		(hatch none 0.5)
		(connect_pads
			(clearance 0)
		)
		(min_thickness 0.25)
		(keepout
			(tracks allowed)
			(vias allowed)
			(pads allowed)
			(copperpour allowed)
			(footprints allowed)
		)
		(placement
			(enabled no)
			(sheetname "")
		)
		(fill
			(thermal_gap 0.5)
			(thermal_bridge_width 0.5)
			(island_removal_mode 0)
		)
		(polygon
			(pts
				(xy 420.461186 -226.268534) (xy 420.461186 -225.992944) (xy 421.019986 -225.992944) (xy 421.019986 -226.268534)
			)
		)
	)
	(zone
		(layer "In11.Cu")
		(hatch none 0.5)
		(connect_pads
			(clearance 0)
		)
		(min_thickness 0.25)
		(keepout
			(tracks allowed)
			(vias allowed)
			(pads allowed)
			(copperpour allowed)
			(footprints allowed)
		)
		(placement
			(enabled no)
			(sheetname "")
		)
		(fill
			(thermal_gap 0.5)
			(thermal_bridge_width 0.5)
			(island_removal_mode 0)
		)
		(polygon
			(pts
				(xy 20.570952 -223.94672) (xy 20.570952 -223.397064) (xy 21.200872 -223.397064) (xy 21.200872 -223.94672)
			)
		)
	)
	(zone
		(layer "In11.Cu")
		(hatch none 0.5)
		(connect_pads
			(clearance 0)
		)
		(min_thickness 0.25)
		(keepout
			(tracks allowed)
			(vias allowed)
			(pads allowed)
			(copperpour allowed)
			(footprints allowed)
		)
		(placement
			(enabled no)
			(sheetname "")
		)
		(fill
			(thermal_gap 0.5)
			(thermal_bridge_width 0.5)
			(island_removal_mode 0)
		)
		(polygon
			(pts
				(xy 172.521118 -251.76861) (xy 172.521118 -251.49302) (xy 173.079918 -251.49302) (xy 173.079918 -251.76861)
			)
		)
	)
	(zone
		(layer "In11.Cu")
		(hatch none 0.5)
		(connect_pads
			(clearance 0)
		)
		(min_thickness 0.25)
		(keepout
			(tracks allowed)
			(vias allowed)
			(pads allowed)
			(copperpour allowed)
			(footprints allowed)
		)
		(placement
			(enabled no)
			(sheetname "")
		)
		(fill
			(thermal_gap 0.5)
			(thermal_bridge_width 0.5)
			(island_removal_mode 0)
		)
		(polygon
			(pts
				(xy 203.245974 -236.36478) (xy 203.245974 -236.64037) (xy 202.687174 -236.64037) (xy 202.687174 -236.36478)
			)
		)
	)
	(zone
		(layer "In11.Cu")
		(hatch none 0.5)
		(connect_pads
			(clearance 0)
		)
		(min_thickness 0.25)
		(keepout
			(tracks allowed)
			(vias allowed)
			(pads allowed)
			(copperpour allowed)
			(footprints allowed)
		)
		(placement
			(enabled no)
			(sheetname "")
		)
		(fill
			(thermal_gap 0.5)
			(thermal_bridge_width 0.5)
			(island_removal_mode 0)
		)
		(polygon
			(pts
				(xy 298.68622 -220.54693) (xy 298.68622 -219.997274) (xy 299.31614 -219.997274) (xy 299.31614 -220.54693)
			)
		)
	)
	(zone
		(layer "In11.Cu")
		(hatch none 0.5)
		(connect_pads
			(clearance 0)
		)
		(min_thickness 0.25)
		(keepout
			(tracks allowed)
			(vias allowed)
			(pads allowed)
			(copperpour allowed)
			(footprints allowed)
		)
		(placement
			(enabled no)
			(sheetname "")
		)
		(fill
			(thermal_gap 0.5)
			(thermal_bridge_width 0.5)
			(island_removal_mode 0)
		)
		(polygon
			(pts
				(xy 46.646084 -224.796858) (xy 46.646084 -224.247202) (xy 47.276004 -224.247202) (xy 47.276004 -224.796858)
			)
		)
	)
	(zone
		(layer "In11.Cu")
		(hatch none 0.5)
		(connect_pads
			(clearance 0)
		)
		(min_thickness 0.25)
		(keepout
			(tracks allowed)
			(vias allowed)
			(pads allowed)
			(copperpour allowed)
			(footprints allowed)
		)
		(placement
			(enabled no)
			(sheetname "")
		)
		(fill
			(thermal_gap 0.5)
			(thermal_bridge_width 0.5)
			(island_removal_mode 0)
		)
		(polygon
			(pts
				(xy 177.170842 -233.81462) (xy 177.170842 -234.09021) (xy 176.612042 -234.09021) (xy 176.612042 -233.81462)
			)
		)
	)
	(zone
		(layer "In11.Cu")
		(hatch none 0.5)
		(connect_pads
			(clearance 0)
		)
		(min_thickness 0.25)
		(keepout
			(tracks allowed)
			(vias allowed)
			(pads allowed)
			(copperpour allowed)
			(footprints allowed)
		)
		(placement
			(enabled no)
			(sheetname "")
		)
		(fill
			(thermal_gap 0.5)
			(thermal_bridge_width 0.5)
			(island_removal_mode 0)
		)
		(polygon
			(pts
				(xy 43.239944 -267.319506) (xy 43.239944 -266.737846) (xy 43.798744 -266.737846) (xy 43.798744 -267.319506)
			)
		)
	)
	(zone
		(layer "In11.Cu")
		(hatch none 0.5)
		(connect_pads
			(clearance 0)
		)
		(min_thickness 0.25)
		(keepout
			(tracks allowed)
			(vias allowed)
			(pads allowed)
			(copperpour allowed)
			(footprints allowed)
		)
		(placement
			(enabled no)
			(sheetname "")
		)
		(fill
			(thermal_gap 0.5)
			(thermal_bridge_width 0.5)
			(island_removal_mode 0)
		)
		(polygon
			(pts
				(xy 298.68622 -209.496914) (xy 298.68622 -208.947258) (xy 299.31614 -208.947258) (xy 299.31614 -209.496914)
			)
		)
	)
	(zone
		(layer "In11.Cu")
		(hatch none 0.5)
		(connect_pads
			(clearance 0)
		)
		(min_thickness 0.25)
		(keepout
			(tracks allowed)
			(vias allowed)
			(pads allowed)
			(copperpour allowed)
			(footprints allowed)
		)
		(placement
			(enabled no)
			(sheetname "")
		)
		(fill
			(thermal_gap 0.5)
			(thermal_bridge_width 0.5)
			(island_removal_mode 0)
		)
		(polygon
			(pts
				(xy 268.51102 -236.696758) (xy 268.51102 -236.147102) (xy 269.14094 -236.147102) (xy 269.14094 -236.696758)
			)
		)
	)
	(zone
		(layer "In11.Cu")
		(hatch none 0.5)
		(connect_pads
			(clearance 0)
		)
		(min_thickness 0.25)
		(keepout
			(tracks allowed)
			(vias allowed)
			(pads allowed)
			(copperpour allowed)
			(footprints allowed)
		)
		(placement
			(enabled no)
			(sheetname "")
		)
		(fill
			(thermal_gap 0.5)
			(thermal_bridge_width 0.5)
			(island_removal_mode 0)
		)
		(polygon
			(pts
				(xy 326.75576 -347.975428) (xy 326.75576 -346.306648) (xy 329.20432 -346.306648) (xy 329.20432 -347.975428)
			)
		)
	)
	(zone
		(layer "In11.Cu")
		(hatch none 0.5)
		(connect_pads
			(clearance 0)
		)
		(min_thickness 0.25)
		(keepout
			(tracks allowed)
			(vias allowed)
			(pads allowed)
			(copperpour allowed)
			(footprints allowed)
		)
		(placement
			(enabled no)
			(sheetname "")
		)
		(fill
			(thermal_gap 0.5)
			(thermal_bridge_width 0.5)
			(island_removal_mode 0)
		)
		(polygon
			(pts
				(xy 46.646084 -288.546794) (xy 46.646084 -287.997138) (xy 47.276004 -287.997138) (xy 47.276004 -288.546794)
			)
		)
	)
	(zone
		(layer "In11.Cu")
		(hatch none 0.5)
		(connect_pads
			(clearance 0)
		)
		(min_thickness 0.25)
		(keepout
			(tracks allowed)
			(vias allowed)
			(pads allowed)
			(copperpour allowed)
			(footprints allowed)
		)
		(placement
			(enabled no)
			(sheetname "")
		)
		(fill
			(thermal_gap 0.5)
			(thermal_bridge_width 0.5)
			(island_removal_mode 0)
		)
		(polygon
			(pts
				(xy 450.636386 -265.368532) (xy 450.636386 -265.092942) (xy 451.195186 -265.092942) (xy 451.195186 -265.368532)
			)
		)
	)
	(zone
		(layer "In11.Cu")
		(hatch none 0.5)
		(connect_pads
			(clearance 0)
		)
		(min_thickness 0.25)
		(keepout
			(tracks allowed)
			(vias allowed)
			(pads allowed)
			(copperpour allowed)
			(footprints allowed)
		)
		(placement
			(enabled no)
			(sheetname "")
		)
		(fill
			(thermal_gap 0.5)
			(thermal_bridge_width 0.5)
			(island_removal_mode 0)
		)
		(polygon
			(pts
				(xy 298.68622 -225.646742) (xy 298.68622 -225.097086) (xy 299.31614 -225.097086) (xy 299.31614 -225.646742)
			)
		)
	)
	(zone
		(layer "In11.Cu")
		(hatch none 0.5)
		(connect_pads
			(clearance 0)
		)
		(min_thickness 0.25)
		(keepout
			(tracks allowed)
			(vias allowed)
			(pads allowed)
			(copperpour allowed)
			(footprints allowed)
		)
		(placement
			(enabled no)
			(sheetname "")
		)
		(fill
			(thermal_gap 0.5)
			(thermal_bridge_width 0.5)
			(island_removal_mode 0)
		)
		(polygon
			(pts
				(xy 416.49904 -179.489608) (xy 416.49904 -175.946308) (xy 416.9918 -175.453548) (xy 417.82238 -175.453548)
				(xy 418.7825 -176.413668) (xy 418.7825 -178.382168) (xy 417.6395 -179.525168) (xy 416.5346 -179.525168)
			)
		)
	)
	(zone
		(layer "In11.Cu")
		(hatch none 0.5)
		(connect_pads
			(clearance 0)
		)
		(min_thickness 0.25)
		(keepout
			(tracks allowed)
			(vias allowed)
			(pads allowed)
			(copperpour allowed)
			(footprints allowed)
		)
		(placement
			(enabled no)
			(sheetname "")
		)
		(fill
			(thermal_gap 0.5)
			(thermal_bridge_width 0.5)
			(island_removal_mode 0)
		)
		(polygon
			(pts
				(xy 46.646084 -271.546828) (xy 46.646084 -270.997172) (xy 47.276004 -270.997172) (xy 47.276004 -271.546828)
			)
		)
	)
	(zone
		(layer "In11.Cu")
		(hatch none 0.5)
		(connect_pads
			(clearance 0)
		)
		(min_thickness 0.25)
		(keepout
			(tracks allowed)
			(vias allowed)
			(pads allowed)
			(copperpour allowed)
			(footprints allowed)
		)
		(placement
			(enabled no)
			(sheetname "")
		)
		(fill
			(thermal_gap 0.5)
			(thermal_bridge_width 0.5)
			(island_removal_mode 0)
		)
		(polygon
			(pts
				(xy 202.696318 -249.21845) (xy 202.696318 -248.94286) (xy 203.255118 -248.94286) (xy 203.255118 -249.21845)
			)
		)
	)
	(zone
		(layer "In11.Cu")
		(hatch none 0.5)
		(connect_pads
			(clearance 0)
		)
		(min_thickness 0.25)
		(keepout
			(tracks allowed)
			(vias allowed)
			(pads allowed)
			(copperpour allowed)
			(footprints allowed)
		)
		(placement
			(enabled no)
			(sheetname "")
		)
		(fill
			(thermal_gap 0.5)
			(thermal_bridge_width 0.5)
			(island_removal_mode 0)
		)
		(polygon
			(pts
				(xy 177.170842 -307.764688) (xy 177.170842 -308.040278) (xy 176.612042 -308.040278) (xy 176.612042 -307.764688)
			)
		)
	)
	(zone
		(layer "In11.Cu")
		(hatch none 0.5)
		(connect_pads
			(clearance 0)
		)
		(min_thickness 0.25)
		(keepout
			(tracks allowed)
			(vias allowed)
			(pads allowed)
			(copperpour allowed)
			(footprints allowed)
		)
		(placement
			(enabled no)
			(sheetname "")
		)
		(fill
			(thermal_gap 0.5)
			(thermal_bridge_width 0.5)
			(island_removal_mode 0)
		)
		(polygon
			(pts
				(xy 420.461186 -220.318584) (xy 420.461186 -220.042994) (xy 421.019986 -220.042994) (xy 421.019986 -220.318584)
			)
		)
	)
	(zone
		(layer "In11.Cu")
		(hatch none 0.5)
		(connect_pads
			(clearance 0)
		)
		(min_thickness 0.25)
		(keepout
			(tracks allowed)
			(vias allowed)
			(pads allowed)
			(copperpour allowed)
			(footprints allowed)
		)
		(placement
			(enabled no)
			(sheetname "")
		)
		(fill
			(thermal_gap 0.5)
			(thermal_bridge_width 0.5)
			(island_removal_mode 0)
		)
		(polygon
			(pts
				(xy 450.636386 -277.268432) (xy 450.636386 -276.992842) (xy 451.195186 -276.992842) (xy 451.195186 -277.268432)
			)
		)
	)
	(zone
		(layer "In11.Cu")
		(hatch none 0.5)
		(connect_pads
			(clearance 0)
		)
		(min_thickness 0.25)
		(keepout
			(tracks allowed)
			(vias allowed)
			(pads allowed)
			(copperpour allowed)
			(footprints allowed)
		)
		(placement
			(enabled no)
			(sheetname "")
		)
		(fill
			(thermal_gap 0.5)
			(thermal_bridge_width 0.5)
			(island_removal_mode 0)
		)
		(polygon
			(pts
				(xy 202.696318 -297.392852) (xy 203.255118 -297.392852) (xy 203.255118 -297.668442) (xy 203.255118 -298.219876)
				(xy 202.722988 -298.219876) (xy 202.722988 -299.073062) (xy 203.255118 -299.073062) (xy 203.255118 -299.540168)
				(xy 201.753978 -299.540168) (xy 201.753978 -297.392852)
			)
		)
	)
	(zone
		(layer "In11.Cu")
		(hatch none 0.5)
		(connect_pads
			(clearance 0)
		)
		(min_thickness 0.25)
		(keepout
			(tracks allowed)
			(vias allowed)
			(pads allowed)
			(copperpour allowed)
			(footprints allowed)
		)
		(placement
			(enabled no)
			(sheetname "")
		)
		(fill
			(thermal_gap 0.5)
			(thermal_bridge_width 0.5)
			(island_removal_mode 0)
		)
		(polygon
			(pts
				(xy 294.586152 -313.196732) (xy 294.586152 -312.647076) (xy 295.216072 -312.647076) (xy 295.216072 -313.196732)
			)
		)
	)
	(zone
		(layer "In11.Cu")
		(hatch none 0.5)
		(connect_pads
			(clearance 0)
		)
		(min_thickness 0.25)
		(keepout
			(tracks allowed)
			(vias allowed)
			(pads allowed)
			(copperpour allowed)
			(footprints allowed)
		)
		(placement
			(enabled no)
			(sheetname "")
		)
		(fill
			(thermal_gap 0.5)
			(thermal_bridge_width 0.5)
			(island_removal_mode 0)
		)
		(polygon
			(pts
				(xy 294.586152 -251.146818) (xy 294.586152 -250.597162) (xy 295.216072 -250.597162) (xy 295.216072 -251.146818)
			)
		)
	)
	(zone
		(layer "In11.Cu")
		(hatch none 0.5)
		(connect_pads
			(clearance 0)
		)
		(min_thickness 0.25)
		(keepout
			(tracks allowed)
			(vias allowed)
			(pads allowed)
			(copperpour allowed)
			(footprints allowed)
		)
		(placement
			(enabled no)
			(sheetname "")
		)
		(fill
			(thermal_gap 0.5)
			(thermal_bridge_width 0.5)
			(island_removal_mode 0)
		)
		(polygon
			(pts
				(xy 172.521118 -211.818474) (xy 172.521118 -211.542884) (xy 173.079918 -211.542884) (xy 173.079918 -211.818474)
			)
		)
	)
	(zone
		(layer "In11.Cu")
		(hatch none 0.5)
		(connect_pads
			(clearance 0)
		)
		(min_thickness 0.25)
		(keepout
			(tracks allowed)
			(vias allowed)
			(pads allowed)
			(copperpour allowed)
			(footprints allowed)
		)
		(placement
			(enabled no)
			(sheetname "")
		)
		(fill
			(thermal_gap 0.5)
			(thermal_bridge_width 0.5)
			(island_removal_mode 0)
		)
		(polygon
			(pts
				(xy 268.51102 -197.59676) (xy 268.51102 -197.047104) (xy 269.14094 -197.047104) (xy 269.14094 -197.59676)
			)
		)
	)
	(zone
		(layer "In11.Cu")
		(hatch none 0.5)
		(connect_pads
			(clearance 0)
		)
		(min_thickness 0.25)
		(keepout
			(tracks allowed)
			(vias allowed)
			(pads allowed)
			(copperpour allowed)
			(footprints allowed)
		)
		(placement
			(enabled no)
			(sheetname "")
		)
		(fill
			(thermal_gap 0.5)
			(thermal_bridge_width 0.5)
			(island_removal_mode 0)
		)
		(polygon
			(pts
				(xy 98.23958 -299.776388) (xy 98.23958 -290.731448) (xy 110.82528 -290.731448) (xy 110.82528 -299.776388)
			)
		)
	)
	(zone
		(layer "In11.Cu")
		(hatch none 0.5)
		(connect_pads
			(clearance 0)
		)
		(min_thickness 0.25)
		(keepout
			(tracks allowed)
			(vias allowed)
			(pads allowed)
			(copperpour allowed)
			(footprints allowed)
		)
		(placement
			(enabled no)
			(sheetname "")
		)
		(fill
			(thermal_gap 0.5)
			(thermal_bridge_width 0.5)
			(island_removal_mode 0)
		)
		(polygon
			(pts
				(xy 50.746152 -246.89689) (xy 50.746152 -246.347234) (xy 51.376072 -246.347234) (xy 51.376072 -246.89689)
			)
		)
	)
	(zone
		(layer "In11.Cu")
		(hatch none 0.5)
		(connect_pads
			(clearance 0)
		)
		(min_thickness 0.25)
		(keepout
			(tracks allowed)
			(vias allowed)
			(pads allowed)
			(copperpour allowed)
			(footprints allowed)
		)
		(placement
			(enabled no)
			(sheetname "")
		)
		(fill
			(thermal_gap 0.5)
			(thermal_bridge_width 0.5)
			(island_removal_mode 0)
		)
		(polygon
			(pts
				(xy 46.646084 -310.646826) (xy 46.646084 -310.09717) (xy 47.276004 -310.09717) (xy 47.276004 -310.646826)
			)
		)
	)
	(zone
		(layer "In11.Cu")
		(hatch none 0.5)
		(connect_pads
			(clearance 0)
		)
		(min_thickness 0.25)
		(keepout
			(tracks allowed)
			(vias allowed)
			(pads allowed)
			(copperpour allowed)
			(footprints allowed)
		)
		(placement
			(enabled no)
			(sheetname "")
		)
		(fill
			(thermal_gap 0.5)
			(thermal_bridge_width 0.5)
			(island_removal_mode 0)
		)
		(polygon
			(pts
				(xy 203.245974 -216.814654) (xy 203.245974 -217.090244) (xy 202.687174 -217.090244) (xy 202.687174 -216.814654)
			)
		)
	)
	(zone
		(layer "In11.Cu")
		(hatch none 0.5)
		(connect_pads
			(clearance 0)
		)
		(min_thickness 0.25)
		(keepout
			(tracks allowed)
			(vias allowed)
			(pads allowed)
			(copperpour allowed)
			(footprints allowed)
		)
		(placement
			(enabled no)
			(sheetname "")
		)
		(fill
			(thermal_gap 0.5)
			(thermal_bridge_width 0.5)
			(island_removal_mode 0)
		)
		(polygon
			(pts
				(xy 202.696318 -293.142924) (xy 203.255118 -293.142924) (xy 203.255118 -293.418514) (xy 203.255118 -293.75989)
				(xy 202.541378 -293.75989) (xy 202.541378 -293.142924)
			)
		)
	)
	(zone
		(layer "In11.Cu")
		(hatch none 0.5)
		(connect_pads
			(clearance 0)
		)
		(min_thickness 0.25)
		(keepout
			(tracks allowed)
			(vias allowed)
			(pads allowed)
			(copperpour allowed)
			(footprints allowed)
		)
		(placement
			(enabled no)
			(sheetname "")
		)
		(fill
			(thermal_gap 0.5)
			(thermal_bridge_width 0.5)
			(island_removal_mode 0)
		)
		(polygon
			(pts
				(xy 203.245974 -224.464626) (xy 203.245974 -224.740216) (xy 202.687174 -224.740216) (xy 202.687174 -224.464626)
			)
		)
	)
	(zone
		(layer "In11.Cu")
		(hatch none 0.5)
		(connect_pads
			(clearance 0)
		)
		(min_thickness 0.25)
		(keepout
			(tracks allowed)
			(vias allowed)
			(pads allowed)
			(copperpour allowed)
			(footprints allowed)
		)
		(placement
			(enabled no)
			(sheetname "")
		)
		(fill
			(thermal_gap 0.5)
			(thermal_bridge_width 0.5)
			(island_removal_mode 0)
		)
		(polygon
			(pts
				(xy 177.170842 -292.464744) (xy 177.170842 -292.740334) (xy 176.612042 -292.740334) (xy 176.612042 -292.464744)
			)
		)
	)
	(zone
		(layer "In11.Cu")
		(hatch none 0.5)
		(connect_pads
			(clearance 0)
		)
		(min_thickness 0.25)
		(keepout
			(tracks allowed)
			(vias allowed)
			(pads allowed)
			(copperpour allowed)
			(footprints allowed)
		)
		(placement
			(enabled no)
			(sheetname "")
		)
		(fill
			(thermal_gap 0.5)
			(thermal_bridge_width 0.5)
			(island_removal_mode 0)
		)
		(polygon
			(pts
				(xy 268.51102 -205.246732) (xy 268.51102 -204.697076) (xy 269.14094 -204.697076) (xy 269.14094 -205.246732)
			)
		)
	)
	(zone
		(layer "In11.Cu")
		(hatch none 0.5)
		(connect_pads
			(clearance 0)
		)
		(min_thickness 0.25)
		(keepout
			(tracks allowed)
			(vias allowed)
			(pads allowed)
			(copperpour allowed)
			(footprints allowed)
		)
		(placement
			(enabled no)
			(sheetname "")
		)
		(fill
			(thermal_gap 0.5)
			(thermal_bridge_width 0.5)
			(island_removal_mode 0)
		)
		(polygon
			(pts
				(xy 420.461186 -233.918506) (xy 420.461186 -233.642916) (xy 421.019986 -233.642916) (xy 421.019986 -233.918506)
			)
		)
	)
	(zone
		(layer "In11.Cu")
		(hatch none 0.5)
		(connect_pads
			(clearance 0)
		)
		(min_thickness 0.25)
		(keepout
			(tracks allowed)
			(vias allowed)
			(pads allowed)
			(copperpour allowed)
			(footprints allowed)
		)
		(placement
			(enabled no)
			(sheetname "")
		)
		(fill
			(thermal_gap 0.5)
			(thermal_bridge_width 0.5)
			(island_removal_mode 0)
		)
		(polygon
			(pts
				(xy 424.561254 -250.918472) (xy 424.561254 -250.642882) (xy 425.120054 -250.642882) (xy 425.120054 -250.918472)
			)
		)
	)
	(zone
		(layer "In11.Cu")
		(hatch none 0.5)
		(connect_pads
			(clearance 0)
		)
		(min_thickness 0.25)
		(keepout
			(tracks allowed)
			(vias allowed)
			(pads allowed)
			(copperpour allowed)
			(footprints allowed)
		)
		(placement
			(enabled no)
			(sheetname "")
		)
		(fill
			(thermal_gap 0.5)
			(thermal_bridge_width 0.5)
			(island_removal_mode 0)
		)
		(polygon
			(pts
				(xy 424.561254 -216.068402) (xy 424.561254 -215.792812) (xy 425.120054 -215.792812) (xy 425.120054 -216.068402)
			)
		)
	)
	(zone
		(layer "In11.Cu")
		(hatch none 0.5)
		(connect_pads
			(clearance 0)
		)
		(min_thickness 0.25)
		(keepout
			(tracks allowed)
			(vias allowed)
			(pads allowed)
			(copperpour allowed)
			(footprints allowed)
		)
		(placement
			(enabled no)
			(sheetname "")
		)
		(fill
			(thermal_gap 0.5)
			(thermal_bridge_width 0.5)
			(island_removal_mode 0)
		)
		(polygon
			(pts
				(xy 191.708786 -210.118452) (xy 191.708786 -209.842862) (xy 192.267586 -209.842862) (xy 192.267586 -210.118452)
			)
		)
	)
	(zone
		(layer "In11.Cu")
		(hatch none 0.5)
		(connect_pads
			(clearance 0)
		)
		(min_thickness 0.25)
		(keepout
			(tracks allowed)
			(vias allowed)
			(pads allowed)
			(copperpour allowed)
			(footprints allowed)
		)
		(placement
			(enabled no)
			(sheetname "")
		)
		(fill
			(thermal_gap 0.5)
			(thermal_bridge_width 0.5)
			(island_removal_mode 0)
		)
		(polygon
			(pts
				(xy 177.170842 -198.114666) (xy 177.170842 -198.390256) (xy 176.612042 -198.390256) (xy 176.612042 -198.114666)
			)
		)
	)
	(zone
		(layer "In11.Cu")
		(hatch none 0.5)
		(connect_pads
			(clearance 0)
		)
		(min_thickness 0.25)
		(keepout
			(tracks allowed)
			(vias allowed)
			(pads allowed)
			(copperpour allowed)
			(footprints allowed)
		)
		(placement
			(enabled no)
			(sheetname "")
		)
		(fill
			(thermal_gap 0.5)
			(thermal_bridge_width 0.5)
			(island_removal_mode 0)
		)
		(polygon
			(pts
				(xy 46.646084 -235.846874) (xy 46.646084 -235.297218) (xy 47.276004 -235.297218) (xy 47.276004 -235.846874)
			)
		)
	)
	(zone
		(layer "In11.Cu")
		(hatch none 0.5)
		(connect_pads
			(clearance 0)
		)
		(min_thickness 0.25)
		(keepout
			(tracks allowed)
			(vias allowed)
			(pads allowed)
			(copperpour allowed)
			(footprints allowed)
		)
		(placement
			(enabled no)
			(sheetname "")
		)
		(fill
			(thermal_gap 0.5)
			(thermal_bridge_width 0.5)
			(island_removal_mode 0)
		)
		(polygon
			(pts
				(xy 421.010842 -217.664792) (xy 421.010842 -217.940382) (xy 420.452042 -217.940382) (xy 420.452042 -217.664792)
			)
		)
	)
	(zone
		(layer "In11.Cu")
		(hatch none 0.5)
		(connect_pads
			(clearance 0)
		)
		(min_thickness 0.25)
		(keepout
			(tracks allowed)
			(vias allowed)
			(pads allowed)
			(copperpour allowed)
			(footprints allowed)
		)
		(placement
			(enabled no)
			(sheetname "")
		)
		(fill
			(thermal_gap 0.5)
			(thermal_bridge_width 0.5)
			(island_removal_mode 0)
		)
		(polygon
			(pts
				(xy 50.746152 -234.996736) (xy 50.746152 -234.44708) (xy 51.376072 -234.44708) (xy 51.376072 -234.996736)
			)
		)
	)
	(zone
		(layer "In11.Cu")
		(hatch none 0.5)
		(connect_pads
			(clearance 0)
		)
		(min_thickness 0.25)
		(keepout
			(tracks allowed)
			(vias allowed)
			(pads allowed)
			(copperpour allowed)
			(footprints allowed)
		)
		(placement
			(enabled no)
			(sheetname "")
		)
		(fill
			(thermal_gap 0.5)
			(thermal_bridge_width 0.5)
			(island_removal_mode 0)
		)
		(polygon
			(pts
				(xy 425.11091 -285.664656) (xy 425.11091 -285.940246) (xy 424.55211 -285.940246) (xy 424.55211 -285.664656)
			)
		)
	)
	(zone
		(layer "In11.Cu")
		(hatch none 0.5)
		(connect_pads
			(clearance 0)
		)
		(min_thickness 0.25)
		(keepout
			(tracks allowed)
			(vias allowed)
			(pads allowed)
			(copperpour allowed)
			(footprints allowed)
		)
		(placement
			(enabled no)
			(sheetname "")
		)
		(fill
			(thermal_gap 0.5)
			(thermal_bridge_width 0.5)
			(island_removal_mode 0)
		)
		(polygon
			(pts
				(xy 173.070774 -294.164766) (xy 173.070774 -294.440356) (xy 172.511974 -294.440356) (xy 172.511974 -294.164766)
			)
		)
	)
	(zone
		(layer "In11.Cu")
		(hatch none 0.5)
		(connect_pads
			(clearance 0)
		)
		(min_thickness 0.25)
		(keepout
			(tracks allowed)
			(vias allowed)
			(pads allowed)
			(copperpour allowed)
			(footprints allowed)
		)
		(placement
			(enabled no)
			(sheetname "")
		)
		(fill
			(thermal_gap 0.5)
			(thermal_bridge_width 0.5)
			(island_removal_mode 0)
		)
		(polygon
			(pts
				(xy 425.11091 -199.814688) (xy 425.11091 -200.090278) (xy 424.55211 -200.090278) (xy 424.55211 -199.814688)
			)
		)
	)
	(zone
		(layer "In11.Cu")
		(hatch none 0.5)
		(connect_pads
			(clearance 0)
		)
		(min_thickness 0.25)
		(keepout
			(tracks allowed)
			(vias allowed)
			(pads allowed)
			(copperpour allowed)
			(footprints allowed)
		)
		(placement
			(enabled no)
			(sheetname "")
		)
		(fill
			(thermal_gap 0.5)
			(thermal_bridge_width 0.5)
			(island_removal_mode 0)
		)
		(polygon
			(pts
				(xy 268.558518 -260.49224) (xy 268.558518 -259.951982) (xy 269.117318 -259.951982) (xy 269.117318 -260.49224)
			)
		)
	)
	(zone
		(layer "In11.Cu")
		(hatch none 0.5)
		(connect_pads
			(clearance 0)
		)
		(min_thickness 0.25)
		(keepout
			(tracks allowed)
			(vias allowed)
			(pads allowed)
			(copperpour allowed)
			(footprints allowed)
		)
		(placement
			(enabled no)
			(sheetname "")
		)
		(fill
			(thermal_gap 0.5)
			(thermal_bridge_width 0.5)
			(island_removal_mode 0)
		)
		(polygon
			(pts
				(xy 46.646084 -282.596844) (xy 46.646084 -282.047188) (xy 47.276004 -282.047188) (xy 47.276004 -282.596844)
			)
		)
	)
	(zone
		(layer "In11.Cu")
		(hatch none 0.5)
		(connect_pads
			(clearance 0)
		)
		(min_thickness 0.25)
		(keepout
			(tracks allowed)
			(vias allowed)
			(pads allowed)
			(copperpour allowed)
			(footprints allowed)
		)
		(placement
			(enabled no)
			(sheetname "")
		)
		(fill
			(thermal_gap 0.5)
			(thermal_bridge_width 0.5)
			(island_removal_mode 0)
		)
		(polygon
			(pts
				(xy 173.070774 -258.464812) (xy 173.070774 -258.740402) (xy 172.511974 -258.740402) (xy 172.511974 -258.464812)
			)
		)
	)
	(zone
		(layer "In11.Cu")
		(hatch none 0.5)
		(connect_pads
			(clearance 0)
		)
		(min_thickness 0.25)
		(keepout
			(tracks allowed)
			(vias allowed)
			(pads allowed)
			(copperpour allowed)
			(footprints allowed)
		)
		(placement
			(enabled no)
			(sheetname "")
		)
		(fill
			(thermal_gap 0.5)
			(thermal_bridge_width 0.5)
			(island_removal_mode 0)
		)
		(polygon
			(pts
				(xy 451.186042 -276.314662) (xy 451.186042 -276.590252) (xy 450.627242 -276.590252) (xy 450.627242 -276.314662)
			)
		)
	)
	(zone
		(layer "In11.Cu")
		(hatch none 0.5)
		(connect_pads
			(clearance 0)
		)
		(min_thickness 0.25)
		(keepout
			(tracks allowed)
			(vias allowed)
			(pads allowed)
			(copperpour allowed)
			(footprints allowed)
		)
		(placement
			(enabled no)
			(sheetname "")
		)
		(fill
			(thermal_gap 0.5)
			(thermal_bridge_width 0.5)
			(island_removal_mode 0)
		)
		(polygon
			(pts
				(xy 50.746152 -229.896924) (xy 50.746152 -229.347268) (xy 51.376072 -229.347268) (xy 51.376072 -229.896924)
			)
		)
	)
	(zone
		(layer "In11.Cu")
		(hatch none 0.5)
		(connect_pads
			(clearance 0)
		)
		(min_thickness 0.25)
		(keepout
			(tracks not_allowed)
			(vias allowed)
			(pads allowed)
			(copperpour not_allowed)
			(footprints allowed)
		)
		(placement
			(enabled no)
			(sheetname "")
		)
		(fill
			(thermal_gap 0.5)
			(thermal_bridge_width 0.5)
			(island_removal_mode 0)
		)
		(polygon
			(pts
				(arc
					(start 156.242004 -428.960788)
					(mid 156.264322 -429.01467)
					(end 156.318204 -429.036988)
				)
				(arc
					(start 157.258004 -429.036988)
					(mid 157.311886 -429.01467)
					(end 157.334204 -428.960788)
				)
				(arc
					(start 157.334204 -426.419264)
					(mid 157.311886 -426.365382)
					(end 157.258004 -426.343064)
				)
				(arc
					(start 156.318204 -426.343064)
					(mid 156.264322 -426.365382)
					(end 156.242004 -426.419264)
				)
			)
		)
	)
	(zone
		(layer "In11.Cu")
		(hatch none 0.5)
		(connect_pads
			(clearance 0)
		)
		(min_thickness 0.25)
		(keepout
			(tracks allowed)
			(vias allowed)
			(pads allowed)
			(copperpour allowed)
			(footprints allowed)
		)
		(placement
			(enabled no)
			(sheetname "")
		)
		(fill
			(thermal_gap 0.5)
			(thermal_bridge_width 0.5)
			(island_removal_mode 0)
		)
		(polygon
			(pts
				(xy 20.624292 -303.000664) (xy 20.624292 -302.450246) (xy 21.183092 -302.450246) (xy 21.183092 -303.000664)
			)
		)
	)
	(zone
		(layer "In11.Cu")
		(hatch none 0.5)
		(connect_pads
			(clearance 0)
		)
		(min_thickness 0.25)
		(keepout
			(tracks allowed)
			(vias allowed)
			(pads allowed)
			(copperpour allowed)
			(footprints allowed)
		)
		(placement
			(enabled no)
			(sheetname "")
		)
		(fill
			(thermal_gap 0.5)
			(thermal_bridge_width 0.5)
			(island_removal_mode 0)
		)
		(polygon
			(pts
				(xy 298.68622 -223.94672) (xy 298.68622 -223.397064) (xy 299.31614 -223.397064) (xy 299.31614 -223.94672)
			)
		)
	)
	(zone
		(layer "In11.Cu")
		(hatch none 0.5)
		(connect_pads
			(clearance 0)
		)
		(min_thickness 0.25)
		(keepout
			(tracks allowed)
			(vias allowed)
			(pads allowed)
			(copperpour allowed)
			(footprints allowed)
		)
		(placement
			(enabled no)
			(sheetname "")
		)
		(fill
			(thermal_gap 0.5)
			(thermal_bridge_width 0.5)
			(island_removal_mode 0)
		)
		(polygon
			(pts
				(xy 46.646084 -209.496914) (xy 46.646084 -208.947258) (xy 47.276004 -208.947258) (xy 47.276004 -209.496914)
			)
		)
	)
	(zone
		(layer "In11.Cu")
		(hatch none 0.5)
		(connect_pads
			(clearance 0)
		)
		(min_thickness 0.25)
		(keepout
			(tracks allowed)
			(vias allowed)
			(pads allowed)
			(copperpour allowed)
			(footprints allowed)
		)
		(placement
			(enabled no)
			(sheetname "")
		)
		(fill
			(thermal_gap 0.5)
			(thermal_bridge_width 0.5)
			(island_removal_mode 0)
		)
		(polygon
			(pts
				(xy 20.570952 -236.696758) (xy 20.570952 -236.147102) (xy 21.200872 -236.147102) (xy 21.200872 -236.696758)
			)
		)
	)
	(zone
		(layer "In11.Cu")
		(hatch none 0.5)
		(connect_pads
			(clearance 0)
		)
		(min_thickness 0.25)
		(keepout
			(tracks allowed)
			(vias allowed)
			(pads allowed)
			(copperpour allowed)
			(footprints allowed)
		)
		(placement
			(enabled no)
			(sheetname "")
		)
		(fill
			(thermal_gap 0.5)
			(thermal_bridge_width 0.5)
			(island_removal_mode 0)
		)
		(polygon
			(pts
				(xy 210.240118 -267.918438) (xy 210.240118 -267.642848) (xy 210.798918 -267.642848) (xy 210.798918 -267.918438)
			)
		)
	)
	(zone
		(layer "In11.Cu")
		(hatch none 0.5)
		(connect_pads
			(clearance 0)
		)
		(min_thickness 0.25)
		(keepout
			(tracks allowed)
			(vias allowed)
			(pads allowed)
			(copperpour allowed)
			(footprints allowed)
		)
		(placement
			(enabled no)
			(sheetname "")
		)
		(fill
			(thermal_gap 0.5)
			(thermal_bridge_width 0.5)
			(island_removal_mode 0)
		)
		(polygon
			(pts
				(xy 420.461186 -224.568512) (xy 420.461186 -224.292922) (xy 421.019986 -224.292922) (xy 421.019986 -224.568512)
			)
		)
	)
	(zone
		(layer "In11.Cu")
		(hatch none 0.5)
		(connect_pads
			(clearance 0)
		)
		(min_thickness 0.25)
		(keepout
			(tracks allowed)
			(vias allowed)
			(pads allowed)
			(copperpour allowed)
			(footprints allowed)
		)
		(placement
			(enabled no)
			(sheetname "")
		)
		(fill
			(thermal_gap 0.5)
			(thermal_bridge_width 0.5)
			(island_removal_mode 0)
		)
		(polygon
			(pts
				(xy 424.561254 -312.118502) (xy 424.561254 -311.842912) (xy 425.120054 -311.842912) (xy 425.120054 -312.118502)
			)
		)
	)
	(zone
		(layer "In11.Cu")
		(hatch none 0.5)
		(connect_pads
			(clearance 0)
		)
		(min_thickness 0.25)
		(keepout
			(tracks allowed)
			(vias allowed)
			(pads allowed)
			(copperpour allowed)
			(footprints allowed)
		)
		(placement
			(enabled no)
			(sheetname "")
		)
		(fill
			(thermal_gap 0.5)
			(thermal_bridge_width 0.5)
			(island_removal_mode 0)
		)
		(polygon
			(pts
				(xy 424.561254 -219.468446) (xy 424.561254 -219.192856) (xy 425.120054 -219.192856) (xy 425.120054 -219.468446)
			)
		)
	)
	(zone
		(layer "In11.Cu")
		(hatch none 0.5)
		(connect_pads
			(clearance 0)
		)
		(min_thickness 0.25)
		(keepout
			(tracks allowed)
			(vias allowed)
			(pads allowed)
			(copperpour allowed)
			(footprints allowed)
		)
		(placement
			(enabled no)
			(sheetname "")
		)
		(fill
			(thermal_gap 0.5)
			(thermal_bridge_width 0.5)
			(island_removal_mode 0)
		)
		(polygon
			(pts
				(xy 451.186042 -248.26468) (xy 451.186042 -248.54027) (xy 450.627242 -248.54027) (xy 450.627242 -248.26468)
			)
		)
	)
	(zone
		(layer "In11.Cu")
		(hatch none 0.5)
		(connect_pads
			(clearance 0)
		)
		(min_thickness 0.25)
		(keepout
			(tracks allowed)
			(vias allowed)
			(pads allowed)
			(copperpour allowed)
			(footprints allowed)
		)
		(placement
			(enabled no)
			(sheetname "")
		)
		(fill
			(thermal_gap 0.5)
			(thermal_bridge_width 0.5)
			(island_removal_mode 0)
		)
		(polygon
			(pts
				(xy 268.51102 -220.54693) (xy 268.51102 -219.997274) (xy 269.14094 -219.997274) (xy 269.14094 -220.54693)
			)
		)
	)
	(zone
		(layer "In11.Cu")
		(hatch none 0.5)
		(connect_pads
			(clearance 0)
		)
		(min_thickness 0.25)
		(keepout
			(tracks allowed)
			(vias allowed)
			(pads allowed)
			(copperpour allowed)
			(footprints allowed)
		)
		(placement
			(enabled no)
			(sheetname "")
		)
		(fill
			(thermal_gap 0.5)
			(thermal_bridge_width 0.5)
			(island_removal_mode 0)
		)
		(polygon
			(pts
				(xy 202.696318 -272.16862) (xy 202.696318 -271.89303) (xy 203.255118 -271.89303) (xy 203.255118 -272.16862)
			)
		)
	)
	(zone
		(layer "In11.Cu")
		(hatch none 0.5)
		(connect_pads
			(clearance 0)
		)
		(min_thickness 0.25)
		(keepout
			(tracks allowed)
			(vias allowed)
			(pads allowed)
			(copperpour allowed)
			(footprints allowed)
		)
		(placement
			(enabled no)
			(sheetname "")
		)
		(fill
			(thermal_gap 0.5)
			(thermal_bridge_width 0.5)
			(island_removal_mode 0)
		)
		(polygon
			(pts
				(xy 287.34258 -367.629948) (xy 287.34258 -366.332008) (xy 289.06724 -366.332008) (xy 289.06724 -367.629948)
			)
		)
	)
	(zone
		(layer "In11.Cu")
		(hatch none 0.5)
		(connect_pads
			(clearance 0)
		)
		(min_thickness 0.25)
		(keepout
			(tracks allowed)
			(vias allowed)
			(pads allowed)
			(copperpour allowed)
			(footprints allowed)
		)
		(placement
			(enabled no)
			(sheetname "")
		)
		(fill
			(thermal_gap 0.5)
			(thermal_bridge_width 0.5)
			(island_removal_mode 0)
		)
		(polygon
			(pts
				(xy 424.561254 -307.018436) (xy 424.561254 -306.742846) (xy 425.120054 -306.742846) (xy 425.120054 -307.018436)
			)
		)
	)
	(zone
		(layer "In11.Cu")
		(hatch none 0.5)
		(connect_pads
			(clearance 0)
		)
		(min_thickness 0.25)
		(keepout
			(tracks allowed)
			(vias allowed)
			(pads allowed)
			(copperpour allowed)
			(footprints allowed)
		)
		(placement
			(enabled no)
			(sheetname "")
		)
		(fill
			(thermal_gap 0.5)
			(thermal_bridge_width 0.5)
			(island_removal_mode 0)
		)
		(polygon
			(pts
				(xy 294.586152 -312.346848) (xy 294.586152 -311.797192) (xy 295.216072 -311.797192) (xy 295.216072 -312.346848)
			)
		)
	)
	(zone
		(layer "In11.Cu")
		(hatch none 0.5)
		(connect_pads
			(clearance 0)
		)
		(min_thickness 0.25)
		(keepout
			(tracks allowed)
			(vias allowed)
			(pads allowed)
			(copperpour allowed)
			(footprints allowed)
		)
		(placement
			(enabled no)
			(sheetname "")
		)
		(fill
			(thermal_gap 0.5)
			(thermal_bridge_width 0.5)
			(island_removal_mode 0)
		)
		(polygon
			(pts
				(xy 176.621186 -274.718526) (xy 176.621186 -274.442936) (xy 177.179986 -274.442936) (xy 177.179986 -274.718526)
			)
		)
	)
	(zone
		(layer "In11.Cu")
		(hatch none 0.5)
		(connect_pads
			(clearance 0)
		)
		(min_thickness 0.25)
		(keepout
			(tracks allowed)
			(vias allowed)
			(pads allowed)
			(copperpour allowed)
			(footprints allowed)
		)
		(placement
			(enabled no)
			(sheetname "")
		)
		(fill
			(thermal_gap 0.5)
			(thermal_bridge_width 0.5)
			(island_removal_mode 0)
		)
		(polygon
			(pts
				(xy 50.746152 -237.546896) (xy 50.746152 -236.99724) (xy 51.376072 -236.99724) (xy 51.376072 -237.546896)
			)
		)
	)
	(zone
		(layer "In11.Cu")
		(hatch none 0.5)
		(connect_pads
			(clearance 0)
		)
		(min_thickness 0.25)
		(keepout
			(tracks allowed)
			(vias allowed)
			(pads allowed)
			(copperpour allowed)
			(footprints allowed)
		)
		(placement
			(enabled no)
			(sheetname "")
		)
		(fill
			(thermal_gap 0.5)
			(thermal_bridge_width 0.5)
			(island_removal_mode 0)
		)
		(polygon
			(pts
				(xy 389.610346 -281.33421) (xy 390.359646 -281.33421) (xy 391.093706 -280.60015) (xy 391.093706 -279.90927)
				(xy 387.464046 -276.27961) (xy 387.32968 -276.27961) (xy 387.32968 -276.789134) (xy 387.708902 -277.168356)
				(xy 387.708902 -277.29942) (xy 387.615684 -277.392638) (xy 387.615684 -277.673816) (xy 387.746748 -277.80488)
				(xy 387.746748 -278.004524) (xy 387.602222 -278.14905) (xy 387.602222 -278.34082) (xy 387.74751 -278.486108)
				(xy 387.74751 -278.6634) (xy 387.572758 -278.838152) (xy 387.570726 -278.838152) (xy 387.570726 -279.29459)
				(xy 387.570726 -279.681432) (xy 387.961886 -280.072592) (xy 388.088886 -280.199592) (xy 388.088886 -280.47061)
				(xy 387.636766 -280.92273) (xy 387.636766 -281.01163) (xy 387.735826 -281.11069) (xy 387.740906 -281.11069)
				(xy 387.796786 -281.16657) (xy 387.796786 -281.32151) (xy 387.616446 -281.50185) (xy 387.616446 -281.63647)
				(xy 387.616446 -281.707082) (xy 387.3373 -281.986228) (xy 387.337808 -281.986736) (xy 387.337808 -282.026868)
				(xy 387.337808 -282.379928) (xy 388.79907 -283.84119) (xy 388.985506 -283.84119) (xy 389.076946 -283.74975)
				(xy 389.076946 -282.98267) (xy 388.909306 -282.81503) (xy 388.909306 -281.83713) (xy 389.412226 -281.33421)
			)
		)
	)
	(zone
		(layer "In11.Cu")
		(hatch none 0.5)
		(connect_pads
			(clearance 0)
		)
		(min_thickness 0.25)
		(keepout
			(tracks allowed)
			(vias allowed)
			(pads allowed)
			(copperpour allowed)
			(footprints allowed)
		)
		(placement
			(enabled no)
			(sheetname "")
		)
		(fill
			(thermal_gap 0.5)
			(thermal_bridge_width 0.5)
			(island_removal_mode 0)
		)
		(polygon
			(pts
				(xy 173.070774 -198.114666) (xy 173.070774 -198.390256) (xy 172.511974 -198.390256) (xy 172.511974 -198.114666)
			)
		)
	)
	(zone
		(layer "In11.Cu")
		(hatch none 0.5)
		(connect_pads
			(clearance 0)
		)
		(min_thickness 0.25)
		(keepout
			(tracks allowed)
			(vias allowed)
			(pads allowed)
			(copperpour allowed)
			(footprints allowed)
		)
		(placement
			(enabled no)
			(sheetname "")
		)
		(fill
			(thermal_gap 0.5)
			(thermal_bridge_width 0.5)
			(island_removal_mode 0)
		)
		(polygon
			(pts
				(xy 50.746152 -250.296934) (xy 50.746152 -249.747278) (xy 51.376072 -249.747278) (xy 51.376072 -250.296934)
			)
		)
	)
	(zone
		(layer "In11.Cu")
		(hatch none 0.5)
		(connect_pads
			(clearance 0)
		)
		(min_thickness 0.25)
		(keepout
			(tracks allowed)
			(vias allowed)
			(pads allowed)
			(copperpour allowed)
			(footprints allowed)
		)
		(placement
			(enabled no)
			(sheetname "")
		)
		(fill
			(thermal_gap 0.5)
			(thermal_bridge_width 0.5)
			(island_removal_mode 0)
		)
		(polygon
			(pts
				(xy 46.646084 -247.746774) (xy 46.646084 -247.197118) (xy 47.276004 -247.197118) (xy 47.276004 -247.746774)
			)
		)
	)
	(zone
		(layer "In11.Cu")
		(hatch none 0.5)
		(connect_pads
			(clearance 0)
		)
		(min_thickness 0.25)
		(keepout
			(tracks allowed)
			(vias allowed)
			(pads allowed)
			(copperpour allowed)
			(footprints allowed)
		)
		(placement
			(enabled no)
			(sheetname "")
		)
		(fill
			(thermal_gap 0.5)
			(thermal_bridge_width 0.5)
			(island_removal_mode 0)
		)
		(polygon
			(pts
				(xy 268.51102 -216.296748) (xy 268.51102 -215.747092) (xy 269.14094 -215.747092) (xy 269.14094 -216.296748)
			)
		)
	)
	(zone
		(layer "In11.Cu")
		(hatch none 0.5)
		(connect_pads
			(clearance 0)
		)
		(min_thickness 0.25)
		(keepout
			(tracks allowed)
			(vias allowed)
			(pads allowed)
			(copperpour allowed)
			(footprints allowed)
		)
		(placement
			(enabled no)
			(sheetname "")
		)
		(fill
			(thermal_gap 0.5)
			(thermal_bridge_width 0.5)
			(island_removal_mode 0)
		)
		(polygon
			(pts
				(xy 425.11091 -208.314798) (xy 425.11091 -208.590388) (xy 424.55211 -208.590388) (xy 424.55211 -208.314798)
			)
		)
	)
	(zone
		(layer "In11.Cu")
		(hatch none 0.5)
		(connect_pads
			(clearance 0)
		)
		(min_thickness 0.25)
		(keepout
			(tracks allowed)
			(vias allowed)
			(pads allowed)
			(copperpour allowed)
			(footprints allowed)
		)
		(placement
			(enabled no)
			(sheetname "")
		)
		(fill
			(thermal_gap 0.5)
			(thermal_bridge_width 0.5)
			(island_removal_mode 0)
		)
		(polygon
			(pts
				(xy 177.170842 -245.714774) (xy 177.170842 -245.990364) (xy 176.612042 -245.990364) (xy 176.612042 -245.714774)
			)
		)
	)
	(zone
		(layer "In11.Cu")
		(hatch none 0.5)
		(connect_pads
			(clearance 0)
		)
		(min_thickness 0.25)
		(keepout
			(tracks allowed)
			(vias allowed)
			(pads allowed)
			(copperpour allowed)
			(footprints allowed)
		)
		(placement
			(enabled no)
			(sheetname "")
		)
		(fill
			(thermal_gap 0.5)
			(thermal_bridge_width 0.5)
			(island_removal_mode 0)
		)
		(polygon
			(pts
				(xy 187.608718 -283.218382) (xy 187.608718 -282.942792) (xy 188.167518 -282.942792) (xy 188.167518 -283.218382)
			)
		)
	)
	(zone
		(layer "In11.Cu")
		(hatch none 0.5)
		(connect_pads
			(clearance 0)
		)
		(min_thickness 0.25)
		(keepout
			(tracks allowed)
			(vias allowed)
			(pads allowed)
			(copperpour allowed)
			(footprints allowed)
		)
		(placement
			(enabled no)
			(sheetname "")
		)
		(fill
			(thermal_gap 0.5)
			(thermal_bridge_width 0.5)
			(island_removal_mode 0)
		)
		(polygon
			(pts
				(xy 420.461186 -300.218602) (xy 420.461186 -299.943012) (xy 421.019986 -299.943012) (xy 421.019986 -300.218602)
			)
		)
	)
	(zone
		(layer "In11.Cu")
		(hatch none 0.5)
		(connect_pads
			(clearance 0)
		)
		(min_thickness 0.25)
		(keepout
			(tracks allowed)
			(vias allowed)
			(pads allowed)
			(copperpour allowed)
			(footprints allowed)
		)
		(placement
			(enabled no)
			(sheetname "")
		)
		(fill
			(thermal_gap 0.5)
			(thermal_bridge_width 0.5)
			(island_removal_mode 0)
		)
		(polygon
			(pts
				(xy 424.561254 -261.118604) (xy 424.561254 -260.843014) (xy 425.120054 -260.843014) (xy 425.120054 -261.118604)
			)
		)
	)
	(zone
		(layer "In11.Cu")
		(hatch none 0.5)
		(connect_pads
			(clearance 0)
		)
		(min_thickness 0.25)
		(keepout
			(tracks allowed)
			(vias allowed)
			(pads allowed)
			(copperpour allowed)
			(footprints allowed)
		)
		(placement
			(enabled no)
			(sheetname "")
		)
		(fill
			(thermal_gap 0.5)
			(thermal_bridge_width 0.5)
			(island_removal_mode 0)
		)
		(polygon
			(pts
				(xy 421.010842 -308.614826) (xy 421.010842 -308.890416) (xy 420.452042 -308.890416) (xy 420.452042 -308.614826)
			)
		)
	)
	(zone
		(layer "In11.Cu")
		(hatch none 0.5)
		(connect_pads
			(clearance 0)
		)
		(min_thickness 0.25)
		(keepout
			(tracks allowed)
			(vias allowed)
			(pads allowed)
			(copperpour allowed)
			(footprints allowed)
		)
		(placement
			(enabled no)
			(sheetname "")
		)
		(fill
			(thermal_gap 0.5)
			(thermal_bridge_width 0.5)
			(island_removal_mode 0)
		)
		(polygon
			(pts
				(xy 20.570952 -227.346764) (xy 20.570952 -226.797108) (xy 21.200872 -226.797108) (xy 21.200872 -227.346764)
			)
		)
	)
	(zone
		(layer "In11.Cu")
		(hatch none 0.5)
		(connect_pads
			(clearance 0)
		)
		(min_thickness 0.25)
		(keepout
			(tracks allowed)
			(vias allowed)
			(pads allowed)
			(copperpour allowed)
			(footprints allowed)
		)
		(placement
			(enabled no)
			(sheetname "")
		)
		(fill
			(thermal_gap 0.5)
			(thermal_bridge_width 0.5)
			(island_removal_mode 0)
		)
		(polygon
			(pts
				(xy 46.646084 -240.096802) (xy 46.646084 -239.547146) (xy 47.276004 -239.547146) (xy 47.276004 -240.096802)
			)
		)
	)
	(zone
		(layer "In11.Cu")
		(hatch none 0.5)
		(connect_pads
			(clearance 0)
		)
		(min_thickness 0.25)
		(keepout
			(tracks allowed)
			(vias allowed)
			(pads allowed)
			(copperpour allowed)
			(footprints allowed)
		)
		(placement
			(enabled no)
			(sheetname "")
		)
		(fill
			(thermal_gap 0.5)
			(thermal_bridge_width 0.5)
			(island_removal_mode 0)
		)
		(polygon
			(pts
				(xy 294.586152 -286.846772) (xy 294.586152 -286.297116) (xy 295.216072 -286.297116) (xy 295.216072 -286.846772)
			)
		)
	)
	(zone
		(layer "In11.Cu")
		(hatch none 0.5)
		(connect_pads
			(clearance 0)
		)
		(min_thickness 0.25)
		(keepout
			(tracks allowed)
			(vias allowed)
			(pads allowed)
			(copperpour allowed)
			(footprints allowed)
		)
		(placement
			(enabled no)
			(sheetname "")
		)
		(fill
			(thermal_gap 0.5)
			(thermal_bridge_width 0.5)
			(island_removal_mode 0)
		)
		(polygon
			(pts
				(xy 450.636386 -293.142924) (xy 451.195186 -293.142924) (xy 451.195186 -293.418514) (xy 451.195186 -293.75989)
				(xy 450.481446 -293.75989) (xy 450.481446 -293.142924)
			)
		)
	)
	(zone
		(layer "In11.Cu")
		(hatch none 0.5)
		(connect_pads
			(clearance 0)
		)
		(min_thickness 0.25)
		(keepout
			(tracks allowed)
			(vias allowed)
			(pads allowed)
			(copperpour allowed)
			(footprints allowed)
		)
		(placement
			(enabled no)
			(sheetname "")
		)
		(fill
			(thermal_gap 0.5)
			(thermal_bridge_width 0.5)
			(island_removal_mode 0)
		)
		(polygon
			(pts
				(xy 202.696318 -212.668612) (xy 202.696318 -212.393022) (xy 203.255118 -212.393022) (xy 203.255118 -212.668612)
			)
		)
	)
	(zone
		(layer "In11.Cu")
		(hatch none 0.5)
		(connect_pads
			(clearance 0)
		)
		(min_thickness 0.25)
		(keepout
			(tracks allowed)
			(vias allowed)
			(pads allowed)
			(copperpour allowed)
			(footprints allowed)
		)
		(placement
			(enabled no)
			(sheetname "")
		)
		(fill
			(thermal_gap 0.5)
			(thermal_bridge_width 0.5)
			(island_removal_mode 0)
		)
		(polygon
			(pts
				(xy 294.586152 -282.596844) (xy 294.586152 -282.047188) (xy 295.216072 -282.047188) (xy 295.216072 -282.596844)
			)
		)
	)
	(zone
		(layer "In11.Cu")
		(hatch none 0.5)
		(connect_pads
			(clearance 0)
		)
		(min_thickness 0.25)
		(keepout
			(tracks allowed)
			(vias allowed)
			(pads allowed)
			(copperpour allowed)
			(footprints allowed)
		)
		(placement
			(enabled no)
			(sheetname "")
		)
		(fill
			(thermal_gap 0.5)
			(thermal_bridge_width 0.5)
			(island_removal_mode 0)
		)
		(polygon
			(pts
				(xy 294.586152 -275.796756) (xy 294.586152 -275.2471) (xy 295.216072 -275.2471) (xy 295.216072 -275.796756)
			)
		)
	)
	(zone
		(layer "In11.Cu")
		(hatch none 0.5)
		(connect_pads
			(clearance 0)
		)
		(min_thickness 0.25)
		(keepout
			(tracks allowed)
			(vias allowed)
			(pads allowed)
			(copperpour allowed)
			(footprints allowed)
		)
		(placement
			(enabled no)
			(sheetname "")
		)
		(fill
			(thermal_gap 0.5)
			(thermal_bridge_width 0.5)
			(island_removal_mode 0)
		)
		(polygon
			(pts
				(xy 421.010842 -315.41466) (xy 421.010842 -315.69025) (xy 420.452042 -315.69025) (xy 420.452042 -315.41466)
			)
		)
	)
	(zone
		(layer "In11.Cu")
		(hatch none 0.5)
		(connect_pads
			(clearance 0)
		)
		(min_thickness 0.25)
		(keepout
			(tracks allowed)
			(vias allowed)
			(pads allowed)
			(copperpour allowed)
			(footprints allowed)
		)
		(placement
			(enabled no)
			(sheetname "")
		)
		(fill
			(thermal_gap 0.5)
			(thermal_bridge_width 0.5)
			(island_removal_mode 0)
		)
		(polygon
			(pts
				(xy 177.170842 -206.614776) (xy 177.170842 -206.890366) (xy 176.612042 -206.890366) (xy 176.612042 -206.614776)
			)
		)
	)
	(zone
		(layer "In11.Cu")
		(hatch none 0.5)
		(connect_pads
			(clearance 0)
		)
		(min_thickness 0.25)
		(keepout
			(tracks allowed)
			(vias allowed)
			(pads allowed)
			(copperpour allowed)
			(footprints allowed)
		)
		(placement
			(enabled no)
			(sheetname "")
		)
		(fill
			(thermal_gap 0.5)
			(thermal_bridge_width 0.5)
			(island_removal_mode 0)
		)
		(polygon
			(pts
				(xy 191.708786 -308.718458) (xy 191.708786 -308.442868) (xy 192.267586 -308.442868) (xy 192.267586 -308.718458)
			)
		)
	)
	(zone
		(layer "In11.Cu")
		(hatch none 0.5)
		(connect_pads
			(clearance 0)
		)
		(min_thickness 0.25)
		(keepout
			(tracks allowed)
			(vias allowed)
			(pads allowed)
			(copperpour allowed)
			(footprints allowed)
		)
		(placement
			(enabled no)
			(sheetname "")
		)
		(fill
			(thermal_gap 0.5)
			(thermal_bridge_width 0.5)
			(island_removal_mode 0)
		)
		(polygon
			(pts
				(xy 421.010842 -234.664758) (xy 421.010842 -234.940348) (xy 420.452042 -234.940348) (xy 420.452042 -234.664758)
			)
		)
	)
	(zone
		(layer "In11.Cu")
		(hatch none 0.5)
		(connect_pads
			(clearance 0)
		)
		(min_thickness 0.25)
		(keepout
			(tracks allowed)
			(vias allowed)
			(pads allowed)
			(copperpour allowed)
			(footprints allowed)
		)
		(placement
			(enabled no)
			(sheetname "")
		)
		(fill
			(thermal_gap 0.5)
			(thermal_bridge_width 0.5)
			(island_removal_mode 0)
		)
		(polygon
			(pts
				(xy 20.570952 -228.196902) (xy 20.570952 -227.647246) (xy 21.200872 -227.647246) (xy 21.200872 -228.196902)
			)
		)
	)
	(zone
		(layer "In11.Cu")
		(hatch none 0.5)
		(connect_pads
			(clearance 0)
		)
		(min_thickness 0.25)
		(keepout
			(tracks allowed)
			(vias allowed)
			(pads allowed)
			(copperpour allowed)
			(footprints allowed)
		)
		(placement
			(enabled no)
			(sheetname "")
		)
		(fill
			(thermal_gap 0.5)
			(thermal_bridge_width 0.5)
			(island_removal_mode 0)
		)
		(polygon
			(pts
				(xy 450.636386 -249.21845) (xy 450.636386 -248.94286) (xy 451.195186 -248.94286) (xy 451.195186 -249.21845)
			)
		)
	)
	(zone
		(layer "In11.Cu")
		(hatch none 0.5)
		(connect_pads
			(clearance 0)
		)
		(min_thickness 0.25)
		(keepout
			(tracks allowed)
			(vias allowed)
			(pads allowed)
			(copperpour allowed)
			(footprints allowed)
		)
		(placement
			(enabled no)
			(sheetname "")
		)
		(fill
			(thermal_gap 0.5)
			(thermal_bridge_width 0.5)
			(island_removal_mode 0)
		)
		(polygon
			(pts
				(xy 424.561254 -195.668392) (xy 424.561254 -195.392802) (xy 425.120054 -195.392802) (xy 425.120054 -195.668392)
			)
		)
	)
	(zone
		(layer "In11.Cu")
		(hatch none 0.5)
		(connect_pads
			(clearance 0)
		)
		(min_thickness 0.25)
		(keepout
			(tracks allowed)
			(vias allowed)
			(pads allowed)
			(copperpour allowed)
			(footprints allowed)
		)
		(placement
			(enabled no)
			(sheetname "")
		)
		(fill
			(thermal_gap 0.5)
			(thermal_bridge_width 0.5)
			(island_removal_mode 0)
		)
		(polygon
			(pts
				(xy 450.636386 -212.668612) (xy 450.636386 -212.393022) (xy 451.195186 -212.393022) (xy 451.195186 -212.668612)
			)
		)
	)
	(zone
		(layer "In11.Cu")
		(hatch none 0.5)
		(connect_pads
			(clearance 0)
		)
		(min_thickness 0.25)
		(keepout
			(tracks allowed)
			(vias allowed)
			(pads allowed)
			(copperpour allowed)
			(footprints allowed)
		)
		(placement
			(enabled no)
			(sheetname "")
		)
		(fill
			(thermal_gap 0.5)
			(thermal_bridge_width 0.5)
			(island_removal_mode 0)
		)
		(polygon
			(pts
				(xy 268.56436 -292.800786) (xy 268.56436 -292.250368) (xy 269.12316 -292.250368) (xy 269.12316 -292.800786)
			)
		)
	)
	(zone
		(layer "In11.Cu")
		(hatch none 0.5)
		(connect_pads
			(clearance 0)
		)
		(min_thickness 0.25)
		(keepout
			(tracks allowed)
			(vias allowed)
			(pads allowed)
			(copperpour allowed)
			(footprints allowed)
		)
		(placement
			(enabled no)
			(sheetname "")
		)
		(fill
			(thermal_gap 0.5)
			(thermal_bridge_width 0.5)
			(island_removal_mode 0)
		)
		(polygon
			(pts
				(xy 202.696318 -267.068554) (xy 202.696318 -266.792964) (xy 203.255118 -266.792964) (xy 203.255118 -267.068554)
			)
		)
	)
	(zone
		(layer "In11.Cu")
		(hatch none 0.5)
		(connect_pads
			(clearance 0)
		)
		(min_thickness 0.25)
		(keepout
			(tracks allowed)
			(vias allowed)
			(pads allowed)
			(copperpour allowed)
			(footprints allowed)
		)
		(placement
			(enabled no)
			(sheetname "")
		)
		(fill
			(thermal_gap 0.5)
			(thermal_bridge_width 0.5)
			(island_removal_mode 0)
		)
		(polygon
			(pts
				(xy 176.621186 -237.31855) (xy 176.621186 -237.04296) (xy 177.179986 -237.04296) (xy 177.179986 -237.31855)
			)
		)
	)
	(zone
		(layer "In11.Cu")
		(hatch none 0.5)
		(connect_pads
			(clearance 0)
		)
		(min_thickness 0.25)
		(keepout
			(tracks allowed)
			(vias allowed)
			(pads allowed)
			(copperpour allowed)
			(footprints allowed)
		)
		(placement
			(enabled no)
			(sheetname "")
		)
		(fill
			(thermal_gap 0.5)
			(thermal_bridge_width 0.5)
			(island_removal_mode 0)
		)
		(polygon
			(pts
				(xy 296.30624 -368.491008) (xy 296.30624 -366.131348) (xy 298.75734 -366.131348) (xy 298.75734 -368.491008)
			)
		)
	)
	(zone
		(layer "In11.Cu")
		(hatch none 0.5)
		(connect_pads
			(clearance 0)
		)
		(min_thickness 0.25)
		(keepout
			(tracks allowed)
			(vias allowed)
			(pads allowed)
			(copperpour allowed)
			(footprints allowed)
		)
		(placement
			(enabled no)
			(sheetname "")
		)
		(fill
			(thermal_gap 0.5)
			(thermal_bridge_width 0.5)
			(island_removal_mode 0)
		)
		(polygon
			(pts
				(xy 298.71162 -312.346848) (xy 298.71162 -311.797192) (xy 299.34154 -311.797192) (xy 299.34154 -312.346848)
			)
		)
	)
	(zone
		(layer "In11.Cu")
		(hatch none 0.5)
		(connect_pads
			(clearance 0)
		)
		(min_thickness 0.25)
		(keepout
			(tracks allowed)
			(vias allowed)
			(pads allowed)
			(copperpour allowed)
			(footprints allowed)
		)
		(placement
			(enabled no)
			(sheetname "")
		)
		(fill
			(thermal_gap 0.5)
			(thermal_bridge_width 0.5)
			(island_removal_mode 0)
		)
		(polygon
			(pts
				(xy 184.164986 -259.418582) (xy 184.164986 -259.142992) (xy 184.723786 -259.142992) (xy 184.723786 -259.418582)
			)
		)
	)
	(zone
		(layer "In11.Cu")
		(hatch none 0.5)
		(connect_pads
			(clearance 0)
		)
		(min_thickness 0.25)
		(keepout
			(tracks allowed)
			(vias allowed)
			(pads allowed)
			(copperpour allowed)
			(footprints allowed)
		)
		(placement
			(enabled no)
			(sheetname "")
		)
		(fill
			(thermal_gap 0.5)
			(thermal_bridge_width 0.5)
			(island_removal_mode 0)
		)
		(polygon
			(pts
				(xy 46.646084 -296.196766) (xy 46.646084 -295.64711) (xy 47.276004 -295.64711) (xy 47.276004 -296.196766)
			)
		)
	)
	(zone
		(layer "In11.Cu")
		(hatch none 0.5)
		(connect_pads
			(clearance 0)
		)
		(min_thickness 0.25)
		(keepout
			(tracks allowed)
			(vias allowed)
			(pads allowed)
			(copperpour allowed)
			(footprints allowed)
		)
		(placement
			(enabled no)
			(sheetname "")
		)
		(fill
			(thermal_gap 0.5)
			(thermal_bridge_width 0.5)
			(island_removal_mode 0)
		)
		(polygon
			(pts
				(xy 173.070774 -272.914618) (xy 173.070774 -273.190208) (xy 172.511974 -273.190208) (xy 172.511974 -272.914618)
			)
		)
	)
	(zone
		(layer "In11.Cu")
		(hatch none 0.5)
		(connect_pads
			(clearance 0)
		)
		(min_thickness 0.25)
		(keepout
			(tracks allowed)
			(vias allowed)
			(pads allowed)
			(copperpour allowed)
			(footprints allowed)
		)
		(placement
			(enabled no)
			(sheetname "")
		)
		(fill
			(thermal_gap 0.5)
			(thermal_bridge_width 0.5)
			(island_removal_mode 0)
		)
		(polygon
			(pts
				(xy 43.25493 -259.651754) (xy 43.25493 -259.083302) (xy 43.78071 -259.083302) (xy 43.78071 -259.651754)
			)
		)
	)
	(zone
		(layer "In11.Cu")
		(hatch none 0.5)
		(connect_pads
			(clearance 0)
		)
		(min_thickness 0.25)
		(keepout
			(tracks allowed)
			(vias allowed)
			(pads allowed)
			(copperpour allowed)
			(footprints allowed)
		)
		(placement
			(enabled no)
			(sheetname "")
		)
		(fill
			(thermal_gap 0.5)
			(thermal_bridge_width 0.5)
			(island_removal_mode 0)
		)
		(polygon
			(pts
				(xy 425.11091 -238.064802) (xy 425.11091 -238.340392) (xy 424.55211 -238.340392) (xy 424.55211 -238.064802)
			)
		)
	)
	(zone
		(layer "In11.Cu")
		(hatch none 0.5)
		(connect_pads
			(clearance 0)
		)
		(min_thickness 0.25)
		(keepout
			(tracks allowed)
			(vias allowed)
			(pads allowed)
			(copperpour allowed)
			(footprints allowed)
		)
		(placement
			(enabled no)
			(sheetname "")
		)
		(fill
			(thermal_gap 0.5)
			(thermal_bridge_width 0.5)
			(island_removal_mode 0)
		)
		(polygon
			(pts
				(xy 450.636386 -281.518614) (xy 450.636386 -281.243024) (xy 451.195186 -281.243024) (xy 451.195186 -281.518614)
			)
		)
	)
	(zone
		(layer "In11.Cu")
		(hatch none 0.5)
		(connect_pads
			(clearance 0)
		)
		(min_thickness 0.25)
		(keepout
			(tracks allowed)
			(vias allowed)
			(pads allowed)
			(copperpour allowed)
			(footprints allowed)
		)
		(placement
			(enabled no)
			(sheetname "")
		)
		(fill
			(thermal_gap 0.5)
			(thermal_bridge_width 0.5)
			(island_removal_mode 0)
		)
		(polygon
			(pts
				(xy 424.561254 -239.018572) (xy 424.561254 -238.742982) (xy 425.120054 -238.742982) (xy 425.120054 -239.018572)
			)
		)
	)
	(zone
		(layer "In11.Cu")
		(hatch none 0.5)
		(connect_pads
			(clearance 0)
		)
		(min_thickness 0.25)
		(keepout
			(tracks allowed)
			(vias allowed)
			(pads allowed)
			(copperpour allowed)
			(footprints allowed)
		)
		(placement
			(enabled no)
			(sheetname "")
		)
		(fill
			(thermal_gap 0.5)
			(thermal_bridge_width 0.5)
			(island_removal_mode 0)
		)
		(polygon
			(pts
				(xy 203.245974 -300.114716) (xy 203.245974 -300.390306) (xy 202.757024 -300.390306) (xy 202.757024 -300.787562)
				(xy 203.224384 -300.787562) (xy 203.224384 -301.289212) (xy 201.732388 -301.289212) (xy 201.732388 -300.114716)
				(xy 202.687174 -300.114716)
			)
		)
	)
	(zone
		(layer "In11.Cu")
		(hatch none 0.5)
		(connect_pads
			(clearance 0)
		)
		(min_thickness 0.25)
		(keepout
			(tracks allowed)
			(vias allowed)
			(pads allowed)
			(copperpour allowed)
			(footprints allowed)
		)
		(placement
			(enabled no)
			(sheetname "")
		)
		(fill
			(thermal_gap 0.5)
			(thermal_bridge_width 0.5)
			(island_removal_mode 0)
		)
		(polygon
			(pts
				(xy 20.624292 -300.450758) (xy 20.624292 -299.90034) (xy 21.183092 -299.90034) (xy 21.183092 -300.450758)
			)
		)
	)
	(zone
		(layer "In11.Cu")
		(hatch none 0.5)
		(connect_pads
			(clearance 0)
		)
		(min_thickness 0.25)
		(keepout
			(tracks allowed)
			(vias allowed)
			(pads allowed)
			(copperpour allowed)
			(footprints allowed)
		)
		(placement
			(enabled no)
			(sheetname "")
		)
		(fill
			(thermal_gap 0.5)
			(thermal_bridge_width 0.5)
			(island_removal_mode 0)
		)
		(polygon
			(pts
				(xy 455.28611 -266.964668) (xy 455.28611 -267.240258) (xy 454.72731 -267.240258) (xy 454.72731 -266.964668)
			)
		)
	)
	(zone
		(layer "In11.Cu")
		(hatch none 0.5)
		(connect_pads
			(clearance 0)
		)
		(min_thickness 0.25)
		(keepout
			(tracks not_allowed)
			(vias allowed)
			(pads allowed)
			(copperpour not_allowed)
			(footprints allowed)
		)
		(placement
			(enabled no)
			(sheetname "")
		)
		(fill
			(thermal_gap 0.5)
			(thermal_bridge_width 0.5)
			(island_removal_mode 0)
		)
		(polygon
			(pts
				(arc
					(start 85.14207 -428.960788)
					(mid 85.164388 -429.01467)
					(end 85.21827 -429.036988)
				)
				(arc
					(start 86.15807 -429.036988)
					(mid 86.211952 -429.01467)
					(end 86.23427 -428.960788)
				)
				(arc
					(start 86.23427 -426.419264)
					(mid 86.211952 -426.365382)
					(end 86.15807 -426.343064)
				)
				(arc
					(start 85.21827 -426.343064)
					(mid 85.164388 -426.365382)
					(end 85.14207 -426.419264)
				)
			)
		)
	)
	(zone
		(layer "In11.Cu")
		(hatch none 0.5)
		(connect_pads
			(clearance 0)
		)
		(min_thickness 0.25)
		(keepout
			(tracks allowed)
			(vias allowed)
			(pads allowed)
			(copperpour allowed)
			(footprints allowed)
		)
		(placement
			(enabled no)
			(sheetname "")
		)
		(fill
			(thermal_gap 0.5)
			(thermal_bridge_width 0.5)
			(island_removal_mode 0)
		)
		(polygon
			(pts
				(xy 8.974328 -246.012208) (xy 8.974328 -244.690138) (xy 9.501886 -244.690138) (xy 9.501886 -246.012208)
			)
		)
	)
	(zone
		(layer "In11.Cu")
		(hatch none 0.5)
		(connect_pads
			(clearance 0)
		)
		(min_thickness 0.25)
		(keepout
			(tracks allowed)
			(vias allowed)
			(pads allowed)
			(copperpour allowed)
			(footprints allowed)
		)
		(placement
			(enabled no)
			(sheetname "")
		)
		(fill
			(thermal_gap 0.5)
			(thermal_bridge_width 0.5)
			(island_removal_mode 0)
		)
		(polygon
			(pts
				(xy 425.11091 -312.864754) (xy 425.11091 -313.140344) (xy 424.55211 -313.140344) (xy 424.55211 -312.864754)
			)
		)
	)
	(zone
		(layer "In11.Cu")
		(hatch none 0.5)
		(connect_pads
			(clearance 0)
		)
		(min_thickness 0.25)
		(keepout
			(tracks allowed)
			(vias allowed)
			(pads allowed)
			(copperpour allowed)
			(footprints allowed)
		)
		(placement
			(enabled no)
			(sheetname "")
		)
		(fill
			(thermal_gap 0.5)
			(thermal_bridge_width 0.5)
			(island_removal_mode 0)
		)
		(polygon
			(pts
				(xy 202.696318 -247.518428) (xy 202.696318 -247.242838) (xy 203.255118 -247.242838) (xy 203.255118 -247.518428)
			)
		)
	)
	(zone
		(layer "In11.Cu")
		(hatch none 0.5)
		(connect_pads
			(clearance 0)
		)
		(min_thickness 0.25)
		(keepout
			(tracks allowed)
			(vias allowed)
			(pads allowed)
			(copperpour allowed)
			(footprints allowed)
		)
		(placement
			(enabled no)
			(sheetname "")
		)
		(fill
			(thermal_gap 0.5)
			(thermal_bridge_width 0.5)
			(island_removal_mode 0)
		)
		(polygon
			(pts
				(xy 421.010842 -278.014684) (xy 421.010842 -278.290274) (xy 420.452042 -278.290274) (xy 420.452042 -278.014684)
			)
		)
	)
	(zone
		(layer "In11.Cu")
		(hatch none 0.5)
		(connect_pads
			(clearance 0)
		)
		(min_thickness 0.25)
		(keepout
			(tracks allowed)
			(vias allowed)
			(pads allowed)
			(copperpour allowed)
			(footprints allowed)
		)
		(placement
			(enabled no)
			(sheetname "")
		)
		(fill
			(thermal_gap 0.5)
			(thermal_bridge_width 0.5)
			(island_removal_mode 0)
		)
		(polygon
			(pts
				(xy 298.68622 -201.846942) (xy 298.68622 -201.297286) (xy 299.31614 -201.297286) (xy 299.31614 -201.846942)
			)
		)
	)
	(zone
		(layer "In11.Cu")
		(hatch none 0.5)
		(connect_pads
			(clearance 0)
		)
		(min_thickness 0.25)
		(keepout
			(tracks allowed)
			(vias allowed)
			(pads allowed)
			(copperpour allowed)
			(footprints allowed)
		)
		(placement
			(enabled no)
			(sheetname "")
		)
		(fill
			(thermal_gap 0.5)
			(thermal_bridge_width 0.5)
			(island_removal_mode 0)
		)
		(polygon
			(pts
				(xy 424.561254 -308.718458) (xy 424.561254 -308.442868) (xy 425.120054 -308.442868) (xy 425.120054 -308.718458)
			)
		)
	)
	(zone
		(layer "In11.Cu")
		(hatch none 0.5)
		(connect_pads
			(clearance 0)
		)
		(min_thickness 0.25)
		(keepout
			(tracks allowed)
			(vias allowed)
			(pads allowed)
			(copperpour allowed)
			(footprints allowed)
		)
		(placement
			(enabled no)
			(sheetname "")
		)
		(fill
			(thermal_gap 0.5)
			(thermal_bridge_width 0.5)
			(island_removal_mode 0)
		)
		(polygon
			(pts
				(xy 425.11091 -248.26468) (xy 425.11091 -248.54027) (xy 424.55211 -248.54027) (xy 424.55211 -248.26468)
			)
		)
	)
	(zone
		(layer "In11.Cu")
		(hatch none 0.5)
		(connect_pads
			(clearance 0)
		)
		(min_thickness 0.25)
		(keepout
			(tracks allowed)
			(vias allowed)
			(pads allowed)
			(copperpour allowed)
			(footprints allowed)
		)
		(placement
			(enabled no)
			(sheetname "")
		)
		(fill
			(thermal_gap 0.5)
			(thermal_bridge_width 0.5)
			(island_removal_mode 0)
		)
		(polygon
			(pts
				(xy 173.070774 -199.814688) (xy 173.070774 -200.090278) (xy 172.511974 -200.090278) (xy 172.511974 -199.814688)
			)
		)
	)
	(zone
		(layer "In11.Cu")
		(hatch none 0.5)
		(connect_pads
			(clearance 0)
		)
		(min_thickness 0.25)
		(keepout
			(tracks allowed)
			(vias allowed)
			(pads allowed)
			(copperpour allowed)
			(footprints allowed)
		)
		(placement
			(enabled no)
			(sheetname "")
		)
		(fill
			(thermal_gap 0.5)
			(thermal_bridge_width 0.5)
			(island_removal_mode 0)
		)
		(polygon
			(pts
				(xy 20.570952 -195.896738) (xy 20.570952 -195.347082) (xy 21.200872 -195.347082) (xy 21.200872 -195.896738)
			)
		)
	)
	(zone
		(layer "In11.Cu")
		(hatch none 0.5)
		(connect_pads
			(clearance 0)
		)
		(min_thickness 0.25)
		(keepout
			(tracks not_allowed)
			(vias allowed)
			(pads allowed)
			(copperpour not_allowed)
			(footprints allowed)
		)
		(placement
			(enabled no)
			(sheetname "")
		)
		(fill
			(thermal_gap 0.5)
			(thermal_bridge_width 0.5)
			(island_removal_mode 0)
		)
		(polygon
			(pts
				(arc
					(start 345.142058 -428.960788)
					(mid 345.164376 -429.01467)
					(end 345.218258 -429.036988)
				)
				(arc
					(start 346.158058 -429.036988)
					(mid 346.21194 -429.01467)
					(end 346.234258 -428.960788)
				)
				(arc
					(start 346.234258 -426.419264)
					(mid 346.21194 -426.365382)
					(end 346.158058 -426.343064)
				)
				(arc
					(start 345.218258 -426.343064)
					(mid 345.164376 -426.365382)
					(end 345.142058 -426.419264)
				)
			)
		)
	)
	(zone
		(layer "In11.Cu")
		(hatch none 0.5)
		(connect_pads
			(clearance 0)
		)
		(min_thickness 0.25)
		(keepout
			(tracks allowed)
			(vias allowed)
			(pads allowed)
			(copperpour allowed)
			(footprints allowed)
		)
		(placement
			(enabled no)
			(sheetname "")
		)
		(fill
			(thermal_gap 0.5)
			(thermal_bridge_width 0.5)
			(island_removal_mode 0)
		)
		(polygon
			(pts
				(xy 440.12231 -267.814806) (xy 440.12231 -268.090396) (xy 439.56351 -268.090396) (xy 439.56351 -267.814806)
			)
		)
	)
	(zone
		(layer "In11.Cu")
		(hatch none 0.5)
		(connect_pads
			(clearance 0)
		)
		(min_thickness 0.25)
		(keepout
			(tracks allowed)
			(vias allowed)
			(pads allowed)
			(copperpour allowed)
			(footprints allowed)
		)
		(placement
			(enabled no)
			(sheetname "")
		)
		(fill
			(thermal_gap 0.5)
			(thermal_bridge_width 0.5)
			(island_removal_mode 0)
		)
		(polygon
			(pts
				(xy 451.186042 -261.014718) (xy 451.186042 -261.290308) (xy 450.627242 -261.290308) (xy 450.627242 -261.014718)
			)
		)
	)
	(zone
		(layer "In11.Cu")
		(hatch none 0.5)
		(connect_pads
			(clearance 0)
		)
		(min_thickness 0.25)
		(keepout
			(tracks allowed)
			(vias allowed)
			(pads allowed)
			(copperpour allowed)
			(footprints allowed)
		)
		(placement
			(enabled no)
			(sheetname "")
		)
		(fill
			(thermal_gap 0.5)
			(thermal_bridge_width 0.5)
			(island_removal_mode 0)
		)
		(polygon
			(pts
				(xy 298.71162 -259.646928) (xy 298.71162 -259.097272) (xy 299.34154 -259.097272) (xy 299.34154 -259.646928)
			)
		)
	)
	(zone
		(layer "In11.Cu")
		(hatch none 0.5)
		(connect_pads
			(clearance 0)
		)
		(min_thickness 0.25)
		(keepout
			(tracks allowed)
			(vias allowed)
			(pads allowed)
			(copperpour allowed)
			(footprints allowed)
		)
		(placement
			(enabled no)
			(sheetname "")
		)
		(fill
			(thermal_gap 0.5)
			(thermal_bridge_width 0.5)
			(island_removal_mode 0)
		)
		(polygon
			(pts
				(xy 425.11091 -278.014684) (xy 425.11091 -278.290274) (xy 424.55211 -278.290274) (xy 424.55211 -278.014684)
			)
		)
	)
	(zone
		(layer "In11.Cu")
		(hatch none 0.5)
		(connect_pads
			(clearance 0)
		)
		(min_thickness 0.25)
		(keepout
			(tracks allowed)
			(vias allowed)
			(pads allowed)
			(copperpour allowed)
			(footprints allowed)
		)
		(placement
			(enabled no)
			(sheetname "")
		)
		(fill
			(thermal_gap 0.5)
			(thermal_bridge_width 0.5)
			(island_removal_mode 0)
		)
		(polygon
			(pts
				(xy 188.158374 -309.46471) (xy 188.158374 -309.7403) (xy 187.599574 -309.7403) (xy 187.599574 -309.46471)
			)
		)
	)
	(zone
		(layer "In11.Cu")
		(hatch none 0.5)
		(connect_pads
			(clearance 0)
		)
		(min_thickness 0.25)
		(keepout
			(tracks allowed)
			(vias allowed)
			(pads allowed)
			(copperpour allowed)
			(footprints allowed)
		)
		(placement
			(enabled no)
			(sheetname "")
		)
		(fill
			(thermal_gap 0.5)
			(thermal_bridge_width 0.5)
			(island_removal_mode 0)
		)
		(polygon
			(pts
				(xy 451.186042 -216.814654) (xy 451.186042 -217.090244) (xy 450.627242 -217.090244) (xy 450.627242 -216.814654)
			)
		)
	)
	(zone
		(layer "In11.Cu")
		(hatch none 0.5)
		(connect_pads
			(clearance 0)
		)
		(min_thickness 0.25)
		(keepout
			(tracks allowed)
			(vias allowed)
			(pads allowed)
			(copperpour allowed)
			(footprints allowed)
		)
		(placement
			(enabled no)
			(sheetname "")
		)
		(fill
			(thermal_gap 0.5)
			(thermal_bridge_width 0.5)
			(island_removal_mode 0)
		)
		(polygon
			(pts
				(xy 20.624292 -276.650704) (xy 20.624292 -276.100286) (xy 21.183092 -276.100286) (xy 21.183092 -276.650704)
			)
		)
	)
	(zone
		(layer "In11.Cu")
		(hatch none 0.5)
		(connect_pads
			(clearance 0)
		)
		(min_thickness 0.25)
		(keepout
			(tracks not_allowed)
			(vias allowed)
			(pads allowed)
			(copperpour not_allowed)
			(footprints allowed)
		)
		(placement
			(enabled no)
			(sheetname "")
		)
		(fill
			(thermal_gap 0.5)
			(thermal_bridge_width 0.5)
			(island_removal_mode 0)
		)
		(polygon
			(pts
				(arc
					(start 341.142066 -428.960788)
					(mid 341.164384 -429.01467)
					(end 341.218266 -429.036988)
				)
				(arc
					(start 342.158066 -429.036988)
					(mid 342.211948 -429.01467)
					(end 342.234266 -428.960788)
				)
				(arc
					(start 342.234266 -426.419264)
					(mid 342.211948 -426.365382)
					(end 342.158066 -426.343064)
				)
				(arc
					(start 341.218266 -426.343064)
					(mid 341.164384 -426.365382)
					(end 341.142066 -426.419264)
				)
			)
		)
	)
	(zone
		(layer "In11.Cu")
		(hatch none 0.5)
		(connect_pads
			(clearance 0)
		)
		(min_thickness 0.25)
		(keepout
			(tracks allowed)
			(vias allowed)
			(pads allowed)
			(copperpour allowed)
			(footprints allowed)
		)
		(placement
			(enabled no)
			(sheetname "")
		)
		(fill
			(thermal_gap 0.5)
			(thermal_bridge_width 0.5)
			(island_removal_mode 0)
		)
		(polygon
			(pts
				(xy 424.561254 -288.318448) (xy 424.561254 -288.042858) (xy 425.120054 -288.042858) (xy 425.120054 -288.318448)
			)
		)
	)
	(zone
		(layer "In11.Cu")
		(hatch none 0.5)
		(connect_pads
			(clearance 0)
		)
		(min_thickness 0.25)
		(keepout
			(tracks allowed)
			(vias allowed)
			(pads allowed)
			(copperpour allowed)
			(footprints allowed)
		)
		(placement
			(enabled no)
			(sheetname "")
		)
		(fill
			(thermal_gap 0.5)
			(thermal_bridge_width 0.5)
			(island_removal_mode 0)
		)
		(polygon
			(pts
				(xy 298.68622 -218.846908) (xy 298.68622 -218.297252) (xy 299.31614 -218.297252) (xy 299.31614 -218.846908)
			)
		)
	)
	(zone
		(layer "In11.Cu")
		(hatch none 0.5)
		(connect_pads
			(clearance 0)
		)
		(min_thickness 0.25)
		(keepout
			(tracks allowed)
			(vias allowed)
			(pads allowed)
			(copperpour allowed)
			(footprints allowed)
		)
		(placement
			(enabled no)
			(sheetname "")
		)
		(fill
			(thermal_gap 0.5)
			(thermal_bridge_width 0.5)
			(island_removal_mode 0)
		)
		(polygon
			(pts
				(xy 157.433518 -225.418396) (xy 157.433518 -225.142806) (xy 157.992318 -225.142806) (xy 157.992318 -225.418396)
			)
		)
	)
	(zone
		(layer "In11.Cu")
		(hatch none 0.5)
		(connect_pads
			(clearance 0)
		)
		(min_thickness 0.25)
		(keepout
			(tracks allowed)
			(vias allowed)
			(pads allowed)
			(copperpour allowed)
			(footprints allowed)
		)
		(placement
			(enabled no)
			(sheetname "")
		)
		(fill
			(thermal_gap 0.5)
			(thermal_bridge_width 0.5)
			(island_removal_mode 0)
		)
		(polygon
			(pts
				(xy 46.646084 -241.796824) (xy 46.646084 -241.247168) (xy 47.276004 -241.247168) (xy 47.276004 -241.796824)
			)
		)
	)
	(zone
		(layer "In11.Cu")
		(hatch none 0.5)
		(connect_pads
			(clearance 0)
		)
		(min_thickness 0.25)
		(keepout
			(tracks allowed)
			(vias allowed)
			(pads allowed)
			(copperpour allowed)
			(footprints allowed)
		)
		(placement
			(enabled no)
			(sheetname "")
		)
		(fill
			(thermal_gap 0.5)
			(thermal_bridge_width 0.5)
			(island_removal_mode 0)
		)
		(polygon
			(pts
				(xy 20.624292 -281.75077) (xy 20.624292 -281.200352) (xy 21.183092 -281.200352) (xy 21.183092 -281.75077)
			)
		)
	)
	(zone
		(layer "In11.Cu")
		(hatch none 0.5)
		(connect_pads
			(clearance 0)
		)
		(min_thickness 0.25)
		(keepout
			(tracks allowed)
			(vias allowed)
			(pads allowed)
			(copperpour allowed)
			(footprints allowed)
		)
		(placement
			(enabled no)
			(sheetname "")
		)
		(fill
			(thermal_gap 0.5)
			(thermal_bridge_width 0.5)
			(island_removal_mode 0)
		)
		(polygon
			(pts
				(xy 420.461186 -312.968386) (xy 420.461186 -312.692796) (xy 421.019986 -312.692796) (xy 421.019986 -312.968386)
			)
		)
	)
	(zone
		(layer "In11.Cu")
		(hatch none 0.5)
		(connect_pads
			(clearance 0)
		)
		(min_thickness 0.25)
		(keepout
			(tracks allowed)
			(vias allowed)
			(pads allowed)
			(copperpour allowed)
			(footprints allowed)
		)
		(placement
			(enabled no)
			(sheetname "")
		)
		(fill
			(thermal_gap 0.5)
			(thermal_bridge_width 0.5)
			(island_removal_mode 0)
		)
		(polygon
			(pts
				(xy 102.965758 -210.893152) (xy 107.577382 -210.893152) (xy 110.310676 -210.893152) (xy 138.575288 -210.892644)
				(xy 138.773916 -211.091272) (xy 138.773916 -216.51468) (xy 139.451588 -217.192352) (xy 139.451842 -219.271342)
				(xy 140.282168 -220.101668) (xy 140.282168 -220.349826) (xy 140.432028 -220.499686) (xy 140.432028 -220.739208)
				(xy 140.308584 -220.862652) (xy 140.308584 -221.189804) (xy 141.185392 -222.066612) (xy 141.185392 -222.179642)
				(xy 140.944092 -222.420942) (xy 140.944092 -223.422464) (xy 140.06576 -224.300796) (xy 140.06576 -224.373948)
				(xy 140.96619 -225.274378) (xy 140.96619 -225.32213) (xy 140.405612 -225.882708) (xy 140.405612 -225.957892)
				(xy 140.6779 -226.23018) (xy 140.6779 -226.393756) (xy 140.2334 -226.838256) (xy 140.2334 -231.473248)
				(xy 140.518134 -231.757982) (xy 140.518134 -232.134156) (xy 140.339572 -232.312718) (xy 140.339572 -234.26674)
				(xy 140.579094 -234.506262) (xy 141.172184 -234.506262) (xy 141.17828 -234.512358) (xy 141.17828 -245.882668)
				(xy 140.795756 -246.265192) (xy 138.486896 -246.265446) (xy 138.479022 -246.265446) (xy 138.37666 -246.367808)
				(xy 138.37666 -246.796052) (xy 138.309604 -246.863108) (xy 138.309604 -249.408188) (xy 138.15822 -249.559572)
				(xy 138.15822 -249.806206) (xy 138.06932 -249.895106) (xy 137.89533 -249.895106) (xy 137.381996 -250.40844)
				(xy 136.922002 -250.40844) (xy 136.785096 -250.271534) (xy 127.345694 -250.271534) (xy 126.8095 -250.807728)
				(xy 124.53366 -250.807728) (xy 124.522738 -250.81865) (xy 124.522738 -251.660406) (xy 124.721366 -251.859034)
				(xy 124.721366 -252.919738) (xy 124.522738 -253.118366) (xy 124.522738 -253.966726) (xy 124.588778 -254.032766)
				(xy 124.997718 -254.032766) (xy 125.13691 -253.893574) (xy 125.253242 -253.893574) (xy 125.253242 -253.83363)
				(xy 125.253242 -253.708154) (xy 125.264418 -253.696978) (xy 125.535944 -253.696978) (xy 125.73254 -253.893574)
				(xy 140.18895 -253.89332) (xy 140.348462 -254.052832) (xy 140.348462 -258.149598) (xy 140.294614 -258.203446)
				(xy 140.18895 -258.203446) (xy 139.394946 -258.203446) (xy 139.294108 -258.304284) (xy 139.294108 -258.760722)
				(xy 139.438634 -258.905248) (xy 140.009118 -258.905248) (xy 140.069062 -258.965192) (xy 140.069062 -260.059932)
				(xy 140.13942 -260.13029) (xy 140.13942 -260.60527) (xy 140.025374 -260.719316) (xy 140.025374 -260.945376)
				(xy 140.215366 -261.135368) (xy 140.215366 -261.335266) (xy 140.203936 -261.346696) (xy 140.175996 -261.346696)
				(xy 139.986004 -261.536688) (xy 139.986004 -261.604252) (xy 140.67155 -262.289798) (xy 140.93571 -262.289798)
				(xy 140.98778 -262.341868) (xy 140.98778 -263.809988) (xy 140.955776 -263.841992) (xy 139.689078 -263.842246)
				(xy 139.689078 -265.798046) (xy 139.689078 -265.910314) (xy 139.936474 -266.15771) (xy 140.08862 -266.15771)
				(xy 140.18895 -266.25804) (xy 140.18895 -268.238732) (xy 140.266928 -268.31671) (xy 140.671042 -268.31671)
				(xy 140.74902 -268.394688) (xy 140.74902 -271.023588) (xy 140.569188 -271.20342) (xy 140.137388 -271.20342)
				(xy 139.967208 -271.20342) (xy 139.75842 -271.412208) (xy 139.75842 -271.582388) (xy 139.39266 -271.948148)
				(xy 139.39266 -276.792182) (xy 139.768834 -277.168356) (xy 139.768834 -277.29942) (xy 139.675616 -277.392638)
				(xy 139.675616 -277.673816) (xy 139.80668 -277.80488) (xy 139.80668 -278.004524) (xy 139.662154 -278.14905)
				(xy 139.662154 -278.34082) (xy 139.807442 -278.486108) (xy 139.807442 -278.6634) (xy 139.63269 -278.838152)
				(xy 139.630658 -278.838152) (xy 139.630658 -279.681432) (xy 140.021818 -280.072592) (xy 140.148818 -280.199592)
				(xy 140.148818 -280.47061) (xy 139.696698 -280.92273) (xy 139.696698 -281.01163) (xy 139.795758 -281.11069)
				(xy 139.800838 -281.11069) (xy 139.856718 -281.16657) (xy 139.856718 -281.32151) (xy 139.6746 -281.503628)
				(xy 139.6746 -281.716988) (xy 139.39774 -281.993848) (xy 139.39774 -282.379928) (xy 139.922758 -282.904946)
				(xy 140.583158 -283.565346) (xy 140.583158 -283.87167) (xy 139.982194 -283.87167) (xy 139.982194 -283.64688)
				(xy 139.312396 -282.977082) (xy 139.093194 -282.977082) (xy 138.373612 -283.696664) (xy 138.373612 -283.86024)
				(xy 138.772392 -284.259274) (xy 138.772392 -284.789626) (xy 139.459716 -285.47695) (xy 139.906756 -285.92399)
				(xy 139.906756 -285.934912) (xy 138.945874 -286.895794) (xy 138.883644 -286.958024) (xy 138.286236 -286.958024)
				(xy 138.266678 -286.977582) (xy 138.266678 -288.07283) (xy 138.775186 -288.581338) (xy 138.77544 -291.495988)
				(xy 110.3122 -291.496496) (xy 107.578906 -291.496496) (xy 102.967282 -291.496496)
			)
		)
	)
	(zone
		(layer "In11.Cu")
		(hatch none 0.5)
		(connect_pads
			(clearance 0)
		)
		(min_thickness 0.25)
		(keepout
			(tracks allowed)
			(vias allowed)
			(pads allowed)
			(copperpour allowed)
			(footprints allowed)
		)
		(placement
			(enabled no)
			(sheetname "")
		)
		(fill
			(thermal_gap 0.5)
			(thermal_bridge_width 0.5)
			(island_removal_mode 0)
		)
		(polygon
			(pts
				(xy 202.696318 -237.04296) (xy 203.255118 -237.04296) (xy 203.255118 -237.31855) (xy 203.255118 -237.70717)
				(xy 202.637898 -237.70717) (xy 202.637898 -237.04296)
			)
		)
	)
	(zone
		(layer "In11.Cu")
		(hatch none 0.5)
		(connect_pads
			(clearance 0)
		)
		(min_thickness 0.25)
		(keepout
			(tracks not_allowed)
			(vias allowed)
			(pads allowed)
			(copperpour not_allowed)
			(footprints allowed)
		)
		(placement
			(enabled no)
			(sheetname "")
		)
		(fill
			(thermal_gap 0.5)
			(thermal_bridge_width 0.5)
			(island_removal_mode 0)
		)
		(polygon
			(pts
				(arc
					(start 328.142092 -428.960788)
					(mid 328.16441 -429.01467)
					(end 328.218292 -429.036988)
				)
				(arc
					(start 329.158092 -429.036988)
					(mid 329.211974 -429.01467)
					(end 329.234292 -428.960788)
				)
				(arc
					(start 329.234292 -426.419264)
					(mid 329.211974 -426.365382)
					(end 329.158092 -426.343064)
				)
				(arc
					(start 328.218292 -426.343064)
					(mid 328.16441 -426.365382)
					(end 328.142092 -426.419264)
				)
			)
		)
	)
	(zone
		(layer "In11.Cu")
		(hatch none 0.5)
		(connect_pads
			(clearance 0)
		)
		(min_thickness 0.25)
		(keepout
			(tracks allowed)
			(vias allowed)
			(pads allowed)
			(copperpour allowed)
			(footprints allowed)
		)
		(placement
			(enabled no)
			(sheetname "")
		)
		(fill
			(thermal_gap 0.5)
			(thermal_bridge_width 0.5)
			(island_removal_mode 0)
		)
		(polygon
			(pts
				(xy 46.646084 -202.696826) (xy 46.646084 -202.14717) (xy 47.276004 -202.14717) (xy 47.276004 -202.696826)
			)
		)
	)
	(zone
		(layer "In11.Cu")
		(hatch none 0.5)
		(connect_pads
			(clearance 0)
		)
		(min_thickness 0.25)
		(keepout
			(tracks allowed)
			(vias allowed)
			(pads allowed)
			(copperpour allowed)
			(footprints allowed)
		)
		(placement
			(enabled no)
			(sheetname "")
		)
		(fill
			(thermal_gap 0.5)
			(thermal_bridge_width 0.5)
			(island_removal_mode 0)
		)
		(polygon
			(pts
				(xy 176.621186 -262.818626) (xy 176.621186 -262.543036) (xy 177.179986 -262.543036) (xy 177.179986 -262.818626)
			)
		)
	)
	(zone
		(layer "In11.Cu")
		(hatch none 0.5)
		(connect_pads
			(clearance 0)
		)
		(min_thickness 0.25)
		(keepout
			(tracks allowed)
			(vias allowed)
			(pads allowed)
			(copperpour allowed)
			(footprints allowed)
		)
		(placement
			(enabled no)
			(sheetname "")
		)
		(fill
			(thermal_gap 0.5)
			(thermal_bridge_width 0.5)
			(island_removal_mode 0)
		)
		(polygon
			(pts
				(xy 405.373586 -225.418396) (xy 405.373586 -225.142806) (xy 405.932386 -225.142806) (xy 405.932386 -225.418396)
			)
		)
	)
	(zone
		(layer "In11.Cu")
		(hatch none 0.5)
		(connect_pads
			(clearance 0)
		)
		(min_thickness 0.25)
		(keepout
			(tracks allowed)
			(vias allowed)
			(pads allowed)
			(copperpour allowed)
			(footprints allowed)
		)
		(placement
			(enabled no)
			(sheetname "")
		)
		(fill
			(thermal_gap 0.5)
			(thermal_bridge_width 0.5)
			(island_removal_mode 0)
		)
		(polygon
			(pts
				(xy 410.02331 -223.614742) (xy 410.02331 -223.890332) (xy 409.46451 -223.890332) (xy 409.46451 -223.614742)
			)
		)
	)
	(zone
		(layer "In11.Cu")
		(hatch none 0.5)
		(connect_pads
			(clearance 0)
		)
		(min_thickness 0.25)
		(keepout
			(tracks allowed)
			(vias allowed)
			(pads allowed)
			(copperpour allowed)
			(footprints allowed)
		)
		(placement
			(enabled no)
			(sheetname "")
		)
		(fill
			(thermal_gap 0.5)
			(thermal_bridge_width 0.5)
			(island_removal_mode 0)
		)
		(polygon
			(pts
				(xy 20.624292 -274.100544) (xy 20.624292 -273.550126) (xy 21.183092 -273.550126) (xy 21.183092 -274.100544)
			)
		)
	)
	(zone
		(layer "In11.Cu")
		(hatch none 0.5)
		(connect_pads
			(clearance 0)
		)
		(min_thickness 0.25)
		(keepout
			(tracks allowed)
			(vias allowed)
			(pads allowed)
			(copperpour allowed)
			(footprints allowed)
		)
		(placement
			(enabled no)
			(sheetname "")
		)
		(fill
			(thermal_gap 0.5)
			(thermal_bridge_width 0.5)
			(island_removal_mode 0)
		)
		(polygon
			(pts
				(xy 173.070774 -266.114784) (xy 173.070774 -266.390374) (xy 172.511974 -266.390374) (xy 172.511974 -266.114784)
			)
		)
	)
	(zone
		(layer "In11.Cu")
		(hatch none 0.5)
		(connect_pads
			(clearance 0)
		)
		(min_thickness 0.25)
		(keepout
			(tracks not_allowed)
			(vias allowed)
			(pads allowed)
			(copperpour not_allowed)
			(footprints allowed)
		)
		(placement
			(enabled no)
			(sheetname "")
		)
		(fill
			(thermal_gap 0.5)
			(thermal_bridge_width 0.5)
			(island_removal_mode 0)
		)
		(polygon
			(pts
				(arc
					(start 316.142116 -428.960788)
					(mid 316.164434 -429.01467)
					(end 316.218316 -429.036988)
				)
				(arc
					(start 317.158116 -429.036988)
					(mid 317.211998 -429.01467)
					(end 317.234316 -428.960788)
				)
				(arc
					(start 317.234316 -426.419264)
					(mid 317.211998 -426.365382)
					(end 317.158116 -426.343064)
				)
				(arc
					(start 316.218316 -426.343064)
					(mid 316.164434 -426.365382)
					(end 316.142116 -426.419264)
				)
			)
		)
	)
	(zone
		(layer "In11.Cu")
		(hatch none 0.5)
		(connect_pads
			(clearance 0)
		)
		(min_thickness 0.25)
		(keepout
			(tracks allowed)
			(vias allowed)
			(pads allowed)
			(copperpour allowed)
			(footprints allowed)
		)
		(placement
			(enabled no)
			(sheetname "")
		)
		(fill
			(thermal_gap 0.5)
			(thermal_bridge_width 0.5)
			(island_removal_mode 0)
		)
		(polygon
			(pts
				(xy 46.646084 -275.796756) (xy 46.646084 -275.2471) (xy 47.276004 -275.2471) (xy 47.276004 -275.796756)
			)
		)
	)
	(zone
		(layer "In11.Cu")
		(hatch none 0.5)
		(connect_pads
			(clearance 0)
		)
		(min_thickness 0.25)
		(keepout
			(tracks allowed)
			(vias allowed)
			(pads allowed)
			(copperpour allowed)
			(footprints allowed)
		)
		(placement
			(enabled no)
			(sheetname "")
		)
		(fill
			(thermal_gap 0.5)
			(thermal_bridge_width 0.5)
			(island_removal_mode 0)
		)
		(polygon
			(pts
				(xy 421.010842 -204.064616) (xy 421.010842 -204.340206) (xy 420.452042 -204.340206) (xy 420.452042 -204.064616)
			)
		)
	)
	(zone
		(layer "In11.Cu")
		(hatch none 0.5)
		(connect_pads
			(clearance 0)
		)
		(min_thickness 0.25)
		(keepout
			(tracks allowed)
			(vias allowed)
			(pads allowed)
			(copperpour allowed)
			(footprints allowed)
		)
		(placement
			(enabled no)
			(sheetname "")
		)
		(fill
			(thermal_gap 0.5)
			(thermal_bridge_width 0.5)
			(island_removal_mode 0)
		)
		(polygon
			(pts
				(xy 298.71162 -297.046904) (xy 298.71162 -296.497248) (xy 299.34154 -296.497248) (xy 299.34154 -297.046904)
			)
		)
	)
	(zone
		(layer "In11.Cu")
		(hatch none 0.5)
		(connect_pads
			(clearance 0)
		)
		(min_thickness 0.25)
		(keepout
			(tracks allowed)
			(vias allowed)
			(pads allowed)
			(copperpour allowed)
			(footprints allowed)
		)
		(placement
			(enabled no)
			(sheetname "")
		)
		(fill
			(thermal_gap 0.5)
			(thermal_bridge_width 0.5)
			(island_removal_mode 0)
		)
		(polygon
			(pts
				(xy 451.186042 -304.364644) (xy 451.186042 -304.640234) (xy 450.627242 -304.640234) (xy 450.627242 -304.364644)
			)
		)
	)
	(zone
		(layer "In11.Cu")
		(hatch none 0.5)
		(connect_pads
			(clearance 0)
		)
		(min_thickness 0.25)
		(keepout
			(tracks allowed)
			(vias allowed)
			(pads allowed)
			(copperpour allowed)
			(footprints allowed)
		)
		(placement
			(enabled no)
			(sheetname "")
		)
		(fill
			(thermal_gap 0.5)
			(thermal_bridge_width 0.5)
			(island_removal_mode 0)
		)
		(polygon
			(pts
				(xy 298.71162 -304.696876) (xy 298.71162 -304.14722) (xy 299.34154 -304.14722) (xy 299.34154 -304.696876)
			)
		)
	)
	(zone
		(layer "In11.Cu")
		(hatch none 0.5)
		(connect_pads
			(clearance 0)
		)
		(min_thickness 0.25)
		(keepout
			(tracks allowed)
			(vias allowed)
			(pads allowed)
			(copperpour allowed)
			(footprints allowed)
		)
		(placement
			(enabled no)
			(sheetname "")
		)
		(fill
			(thermal_gap 0.5)
			(thermal_bridge_width 0.5)
			(island_removal_mode 0)
		)
		(polygon
			(pts
				(xy 424.561254 -283.218382) (xy 424.561254 -282.942792) (xy 425.120054 -282.942792) (xy 425.120054 -283.218382)
			)
		)
	)
	(zone
		(layer "In11.Cu")
		(hatch none 0.5)
		(connect_pads
			(clearance 0)
		)
		(min_thickness 0.25)
		(keepout
			(tracks allowed)
			(vias allowed)
			(pads allowed)
			(copperpour allowed)
			(footprints allowed)
		)
		(placement
			(enabled no)
			(sheetname "")
		)
		(fill
			(thermal_gap 0.5)
			(thermal_bridge_width 0.5)
			(island_removal_mode 0)
		)
		(polygon
			(pts
				(xy 439.648854 -279.818592) (xy 439.648854 -279.543002) (xy 440.207654 -279.543002) (xy 440.207654 -279.818592)
			)
		)
	)
	(zone
		(layer "In11.Cu")
		(hatch none 0.5)
		(connect_pads
			(clearance 0)
		)
		(min_thickness 0.25)
		(keepout
			(tracks allowed)
			(vias allowed)
			(pads allowed)
			(copperpour allowed)
			(footprints allowed)
		)
		(placement
			(enabled no)
			(sheetname "")
		)
		(fill
			(thermal_gap 0.5)
			(thermal_bridge_width 0.5)
			(island_removal_mode 0)
		)
		(polygon
			(pts
				(xy 46.646084 -301.296832) (xy 46.646084 -300.747176) (xy 47.276004 -300.747176) (xy 47.276004 -301.296832)
			)
		)
	)
	(zone
		(layer "In11.Cu")
		(hatch none 0.5)
		(connect_pads
			(clearance 0)
		)
		(min_thickness 0.25)
		(keepout
			(tracks allowed)
			(vias allowed)
			(pads allowed)
			(copperpour allowed)
			(footprints allowed)
		)
		(placement
			(enabled no)
			(sheetname "")
		)
		(fill
			(thermal_gap 0.5)
			(thermal_bridge_width 0.5)
			(island_removal_mode 0)
		)
		(polygon
			(pts
				(xy 203.245974 -286.514794) (xy 203.245974 -286.790384) (xy 202.687174 -286.790384) (xy 202.687174 -286.514794)
			)
		)
	)
	(zone
		(layer "In11.Cu")
		(hatch none 0.5)
		(connect_pads
			(clearance 0)
		)
		(min_thickness 0.25)
		(keepout
			(tracks allowed)
			(vias allowed)
			(pads allowed)
			(copperpour allowed)
			(footprints allowed)
		)
		(placement
			(enabled no)
			(sheetname "")
		)
		(fill
			(thermal_gap 0.5)
			(thermal_bridge_width 0.5)
			(island_removal_mode 0)
		)
		(polygon
			(pts
				(xy 46.646084 -263.046972) (xy 46.646084 -262.497316) (xy 47.276004 -262.497316) (xy 47.276004 -263.046972)
			)
		)
	)
	(zone
		(layer "In11.Cu")
		(hatch none 0.5)
		(connect_pads
			(clearance 0)
		)
		(min_thickness 0.25)
		(keepout
			(tracks allowed)
			(vias allowed)
			(pads allowed)
			(copperpour allowed)
			(footprints allowed)
		)
		(placement
			(enabled no)
			(sheetname "")
		)
		(fill
			(thermal_gap 0.5)
			(thermal_bridge_width 0.5)
			(island_removal_mode 0)
		)
		(polygon
			(pts
				(xy 46.646084 -303.846738) (xy 46.646084 -303.297082) (xy 47.276004 -303.297082) (xy 47.276004 -303.846738)
			)
		)
	)
	(zone
		(layer "In11.Cu")
		(hatch none 0.5)
		(connect_pads
			(clearance 0)
		)
		(min_thickness 0.25)
		(keepout
			(tracks allowed)
			(vias allowed)
			(pads allowed)
			(copperpour allowed)
			(footprints allowed)
		)
		(placement
			(enabled no)
			(sheetname "")
		)
		(fill
			(thermal_gap 0.5)
			(thermal_bridge_width 0.5)
			(island_removal_mode 0)
		)
		(polygon
			(pts
				(xy 203.245974 -220.214698) (xy 203.245974 -220.490288) (xy 202.687174 -220.490288) (xy 202.687174 -220.214698)
			)
		)
	)
	(zone
		(layer "In11.Cu")
		(hatch none 0.5)
		(connect_pads
			(clearance 0)
		)
		(min_thickness 0.25)
		(keepout
			(tracks allowed)
			(vias allowed)
			(pads allowed)
			(copperpour allowed)
			(footprints allowed)
		)
		(placement
			(enabled no)
			(sheetname "")
		)
		(fill
			(thermal_gap 0.5)
			(thermal_bridge_width 0.5)
			(island_removal_mode 0)
		)
		(polygon
			(pts
				(xy 420.461186 -232.218484) (xy 420.461186 -231.942894) (xy 421.019986 -231.942894) (xy 421.019986 -232.218484)
			)
		)
	)
	(zone
		(layer "In11.Cu")
		(hatch none 0.5)
		(connect_pads
			(clearance 0)
		)
		(min_thickness 0.25)
		(keepout
			(tracks allowed)
			(vias allowed)
			(pads allowed)
			(copperpour allowed)
			(footprints allowed)
		)
		(placement
			(enabled no)
			(sheetname "")
		)
		(fill
			(thermal_gap 0.5)
			(thermal_bridge_width 0.5)
			(island_removal_mode 0)
		)
		(polygon
			(pts
				(xy 294.586152 -221.396814) (xy 294.586152 -220.847158) (xy 295.216072 -220.847158) (xy 295.216072 -221.396814)
			)
		)
	)
	(zone
		(layer "In11.Cu")
		(hatch none 0.5)
		(connect_pads
			(clearance 0)
		)
		(min_thickness 0.25)
		(keepout
			(tracks allowed)
			(vias allowed)
			(pads allowed)
			(copperpour allowed)
			(footprints allowed)
		)
		(placement
			(enabled no)
			(sheetname "")
		)
		(fill
			(thermal_gap 0.5)
			(thermal_bridge_width 0.5)
			(island_removal_mode 0)
		)
		(polygon
			(pts
				(xy 424.561254 -249.21845) (xy 424.561254 -248.94286) (xy 425.120054 -248.94286) (xy 425.120054 -249.21845)
			)
		)
	)
	(zone
		(layer "In11.Cu")
		(hatch none 0.5)
		(connect_pads
			(clearance 0)
		)
		(min_thickness 0.25)
		(keepout
			(tracks allowed)
			(vias allowed)
			(pads allowed)
			(copperpour allowed)
			(footprints allowed)
		)
		(placement
			(enabled no)
			(sheetname "")
		)
		(fill
			(thermal_gap 0.5)
			(thermal_bridge_width 0.5)
			(island_removal_mode 0)
		)
		(polygon
			(pts
				(xy 176.621186 -231.3686) (xy 176.621186 -231.09301) (xy 177.179986 -231.09301) (xy 177.179986 -231.3686)
			)
		)
	)
	(zone
		(layer "In11.Cu")
		(hatch none 0.5)
		(connect_pads
			(clearance 0)
		)
		(min_thickness 0.25)
		(keepout
			(tracks allowed)
			(vias allowed)
			(pads allowed)
			(copperpour allowed)
			(footprints allowed)
		)
		(placement
			(enabled no)
			(sheetname "")
		)
		(fill
			(thermal_gap 0.5)
			(thermal_bridge_width 0.5)
			(island_removal_mode 0)
		)
		(polygon
			(pts
				(xy 20.624292 -304.700686) (xy 20.624292 -304.150268) (xy 21.183092 -304.150268) (xy 21.183092 -304.700686)
			)
		)
	)
	(zone
		(layer "In11.Cu")
		(hatch none 0.5)
		(connect_pads
			(clearance 0)
		)
		(min_thickness 0.25)
		(keepout
			(tracks allowed)
			(vias allowed)
			(pads allowed)
			(copperpour allowed)
			(footprints allowed)
		)
		(placement
			(enabled no)
			(sheetname "")
		)
		(fill
			(thermal_gap 0.5)
			(thermal_bridge_width 0.5)
			(island_removal_mode 0)
		)
		(polygon
			(pts
				(xy 177.170842 -228.714808) (xy 177.170842 -228.990398) (xy 176.612042 -228.990398) (xy 176.612042 -228.714808)
			)
		)
	)
	(zone
		(layer "In11.Cu")
		(hatch none 0.5)
		(connect_pads
			(clearance 0)
		)
		(min_thickness 0.25)
		(keepout
			(tracks allowed)
			(vias allowed)
			(pads allowed)
			(copperpour allowed)
			(footprints allowed)
		)
		(placement
			(enabled no)
			(sheetname "")
		)
		(fill
			(thermal_gap 0.5)
			(thermal_bridge_width 0.5)
			(island_removal_mode 0)
		)
		(polygon
			(pts
				(xy 424.561254 -277.268432) (xy 424.561254 -276.992842) (xy 425.120054 -276.992842) (xy 425.120054 -277.268432)
			)
		)
	)
	(zone
		(layer "In11.Cu")
		(hatch none 0.5)
		(connect_pads
			(clearance 0)
		)
		(min_thickness 0.25)
		(keepout
			(tracks allowed)
			(vias allowed)
			(pads allowed)
			(copperpour allowed)
			(footprints allowed)
		)
		(placement
			(enabled no)
			(sheetname "")
		)
		(fill
			(thermal_gap 0.5)
			(thermal_bridge_width 0.5)
			(island_removal_mode 0)
		)
		(polygon
			(pts
				(xy 420.461186 -228.81844) (xy 420.461186 -228.54285) (xy 421.019986 -228.54285) (xy 421.019986 -228.81844)
			)
		)
	)
	(zone
		(layer "In11.Cu")
		(hatch none 0.5)
		(connect_pads
			(clearance 0)
		)
		(min_thickness 0.25)
		(keepout
			(tracks allowed)
			(vias allowed)
			(pads allowed)
			(copperpour allowed)
			(footprints allowed)
		)
		(placement
			(enabled no)
			(sheetname "")
		)
		(fill
			(thermal_gap 0.5)
			(thermal_bridge_width 0.5)
			(island_removal_mode 0)
		)
		(polygon
			(pts
				(xy 298.68622 -239.246918) (xy 298.68622 -238.697262) (xy 299.31614 -238.697262) (xy 299.31614 -239.246918)
			)
		)
	)
	(zone
		(layer "In11.Cu")
		(hatch none 0.5)
		(connect_pads
			(clearance 0)
		)
		(min_thickness 0.25)
		(keepout
			(tracks allowed)
			(vias allowed)
			(pads allowed)
			(copperpour allowed)
			(footprints allowed)
		)
		(placement
			(enabled no)
			(sheetname "")
		)
		(fill
			(thermal_gap 0.5)
			(thermal_bridge_width 0.5)
			(island_removal_mode 0)
		)
		(polygon
			(pts
				(xy 172.521118 -228.81844) (xy 172.521118 -228.54285) (xy 173.079918 -228.54285) (xy 173.079918 -228.81844)
			)
		)
	)
	(zone
		(layer "In11.Cu")
		(hatch none 0.5)
		(connect_pads
			(clearance 0)
		)
		(min_thickness 0.25)
		(keepout
			(tracks allowed)
			(vias allowed)
			(pads allowed)
			(copperpour allowed)
			(footprints allowed)
		)
		(placement
			(enabled no)
			(sheetname "")
		)
		(fill
			(thermal_gap 0.5)
			(thermal_bridge_width 0.5)
			(island_removal_mode 0)
		)
		(polygon
			(pts
				(xy 421.010842 -305.214782) (xy 421.010842 -305.490372) (xy 420.452042 -305.490372) (xy 420.452042 -305.214782)
			)
		)
	)
	(zone
		(layer "In11.Cu")
		(hatch none 0.5)
		(connect_pads
			(clearance 0)
		)
		(min_thickness 0.25)
		(keepout
			(tracks allowed)
			(vias allowed)
			(pads allowed)
			(copperpour allowed)
			(footprints allowed)
		)
		(placement
			(enabled no)
			(sheetname "")
		)
		(fill
			(thermal_gap 0.5)
			(thermal_bridge_width 0.5)
			(island_removal_mode 0)
		)
		(polygon
			(pts
				(xy 268.558518 -267.292328) (xy 268.558518 -266.75207) (xy 269.126462 -266.75207) (xy 269.426944 -266.75207)
				(xy 269.531084 -266.85621) (xy 269.531084 -267.12164) (xy 269.360396 -267.292328) (xy 269.117318 -267.292328)
			)
		)
	)
	(zone
		(layer "In11.Cu")
		(hatch none 0.5)
		(connect_pads
			(clearance 0)
		)
		(min_thickness 0.25)
		(keepout
			(tracks allowed)
			(vias allowed)
			(pads allowed)
			(copperpour allowed)
			(footprints allowed)
		)
		(placement
			(enabled no)
			(sheetname "")
		)
		(fill
			(thermal_gap 0.5)
			(thermal_bridge_width 0.5)
			(island_removal_mode 0)
		)
		(polygon
			(pts
				(xy 172.521118 -220.318584) (xy 172.521118 -220.042994) (xy 173.079918 -220.042994) (xy 173.079918 -220.318584)
			)
		)
	)
	(zone
		(layer "In11.Cu")
		(hatch none 0.5)
		(connect_pads
			(clearance 0)
		)
		(min_thickness 0.25)
		(keepout
			(tracks allowed)
			(vias allowed)
			(pads allowed)
			(copperpour allowed)
			(footprints allowed)
		)
		(placement
			(enabled no)
			(sheetname "")
		)
		(fill
			(thermal_gap 0.5)
			(thermal_bridge_width 0.5)
			(island_removal_mode 0)
		)
		(polygon
			(pts
				(xy 420.461186 -273.868388) (xy 420.461186 -273.592798) (xy 421.019986 -273.592798) (xy 421.019986 -273.868388)
			)
		)
	)
	(zone
		(layer "In11.Cu")
		(hatch none 0.5)
		(connect_pads
			(clearance 0)
		)
		(min_thickness 0.25)
		(keepout
			(tracks allowed)
			(vias allowed)
			(pads allowed)
			(copperpour allowed)
			(footprints allowed)
		)
		(placement
			(enabled no)
			(sheetname "")
		)
		(fill
			(thermal_gap 0.5)
			(thermal_bridge_width 0.5)
			(island_removal_mode 0)
		)
		(polygon
			(pts
				(xy 172.521118 -203.318618) (xy 172.521118 -203.043028) (xy 173.079918 -203.043028) (xy 173.079918 -203.318618)
			)
		)
	)
	(zone
		(layer "In11.Cu")
		(hatch none 0.5)
		(connect_pads
			(clearance 0)
		)
		(min_thickness 0.25)
		(keepout
			(tracks allowed)
			(vias allowed)
			(pads allowed)
			(copperpour allowed)
			(footprints allowed)
		)
		(placement
			(enabled no)
			(sheetname "")
		)
		(fill
			(thermal_gap 0.5)
			(thermal_bridge_width 0.5)
			(island_removal_mode 0)
		)
		(polygon
			(pts
				(xy 421.010842 -272.914618) (xy 421.010842 -273.190208) (xy 420.452042 -273.190208) (xy 420.452042 -272.914618)
			)
		)
	)
	(zone
		(layer "In11.Cu")
		(hatch none 0.5)
		(connect_pads
			(clearance 0)
		)
		(min_thickness 0.25)
		(keepout
			(tracks allowed)
			(vias allowed)
			(pads allowed)
			(copperpour allowed)
			(footprints allowed)
		)
		(placement
			(enabled no)
			(sheetname "")
		)
		(fill
			(thermal_gap 0.5)
			(thermal_bridge_width 0.5)
			(island_removal_mode 0)
		)
		(polygon
			(pts
				(xy 268.51102 -218.846908) (xy 268.51102 -218.297252) (xy 269.14094 -218.297252) (xy 269.14094 -218.846908)
			)
		)
	)
	(zone
		(layer "In11.Cu")
		(hatch none 0.5)
		(connect_pads
			(clearance 0)
		)
		(min_thickness 0.25)
		(keepout
			(tracks allowed)
			(vias allowed)
			(pads allowed)
			(copperpour allowed)
			(footprints allowed)
		)
		(placement
			(enabled no)
			(sheetname "")
		)
		(fill
			(thermal_gap 0.5)
			(thermal_bridge_width 0.5)
			(island_removal_mode 0)
		)
		(polygon
			(pts
				(xy 298.71162 -280.046938) (xy 298.71162 -279.497282) (xy 299.34154 -279.497282) (xy 299.34154 -280.046938)
			)
		)
	)
	(zone
		(layer "In11.Cu")
		(hatch none 0.5)
		(connect_pads
			(clearance 0)
		)
		(min_thickness 0.25)
		(keepout
			(tracks allowed)
			(vias allowed)
			(pads allowed)
			(copperpour allowed)
			(footprints allowed)
		)
		(placement
			(enabled no)
			(sheetname "")
		)
		(fill
			(thermal_gap 0.5)
			(thermal_bridge_width 0.5)
			(island_removal_mode 0)
		)
		(polygon
			(pts
				(xy 203.245974 -241.464846) (xy 203.245974 -241.740436) (xy 202.687174 -241.740436) (xy 202.687174 -241.464846)
			)
		)
	)
	(zone
		(layer "In11.Cu")
		(hatch none 0.5)
		(connect_pads
			(clearance 0)
		)
		(min_thickness 0.25)
		(keepout
			(tracks allowed)
			(vias allowed)
			(pads allowed)
			(copperpour allowed)
			(footprints allowed)
		)
		(placement
			(enabled no)
			(sheetname "")
		)
		(fill
			(thermal_gap 0.5)
			(thermal_bridge_width 0.5)
			(island_removal_mode 0)
		)
		(polygon
			(pts
				(xy 451.186042 -246.564658) (xy 451.186042 -246.840248) (xy 450.627242 -246.840248) (xy 450.627242 -246.564658)
			)
		)
	)
	(zone
		(layer "In11.Cu")
		(hatch none 0.5)
		(connect_pads
			(clearance 0)
		)
		(min_thickness 0.25)
		(keepout
			(tracks allowed)
			(vias allowed)
			(pads allowed)
			(copperpour allowed)
			(footprints allowed)
		)
		(placement
			(enabled no)
			(sheetname "")
		)
		(fill
			(thermal_gap 0.5)
			(thermal_bridge_width 0.5)
			(island_removal_mode 0)
		)
		(polygon
			(pts
				(xy 50.746152 -212.896958) (xy 50.746152 -212.347302) (xy 51.376072 -212.347302) (xy 51.376072 -212.896958)
			)
		)
	)
	(zone
		(layer "In11.Cu")
		(hatch none 0.5)
		(connect_pads
			(clearance 0)
		)
		(min_thickness 0.25)
		(keepout
			(tracks allowed)
			(vias allowed)
			(pads allowed)
			(copperpour allowed)
			(footprints allowed)
		)
		(placement
			(enabled no)
			(sheetname "")
		)
		(fill
			(thermal_gap 0.5)
			(thermal_bridge_width 0.5)
			(island_removal_mode 0)
		)
		(polygon
			(pts
				(xy 420.461186 -218.618562) (xy 420.461186 -218.342972) (xy 421.019986 -218.342972) (xy 421.019986 -218.618562)
			)
		)
	)
	(zone
		(layer "In11.Cu")
		(hatch none 0.5)
		(connect_pads
			(clearance 0)
		)
		(min_thickness 0.25)
		(keepout
			(tracks allowed)
			(vias allowed)
			(pads allowed)
			(copperpour allowed)
			(footprints allowed)
		)
		(placement
			(enabled no)
			(sheetname "")
		)
		(fill
			(thermal_gap 0.5)
			(thermal_bridge_width 0.5)
			(island_removal_mode 0)
		)
		(polygon
			(pts
				(xy 50.771552 -280.046938) (xy 50.771552 -279.497282) (xy 51.401472 -279.497282) (xy 51.401472 -280.046938)
			)
		)
	)
	(zone
		(layer "In11.Cu")
		(hatch none 0.5)
		(connect_pads
			(clearance 0)
		)
		(min_thickness 0.25)
		(keepout
			(tracks allowed)
			(vias allowed)
			(pads allowed)
			(copperpour allowed)
			(footprints allowed)
		)
		(placement
			(enabled no)
			(sheetname "")
		)
		(fill
			(thermal_gap 0.5)
			(thermal_bridge_width 0.5)
			(island_removal_mode 0)
		)
		(polygon
			(pts
				(xy 298.68622 -237.546896) (xy 298.68622 -236.99724) (xy 299.31614 -236.99724) (xy 299.31614 -237.546896)
			)
		)
	)
	(zone
		(layer "In11.Cu")
		(hatch none 0.5)
		(connect_pads
			(clearance 0)
		)
		(min_thickness 0.25)
		(keepout
			(tracks allowed)
			(vias allowed)
			(pads allowed)
			(copperpour allowed)
			(footprints allowed)
		)
		(placement
			(enabled no)
			(sheetname "")
		)
		(fill
			(thermal_gap 0.5)
			(thermal_bridge_width 0.5)
			(island_removal_mode 0)
		)
		(polygon
			(pts
				(xy 451.186042 -251.664724) (xy 451.186042 -251.940314) (xy 450.627242 -251.940314) (xy 450.627242 -251.664724)
			)
		)
	)
	(zone
		(layer "In11.Cu")
		(hatch none 0.5)
		(connect_pads
			(clearance 0)
		)
		(min_thickness 0.25)
		(keepout
			(tracks allowed)
			(vias allowed)
			(pads allowed)
			(copperpour allowed)
			(footprints allowed)
		)
		(placement
			(enabled no)
			(sheetname "")
		)
		(fill
			(thermal_gap 0.5)
			(thermal_bridge_width 0.5)
			(island_removal_mode 0)
		)
		(polygon
			(pts
				(xy 451.186042 -286.514794) (xy 451.186042 -286.790384) (xy 450.627242 -286.790384) (xy 450.627242 -286.514794)
			)
		)
	)
	(zone
		(layer "In11.Cu")
		(hatch none 0.5)
		(connect_pads
			(clearance 0)
		)
		(min_thickness 0.25)
		(keepout
			(tracks allowed)
			(vias allowed)
			(pads allowed)
			(copperpour allowed)
			(footprints allowed)
		)
		(placement
			(enabled no)
			(sheetname "")
		)
		(fill
			(thermal_gap 0.5)
			(thermal_bridge_width 0.5)
			(island_removal_mode 0)
		)
		(polygon
			(pts
				(xy 20.570952 -214.596726) (xy 20.570952 -214.04707) (xy 21.200872 -214.04707) (xy 21.200872 -214.596726)
			)
		)
	)
	(zone
		(layer "In11.Cu")
		(hatch none 0.5)
		(connect_pads
			(clearance 0)
		)
		(min_thickness 0.25)
		(keepout
			(tracks allowed)
			(vias allowed)
			(pads allowed)
			(copperpour allowed)
			(footprints allowed)
		)
		(placement
			(enabled no)
			(sheetname "")
		)
		(fill
			(thermal_gap 0.5)
			(thermal_bridge_width 0.5)
			(island_removal_mode 0)
		)
		(polygon
			(pts
				(xy 353.63658 -297.635168) (xy 353.63658 -292.499288) (xy 356.23246 -292.499288) (xy 356.23246 -297.635168)
			)
		)
	)
	(zone
		(layer "In11.Cu")
		(hatch none 0.5)
		(connect_pads
			(clearance 0)
		)
		(min_thickness 0.25)
		(keepout
			(tracks allowed)
			(vias allowed)
			(pads allowed)
			(copperpour allowed)
			(footprints allowed)
		)
		(placement
			(enabled no)
			(sheetname "")
		)
		(fill
			(thermal_gap 0.5)
			(thermal_bridge_width 0.5)
			(island_removal_mode 0)
		)
		(polygon
			(pts
				(xy 161.533586 -226.268534) (xy 161.533586 -225.992944) (xy 162.092386 -225.992944) (xy 162.092386 -226.268534)
			)
		)
	)
	(zone
		(layer "In11.Cu")
		(hatch none 0.5)
		(connect_pads
			(clearance 0)
		)
		(min_thickness 0.25)
		(keepout
			(tracks allowed)
			(vias allowed)
			(pads allowed)
			(copperpour allowed)
			(footprints allowed)
		)
		(placement
			(enabled no)
			(sheetname "")
		)
		(fill
			(thermal_gap 0.5)
			(thermal_bridge_width 0.5)
			(island_removal_mode 0)
		)
		(polygon
			(pts
				(xy 172.521118 -199.068436) (xy 172.521118 -198.792846) (xy 173.079918 -198.792846) (xy 173.079918 -199.068436)
			)
		)
	)
	(zone
		(layer "In11.Cu")
		(hatch none 0.5)
		(connect_pads
			(clearance 0)
		)
		(min_thickness 0.25)
		(keepout
			(tracks allowed)
			(vias allowed)
			(pads allowed)
			(copperpour allowed)
			(footprints allowed)
		)
		(placement
			(enabled no)
			(sheetname "")
		)
		(fill
			(thermal_gap 0.5)
			(thermal_bridge_width 0.5)
			(island_removal_mode 0)
		)
		(polygon
			(pts
				(xy 451.186042 -291.614606) (xy 451.186042 -291.890196) (xy 451.186042 -291.929058) (xy 450.676264 -291.929058)
				(xy 450.676264 -292.18636) (xy 450.144642 -292.18636) (xy 450.144642 -291.27323) (xy 450.723254 -291.27323)
				(xy 450.723254 -291.614606)
			)
		)
	)
	(zone
		(layer "In11.Cu")
		(hatch none 0.5)
		(connect_pads
			(clearance 0)
		)
		(min_thickness 0.25)
		(keepout
			(tracks allowed)
			(vias allowed)
			(pads allowed)
			(copperpour allowed)
			(footprints allowed)
		)
		(placement
			(enabled no)
			(sheetname "")
		)
		(fill
			(thermal_gap 0.5)
			(thermal_bridge_width 0.5)
			(island_removal_mode 0)
		)
		(polygon
			(pts
				(xy 268.558518 -222.24238) (xy 268.558518 -221.702122) (xy 269.126462 -221.702122) (xy 269.426944 -221.702122)
				(xy 269.531084 -221.806262) (xy 269.531084 -222.071692) (xy 269.360396 -222.24238) (xy 269.117318 -222.24238)
			)
		)
	)
	(zone
		(layer "In11.Cu")
		(hatch none 0.5)
		(connect_pads
			(clearance 0)
		)
		(min_thickness 0.25)
		(keepout
			(tracks allowed)
			(vias allowed)
			(pads allowed)
			(copperpour allowed)
			(footprints allowed)
		)
		(placement
			(enabled no)
			(sheetname "")
		)
		(fill
			(thermal_gap 0.5)
			(thermal_bridge_width 0.5)
			(island_removal_mode 0)
		)
		(polygon
			(pts
				(xy 176.621186 -239.018572) (xy 176.621186 -238.742982) (xy 177.179986 -238.742982) (xy 177.179986 -239.018572)
			)
		)
	)
	(zone
		(layer "In11.Cu")
		(hatch none 0.5)
		(connect_pads
			(clearance 0)
		)
		(min_thickness 0.25)
		(keepout
			(tracks allowed)
			(vias allowed)
			(pads allowed)
			(copperpour allowed)
			(footprints allowed)
		)
		(placement
			(enabled no)
			(sheetname "")
		)
		(fill
			(thermal_gap 0.5)
			(thermal_bridge_width 0.5)
			(island_removal_mode 0)
		)
		(polygon
			(pts
				(xy 268.56436 -309.800752) (xy 268.56436 -309.250334) (xy 269.12316 -309.250334) (xy 269.12316 -309.800752)
			)
		)
	)
	(zone
		(layer "In11.Cu")
		(hatch none 0.5)
		(connect_pads
			(clearance 0)
		)
		(min_thickness 0.25)
		(keepout
			(tracks allowed)
			(vias allowed)
			(pads allowed)
			(copperpour allowed)
			(footprints allowed)
		)
		(placement
			(enabled no)
			(sheetname "")
		)
		(fill
			(thermal_gap 0.5)
			(thermal_bridge_width 0.5)
			(island_removal_mode 0)
		)
		(polygon
			(pts
				(xy 256.914396 -246.012208) (xy 256.914396 -244.690138) (xy 257.441954 -244.690138) (xy 257.441954 -246.012208)
			)
		)
	)
	(zone
		(layer "In11.Cu")
		(hatch none 0.5)
		(connect_pads
			(clearance 0)
		)
		(min_thickness 0.25)
		(keepout
			(tracks allowed)
			(vias allowed)
			(pads allowed)
			(copperpour allowed)
			(footprints allowed)
		)
		(placement
			(enabled no)
			(sheetname "")
		)
		(fill
			(thermal_gap 0.5)
			(thermal_bridge_width 0.5)
			(island_removal_mode 0)
		)
		(polygon
			(pts
				(xy 420.461186 -309.568596) (xy 420.461186 -309.293006) (xy 421.019986 -309.293006) (xy 421.019986 -309.568596)
			)
		)
	)
	(zone
		(layer "In11.Cu")
		(hatch none 0.5)
		(connect_pads
			(clearance 0)
		)
		(min_thickness 0.25)
		(keepout
			(tracks allowed)
			(vias allowed)
			(pads allowed)
			(copperpour allowed)
			(footprints allowed)
		)
		(placement
			(enabled no)
			(sheetname "")
		)
		(fill
			(thermal_gap 0.5)
			(thermal_bridge_width 0.5)
			(island_removal_mode 0)
		)
		(polygon
			(pts
				(xy 294.586152 -271.546828) (xy 294.586152 -270.997172) (xy 295.216072 -270.997172) (xy 295.216072 -271.546828)
			)
		)
	)
	(zone
		(layer "In11.Cu")
		(hatch none 0.5)
		(connect_pads
			(clearance 0)
		)
		(min_thickness 0.25)
		(keepout
			(tracks allowed)
			(vias allowed)
			(pads allowed)
			(copperpour allowed)
			(footprints allowed)
		)
		(placement
			(enabled no)
			(sheetname "")
		)
		(fill
			(thermal_gap 0.5)
			(thermal_bridge_width 0.5)
			(island_removal_mode 0)
		)
		(polygon
			(pts
				(xy 451.186042 -264.414762) (xy 451.186042 -264.690352) (xy 450.627242 -264.690352) (xy 450.627242 -264.414762)
			)
		)
	)
	(zone
		(layer "In11.Cu")
		(hatch none 0.5)
		(connect_pads
			(clearance 0)
		)
		(min_thickness 0.25)
		(keepout
			(tracks allowed)
			(vias allowed)
			(pads allowed)
			(copperpour allowed)
			(footprints allowed)
		)
		(placement
			(enabled no)
			(sheetname "")
		)
		(fill
			(thermal_gap 0.5)
			(thermal_bridge_width 0.5)
			(island_removal_mode 0)
		)
		(polygon
			(pts
				(xy 435.548786 -283.218382) (xy 435.548786 -282.942792) (xy 436.107586 -282.942792) (xy 436.107586 -283.218382)
			)
		)
	)
	(zone
		(layer "In11.Cu")
		(hatch none 0.5)
		(connect_pads
			(clearance 0)
		)
		(min_thickness 0.25)
		(keepout
			(tracks allowed)
			(vias allowed)
			(pads allowed)
			(copperpour allowed)
			(footprints allowed)
		)
		(placement
			(enabled no)
			(sheetname "")
		)
		(fill
			(thermal_gap 0.5)
			(thermal_bridge_width 0.5)
			(island_removal_mode 0)
		)
		(polygon
			(pts
				(xy 420.461186 -268.768576) (xy 420.461186 -268.492986) (xy 421.019986 -268.492986) (xy 421.019986 -268.768576)
			)
		)
	)
	(zone
		(layer "In11.Cu")
		(hatch none 0.5)
		(connect_pads
			(clearance 0)
		)
		(min_thickness 0.25)
		(keepout
			(tracks allowed)
			(vias allowed)
			(pads allowed)
			(copperpour allowed)
			(footprints allowed)
		)
		(placement
			(enabled no)
			(sheetname "")
		)
		(fill
			(thermal_gap 0.5)
			(thermal_bridge_width 0.5)
			(island_removal_mode 0)
		)
		(polygon
			(pts
				(xy 172.521118 -206.718408) (xy 172.521118 -206.442818) (xy 173.079918 -206.442818) (xy 173.079918 -206.718408)
			)
		)
	)
	(zone
		(layer "In11.Cu")
		(hatch none 0.5)
		(connect_pads
			(clearance 0)
		)
		(min_thickness 0.25)
		(keepout
			(tracks allowed)
			(vias allowed)
			(pads allowed)
			(copperpour allowed)
			(footprints allowed)
		)
		(placement
			(enabled no)
			(sheetname "")
		)
		(fill
			(thermal_gap 0.5)
			(thermal_bridge_width 0.5)
			(island_removal_mode 0)
		)
		(polygon
			(pts
				(xy 435.548786 -212.668612) (xy 435.548786 -212.393022) (xy 436.107586 -212.393022) (xy 436.107586 -212.668612)
			)
		)
	)
	(zone
		(layer "In11.Cu")
		(hatch none 0.5)
		(connect_pads
			(clearance 0)
		)
		(min_thickness 0.25)
		(keepout
			(tracks allowed)
			(vias allowed)
			(pads allowed)
			(copperpour allowed)
			(footprints allowed)
		)
		(placement
			(enabled no)
			(sheetname "")
		)
		(fill
			(thermal_gap 0.5)
			(thermal_bridge_width 0.5)
			(island_removal_mode 0)
		)
		(polygon
			(pts
				(xy 50.746152 -209.496914) (xy 50.746152 -208.947258) (xy 51.376072 -208.947258) (xy 51.376072 -209.496914)
			)
		)
	)
	(zone
		(layer "In11.Cu")
		(hatch none 0.5)
		(connect_pads
			(clearance 0)
		)
		(min_thickness 0.25)
		(keepout
			(tracks allowed)
			(vias allowed)
			(pads allowed)
			(copperpour allowed)
			(footprints allowed)
		)
		(placement
			(enabled no)
			(sheetname "")
		)
		(fill
			(thermal_gap 0.5)
			(thermal_bridge_width 0.5)
			(island_removal_mode 0)
		)
		(polygon
			(pts
				(xy 435.548786 -261.968488) (xy 435.548786 -261.692898) (xy 436.107586 -261.692898) (xy 436.107586 -261.968488)
			)
		)
	)
	(zone
		(layer "In11.Cu")
		(hatch none 0.5)
		(connect_pads
			(clearance 0)
		)
		(min_thickness 0.25)
		(keepout
			(tracks allowed)
			(vias allowed)
			(pads allowed)
			(copperpour allowed)
			(footprints allowed)
		)
		(placement
			(enabled no)
			(sheetname "")
		)
		(fill
			(thermal_gap 0.5)
			(thermal_bridge_width 0.5)
			(island_removal_mode 0)
		)
		(polygon
			(pts
				(xy 420.461186 -211.818474) (xy 420.461186 -211.542884) (xy 421.019986 -211.542884) (xy 421.019986 -211.818474)
			)
		)
	)
	(zone
		(layer "In11.Cu")
		(hatch none 0.5)
		(connect_pads
			(clearance 0)
		)
		(min_thickness 0.25)
		(keepout
			(tracks allowed)
			(vias allowed)
			(pads allowed)
			(copperpour allowed)
			(footprints allowed)
		)
		(placement
			(enabled no)
			(sheetname "")
		)
		(fill
			(thermal_gap 0.5)
			(thermal_bridge_width 0.5)
			(island_removal_mode 0)
		)
		(polygon
			(pts
				(xy 172.521118 -291.718492) (xy 172.521118 -291.442902) (xy 173.079918 -291.442902) (xy 173.079918 -291.718492)
			)
		)
	)
	(zone
		(layer "In11.Cu")
		(hatch none 0.5)
		(connect_pads
			(clearance 0)
		)
		(min_thickness 0.25)
		(keepout
			(tracks allowed)
			(vias allowed)
			(pads allowed)
			(copperpour allowed)
			(footprints allowed)
		)
		(placement
			(enabled no)
			(sheetname "")
		)
		(fill
			(thermal_gap 0.5)
			(thermal_bridge_width 0.5)
			(island_removal_mode 0)
		)
		(polygon
			(pts
				(xy 177.170842 -215.114632) (xy 177.170842 -215.390222) (xy 176.612042 -215.390222) (xy 176.612042 -215.114632)
			)
		)
	)
	(zone
		(layer "In11.Cu")
		(hatch none 0.5)
		(connect_pads
			(clearance 0)
		)
		(min_thickness 0.25)
		(keepout
			(tracks allowed)
			(vias allowed)
			(pads allowed)
			(copperpour allowed)
			(footprints allowed)
		)
		(placement
			(enabled no)
			(sheetname "")
		)
		(fill
			(thermal_gap 0.5)
			(thermal_bridge_width 0.5)
			(island_removal_mode 0)
		)
		(polygon
			(pts
				(xy 420.461186 -235.618528) (xy 420.461186 -235.342938) (xy 421.019986 -235.342938) (xy 421.019986 -235.618528)
			)
		)
	)
	(zone
		(layer "In11.Cu")
		(hatch none 0.5)
		(connect_pads
			(clearance 0)
		)
		(min_thickness 0.25)
		(keepout
			(tracks allowed)
			(vias allowed)
			(pads allowed)
			(copperpour allowed)
			(footprints allowed)
		)
		(placement
			(enabled no)
			(sheetname "")
		)
		(fill
			(thermal_gap 0.5)
			(thermal_bridge_width 0.5)
			(island_removal_mode 0)
		)
		(polygon
			(pts
				(xy 173.070774 -209.164682) (xy 173.070774 -209.440272) (xy 172.511974 -209.440272) (xy 172.511974 -209.164682)
			)
		)
	)
	(zone
		(layer "In11.Cu")
		(hatch none 0.5)
		(connect_pads
			(clearance 0)
		)
		(min_thickness 0.25)
		(keepout
			(tracks allowed)
			(vias allowed)
			(pads allowed)
			(copperpour allowed)
			(footprints allowed)
		)
		(placement
			(enabled no)
			(sheetname "")
		)
		(fill
			(thermal_gap 0.5)
			(thermal_bridge_width 0.5)
			(island_removal_mode 0)
		)
		(polygon
			(pts
				(xy 203.245974 -211.714842) (xy 203.245974 -211.990432) (xy 202.687174 -211.990432) (xy 202.687174 -211.714842)
			)
		)
	)
	(zone
		(layer "In11.Cu")
		(hatch none 0.5)
		(connect_pads
			(clearance 0)
		)
		(min_thickness 0.25)
		(keepout
			(tracks allowed)
			(vias allowed)
			(pads allowed)
			(copperpour allowed)
			(footprints allowed)
		)
		(placement
			(enabled no)
			(sheetname "")
		)
		(fill
			(thermal_gap 0.5)
			(thermal_bridge_width 0.5)
			(island_removal_mode 0)
		)
		(polygon
			(pts
				(xy 187.608718 -213.518496) (xy 187.608718 -213.242906) (xy 188.167518 -213.242906) (xy 188.167518 -213.518496)
			)
		)
	)
	(zone
		(layer "In11.Cu")
		(hatch none 0.5)
		(connect_pads
			(clearance 0)
		)
		(min_thickness 0.25)
		(keepout
			(tracks allowed)
			(vias allowed)
			(pads allowed)
			(copperpour allowed)
			(footprints allowed)
		)
		(placement
			(enabled no)
			(sheetname "")
		)
		(fill
			(thermal_gap 0.5)
			(thermal_bridge_width 0.5)
			(island_removal_mode 0)
		)
		(polygon
			(pts
				(xy 46.646084 -229.046786) (xy 46.646084 -228.49713) (xy 47.276004 -228.49713) (xy 47.276004 -229.046786)
			)
		)
	)
	(zone
		(layer "In11.Cu")
		(hatch none 0.5)
		(connect_pads
			(clearance 0)
		)
		(min_thickness 0.25)
		(keepout
			(tracks allowed)
			(vias allowed)
			(pads allowed)
			(copperpour allowed)
			(footprints allowed)
		)
		(placement
			(enabled no)
			(sheetname "")
		)
		(fill
			(thermal_gap 0.5)
			(thermal_bridge_width 0.5)
			(island_removal_mode 0)
		)
		(polygon
			(pts
				(xy 439.648854 -262.818626) (xy 439.648854 -262.543036) (xy 440.207654 -262.543036) (xy 440.207654 -262.818626)
			)
		)
	)
	(zone
		(layer "In11.Cu")
		(hatch none 0.5)
		(connect_pads
			(clearance 0)
		)
		(min_thickness 0.25)
		(keepout
			(tracks allowed)
			(vias allowed)
			(pads allowed)
			(copperpour allowed)
			(footprints allowed)
		)
		(placement
			(enabled no)
			(sheetname "")
		)
		(fill
			(thermal_gap 0.5)
			(thermal_bridge_width 0.5)
			(island_removal_mode 0)
		)
		(polygon
			(pts
				(xy 20.61845 -287.692338) (xy 20.61845 -287.15208) (xy 21.186394 -287.15208) (xy 21.486876 -287.15208)
				(xy 21.591016 -287.25622) (xy 21.591016 -287.52165) (xy 21.420328 -287.692338) (xy 21.17725 -287.692338)
			)
		)
	)
	(zone
		(layer "In11.Cu")
		(hatch none 0.5)
		(connect_pads
			(clearance 0)
		)
		(min_thickness 0.25)
		(keepout
			(tracks allowed)
			(vias allowed)
			(pads allowed)
			(copperpour allowed)
			(footprints allowed)
		)
		(placement
			(enabled no)
			(sheetname "")
		)
		(fill
			(thermal_gap 0.5)
			(thermal_bridge_width 0.5)
			(island_removal_mode 0)
		)
		(polygon
			(pts
				(xy 46.646084 -217.146886) (xy 46.646084 -216.59723) (xy 47.276004 -216.59723) (xy 47.276004 -217.146886)
			)
		)
	)
	(zone
		(layer "In11.Cu")
		(hatch none 0.5)
		(connect_pads
			(clearance 0)
		)
		(min_thickness 0.25)
		(keepout
			(tracks allowed)
			(vias allowed)
			(pads allowed)
			(copperpour allowed)
			(footprints allowed)
		)
		(placement
			(enabled no)
			(sheetname "")
		)
		(fill
			(thermal_gap 0.5)
			(thermal_bridge_width 0.5)
			(island_removal_mode 0)
		)
		(polygon
			(pts
				(xy 172.521118 -259.418582) (xy 172.521118 -259.142992) (xy 173.079918 -259.142992) (xy 173.079918 -259.418582)
			)
		)
	)
	(zone
		(layer "In11.Cu")
		(hatch none 0.5)
		(connect_pads
			(clearance 0)
		)
		(min_thickness 0.25)
		(keepout
			(tracks allowed)
			(vias allowed)
			(pads allowed)
			(copperpour allowed)
			(footprints allowed)
		)
		(placement
			(enabled no)
			(sheetname "")
		)
		(fill
			(thermal_gap 0.5)
			(thermal_bridge_width 0.5)
			(island_removal_mode 0)
		)
		(polygon
			(pts
				(xy 210.789774 -266.964668) (xy 210.789774 -267.240258) (xy 210.230974 -267.240258) (xy 210.230974 -266.964668)
			)
		)
	)
	(zone
		(layer "In11.Cu")
		(hatch none 0.5)
		(connect_pads
			(clearance 0)
		)
		(min_thickness 0.25)
		(keepout
			(tracks allowed)
			(vias allowed)
			(pads allowed)
			(copperpour allowed)
			(footprints allowed)
		)
		(placement
			(enabled no)
			(sheetname "")
		)
		(fill
			(thermal_gap 0.5)
			(thermal_bridge_width 0.5)
			(island_removal_mode 0)
		)
		(polygon
			(pts
				(xy 50.771552 -308.09692) (xy 50.771552 -307.547264) (xy 51.401472 -307.547264) (xy 51.401472 -308.09692)
			)
		)
	)
	(zone
		(layer "In11.Cu")
		(hatch none 0.5)
		(connect_pads
			(clearance 0)
		)
		(min_thickness 0.25)
		(keepout
			(tracks allowed)
			(vias allowed)
			(pads allowed)
			(copperpour allowed)
			(footprints allowed)
		)
		(placement
			(enabled no)
			(sheetname "")
		)
		(fill
			(thermal_gap 0.5)
			(thermal_bridge_width 0.5)
			(island_removal_mode 0)
		)
		(polygon
			(pts
				(xy 450.636386 -297.392852) (xy 451.195186 -297.392852) (xy 451.195186 -297.668442) (xy 451.195186 -298.219876)
				(xy 450.663056 -298.219876) (xy 450.663056 -299.073062) (xy 451.195186 -299.073062) (xy 451.195186 -299.540168)
				(xy 449.694046 -299.540168) (xy 449.694046 -297.392852)
			)
		)
	)
	(zone
		(layer "In11.Cu")
		(hatch none 0.5)
		(connect_pads
			(clearance 0)
		)
		(min_thickness 0.25)
		(keepout
			(tracks allowed)
			(vias allowed)
			(pads allowed)
			(copperpour allowed)
			(footprints allowed)
		)
		(placement
			(enabled no)
			(sheetname "")
		)
		(fill
			(thermal_gap 0.5)
			(thermal_bridge_width 0.5)
			(island_removal_mode 0)
		)
		(polygon
			(pts
				(xy 428.004986 -246.668544) (xy 428.004986 -246.392954) (xy 428.563786 -246.392954) (xy 428.563786 -246.668544)
			)
		)
	)
	(zone
		(layer "In11.Cu")
		(hatch none 0.5)
		(connect_pads
			(clearance 0)
		)
		(min_thickness 0.25)
		(keepout
			(tracks allowed)
			(vias allowed)
			(pads allowed)
			(copperpour allowed)
			(footprints allowed)
		)
		(placement
			(enabled no)
			(sheetname "")
		)
		(fill
			(thermal_gap 0.5)
			(thermal_bridge_width 0.5)
			(island_removal_mode 0)
		)
		(polygon
			(pts
				(xy 420.461186 -278.968454) (xy 420.461186 -278.692864) (xy 421.019986 -278.692864) (xy 421.019986 -278.968454)
			)
		)
	)
	(zone
		(layer "In11.Cu")
		(hatch none 0.5)
		(connect_pads
			(clearance 0)
		)
		(min_thickness 0.25)
		(keepout
			(tracks allowed)
			(vias allowed)
			(pads allowed)
			(copperpour allowed)
			(footprints allowed)
		)
		(placement
			(enabled no)
			(sheetname "")
		)
		(fill
			(thermal_gap 0.5)
			(thermal_bridge_width 0.5)
			(island_removal_mode 0)
		)
		(polygon
			(pts
				(xy 184.714642 -260.164834) (xy 184.714642 -260.440424) (xy 184.155842 -260.440424) (xy 184.155842 -260.164834)
			)
		)
	)
	(zone
		(layer "In11.Cu")
		(hatch none 0.5)
		(connect_pads
			(clearance 0)
		)
		(min_thickness 0.25)
		(keepout
			(tracks allowed)
			(vias allowed)
			(pads allowed)
			(copperpour allowed)
			(footprints allowed)
		)
		(placement
			(enabled no)
			(sheetname "")
		)
		(fill
			(thermal_gap 0.5)
			(thermal_bridge_width 0.5)
			(island_removal_mode 0)
		)
		(polygon
			(pts
				(xy 65.833752 -268.996922) (xy 65.833752 -268.447266) (xy 66.463672 -268.447266) (xy 66.463672 -268.996922)
			)
		)
	)
	(zone
		(layer "In11.Cu")
		(hatch none 0.5)
		(connect_pads
			(clearance 0)
		)
		(min_thickness 0.25)
		(keepout
			(tracks allowed)
			(vias allowed)
			(pads allowed)
			(copperpour allowed)
			(footprints allowed)
		)
		(placement
			(enabled no)
			(sheetname "")
		)
		(fill
			(thermal_gap 0.5)
			(thermal_bridge_width 0.5)
			(island_removal_mode 0)
		)
		(polygon
			(pts
				(xy 203.245974 -270.364712) (xy 203.245974 -270.640302) (xy 202.687174 -270.640302) (xy 202.687174 -270.364712)
			)
		)
	)
	(zone
		(layer "In11.Cu")
		(hatch none 0.5)
		(connect_pads
			(clearance 0)
		)
		(min_thickness 0.25)
		(keepout
			(tracks allowed)
			(vias allowed)
			(pads allowed)
			(copperpour allowed)
			(footprints allowed)
		)
		(placement
			(enabled no)
			(sheetname "")
		)
		(fill
			(thermal_gap 0.5)
			(thermal_bridge_width 0.5)
			(island_removal_mode 0)
		)
		(polygon
			(pts
				(xy 420.461186 -280.668476) (xy 420.461186 -280.392886) (xy 421.019986 -280.392886) (xy 421.019986 -280.668476)
			)
		)
	)
	(zone
		(layer "In11.Cu")
		(hatch none 0.5)
		(connect_pads
			(clearance 0)
		)
		(min_thickness 0.25)
		(keepout
			(tracks allowed)
			(vias allowed)
			(pads allowed)
			(copperpour allowed)
			(footprints allowed)
		)
		(placement
			(enabled no)
			(sheetname "")
		)
		(fill
			(thermal_gap 0.5)
			(thermal_bridge_width 0.5)
			(island_removal_mode 0)
		)
		(polygon
			(pts
				(xy 284.18282 -367.640108) (xy 284.18282 -366.131348) (xy 286.766 -366.131348) (xy 286.766 -367.640108)
			)
		)
	)
	(zone
		(layer "In11.Cu")
		(hatch none 0.5)
		(connect_pads
			(clearance 0)
		)
		(min_thickness 0.25)
		(keepout
			(tracks allowed)
			(vias allowed)
			(pads allowed)
			(copperpour allowed)
			(footprints allowed)
		)
		(placement
			(enabled no)
			(sheetname "")
		)
		(fill
			(thermal_gap 0.5)
			(thermal_bridge_width 0.5)
			(island_removal_mode 0)
		)
		(polygon
			(pts
				(xy 203.245974 -306.064666) (xy 203.245974 -306.340256) (xy 202.687174 -306.340256) (xy 202.687174 -306.064666)
			)
		)
	)
	(zone
		(layer "In11.Cu")
		(hatch none 0.5)
		(connect_pads
			(clearance 0)
		)
		(min_thickness 0.25)
		(keepout
			(tracks allowed)
			(vias allowed)
			(pads allowed)
			(copperpour allowed)
			(footprints allowed)
		)
		(placement
			(enabled no)
			(sheetname "")
		)
		(fill
			(thermal_gap 0.5)
			(thermal_bridge_width 0.5)
			(island_removal_mode 0)
		)
		(polygon
			(pts
				(xy 50.746152 -200.14692) (xy 50.746152 -199.597264) (xy 51.376072 -199.597264) (xy 51.376072 -200.14692)
			)
		)
	)
	(zone
		(layer "In11.Cu")
		(hatch none 0.5)
		(connect_pads
			(clearance 0)
		)
		(min_thickness 0.25)
		(keepout
			(tracks allowed)
			(vias allowed)
			(pads allowed)
			(copperpour allowed)
			(footprints allowed)
		)
		(placement
			(enabled no)
			(sheetname "")
		)
		(fill
			(thermal_gap 0.5)
			(thermal_bridge_width 0.5)
			(island_removal_mode 0)
		)
		(polygon
			(pts
				(xy 294.586152 -294.496744) (xy 294.586152 -293.947088) (xy 295.216072 -293.947088) (xy 295.216072 -294.496744)
			)
		)
	)
	(zone
		(layer "In11.Cu")
		(hatch none 0.5)
		(connect_pads
			(clearance 0)
		)
		(min_thickness 0.25)
		(keepout
			(tracks allowed)
			(vias allowed)
			(pads allowed)
			(copperpour allowed)
			(footprints allowed)
		)
		(placement
			(enabled no)
			(sheetname "")
		)
		(fill
			(thermal_gap 0.5)
			(thermal_bridge_width 0.5)
			(island_removal_mode 0)
		)
		(polygon
			(pts
				(xy 450.636386 -272.16862) (xy 450.636386 -271.89303) (xy 451.195186 -271.89303) (xy 451.195186 -272.16862)
			)
		)
	)
	(zone
		(layer "In11.Cu")
		(hatch none 0.5)
		(connect_pads
			(clearance 0)
		)
		(min_thickness 0.25)
		(keepout
			(tracks allowed)
			(vias allowed)
			(pads allowed)
			(copperpour allowed)
			(footprints allowed)
		)
		(placement
			(enabled no)
			(sheetname "")
		)
		(fill
			(thermal_gap 0.5)
			(thermal_bridge_width 0.5)
			(island_removal_mode 0)
		)
		(polygon
			(pts
				(xy 298.71162 -295.346882) (xy 298.71162 -294.797226) (xy 299.34154 -294.797226) (xy 299.34154 -295.346882)
			)
		)
	)
	(zone
		(layer "In11.Cu")
		(hatch none 0.5)
		(connect_pads
			(clearance 0)
		)
		(min_thickness 0.25)
		(keepout
			(tracks not_allowed)
			(vias allowed)
			(pads allowed)
			(copperpour not_allowed)
			(footprints allowed)
		)
		(placement
			(enabled no)
			(sheetname "")
		)
		(fill
			(thermal_gap 0.5)
			(thermal_bridge_width 0.5)
			(island_removal_mode 0)
		)
		(polygon
			(pts
				(arc
					(start 148.24202 -428.960788)
					(mid 148.264338 -429.01467)
					(end 148.31822 -429.036988)
				)
				(arc
					(start 149.25802 -429.036988)
					(mid 149.311902 -429.01467)
					(end 149.33422 -428.960788)
				)
				(arc
					(start 149.33422 -426.419264)
					(mid 149.311902 -426.365382)
					(end 149.25802 -426.343064)
				)
				(arc
					(start 148.31822 -426.343064)
					(mid 148.264338 -426.365382)
					(end 148.24202 -426.419264)
				)
			)
		)
	)
	(zone
		(layer "In11.Cu")
		(hatch none 0.5)
		(connect_pads
			(clearance 0)
		)
		(min_thickness 0.25)
		(keepout
			(tracks allowed)
			(vias allowed)
			(pads allowed)
			(copperpour allowed)
			(footprints allowed)
		)
		(placement
			(enabled no)
			(sheetname "")
		)
		(fill
			(thermal_gap 0.5)
			(thermal_bridge_width 0.5)
			(island_removal_mode 0)
		)
		(polygon
			(pts
				(xy 172.521118 -278.968454) (xy 172.521118 -278.692864) (xy 173.079918 -278.692864) (xy 173.079918 -278.968454)
			)
		)
	)
	(zone
		(layer "In11.Cu")
		(hatch none 0.5)
		(connect_pads
			(clearance 0)
		)
		(min_thickness 0.25)
		(keepout
			(tracks allowed)
			(vias allowed)
			(pads allowed)
			(copperpour allowed)
			(footprints allowed)
		)
		(placement
			(enabled no)
			(sheetname "")
		)
		(fill
			(thermal_gap 0.5)
			(thermal_bridge_width 0.5)
			(island_removal_mode 0)
		)
		(polygon
			(pts
				(xy 176.621186 -291.718492) (xy 176.621186 -291.442902) (xy 177.179986 -291.442902) (xy 177.179986 -291.718492)
			)
		)
	)
	(zone
		(layer "In11.Cu")
		(hatch none 0.5)
		(connect_pads
			(clearance 0)
		)
		(min_thickness 0.25)
		(keepout
			(tracks allowed)
			(vias allowed)
			(pads allowed)
			(copperpour allowed)
			(footprints allowed)
		)
		(placement
			(enabled no)
			(sheetname "")
		)
		(fill
			(thermal_gap 0.5)
			(thermal_bridge_width 0.5)
			(island_removal_mode 0)
		)
		(polygon
			(pts
				(xy 420.461186 -250.068588) (xy 420.461186 -249.792998) (xy 421.019986 -249.792998) (xy 421.019986 -250.068588)
			)
		)
	)
	(zone
		(layer "In11.Cu")
		(hatch none 0.5)
		(connect_pads
			(clearance 0)
		)
		(min_thickness 0.25)
		(keepout
			(tracks allowed)
			(vias allowed)
			(pads allowed)
			(copperpour allowed)
			(footprints allowed)
		)
		(placement
			(enabled no)
			(sheetname "")
		)
		(fill
			(thermal_gap 0.5)
			(thermal_bridge_width 0.5)
			(island_removal_mode 0)
		)
		(polygon
			(pts
				(xy 451.186042 -296.714672) (xy 451.186042 -296.990262) (xy 450.627242 -296.990262) (xy 450.627242 -296.714672)
			)
		)
	)
	(zone
		(layer "In11.Cu")
		(hatch none 0.5)
		(connect_pads
			(clearance 0)
		)
		(min_thickness 0.25)
		(keepout
			(tracks allowed)
			(vias allowed)
			(pads allowed)
			(copperpour allowed)
			(footprints allowed)
		)
		(placement
			(enabled no)
			(sheetname "")
		)
		(fill
			(thermal_gap 0.5)
			(thermal_bridge_width 0.5)
			(island_removal_mode 0)
		)
		(polygon
			(pts
				(xy 46.646084 -196.746876) (xy 46.646084 -196.19722) (xy 47.276004 -196.19722) (xy 47.276004 -196.746876)
			)
		)
	)
	(zone
		(layer "In11.Cu")
		(hatch none 0.5)
		(connect_pads
			(clearance 0)
		)
		(min_thickness 0.25)
		(keepout
			(tracks allowed)
			(vias allowed)
			(pads allowed)
			(copperpour allowed)
			(footprints allowed)
		)
		(placement
			(enabled no)
			(sheetname "")
		)
		(fill
			(thermal_gap 0.5)
			(thermal_bridge_width 0.5)
			(island_removal_mode 0)
		)
		(polygon
			(pts
				(xy 449.402454 -269.34287) (xy 449.961254 -269.34287) (xy 450.344286 -269.34287) (xy 451.220586 -269.34287)
				(xy 451.220586 -269.85595) (xy 450.344286 -269.85595) (xy 450.344286 -270.24711) (xy 448.886326 -270.24711)
				(xy 448.886326 -269.34287)
			)
		)
	)
	(zone
		(layer "In11.Cu")
		(hatch none 0.5)
		(connect_pads
			(clearance 0)
		)
		(min_thickness 0.25)
		(keepout
			(tracks allowed)
			(vias allowed)
			(pads allowed)
			(copperpour allowed)
			(footprints allowed)
		)
		(placement
			(enabled no)
			(sheetname "")
		)
		(fill
			(thermal_gap 0.5)
			(thermal_bridge_width 0.5)
			(island_removal_mode 0)
		)
		(polygon
			(pts
				(xy 13.074396 -246.012208) (xy 13.074396 -244.690138) (xy 13.601954 -244.690138) (xy 13.601954 -246.012208)
			)
		)
	)
	(zone
		(layer "In11.Cu")
		(hatch none 0.5)
		(connect_pads
			(clearance 0)
		)
		(min_thickness 0.25)
		(keepout
			(tracks allowed)
			(vias allowed)
			(pads allowed)
			(copperpour allowed)
			(footprints allowed)
		)
		(placement
			(enabled no)
			(sheetname "")
		)
		(fill
			(thermal_gap 0.5)
			(thermal_bridge_width 0.5)
			(island_removal_mode 0)
		)
		(polygon
			(pts
				(xy 172.521118 -273.868388) (xy 172.521118 -273.592798) (xy 173.079918 -273.592798) (xy 173.079918 -273.868388)
			)
		)
	)
	(zone
		(layer "In11.Cu")
		(hatch none 0.5)
		(connect_pads
			(clearance 0)
		)
		(min_thickness 0.25)
		(keepout
			(tracks allowed)
			(vias allowed)
			(pads allowed)
			(copperpour allowed)
			(footprints allowed)
		)
		(placement
			(enabled no)
			(sheetname "")
		)
		(fill
			(thermal_gap 0.5)
			(thermal_bridge_width 0.5)
			(island_removal_mode 0)
		)
		(polygon
			(pts
				(xy 176.621186 -315.518546) (xy 176.621186 -315.242956) (xy 177.179986 -315.242956) (xy 177.179986 -315.518546)
			)
		)
	)
	(zone
		(layer "In11.Cu")
		(hatch none 0.5)
		(connect_pads
			(clearance 0)
		)
		(min_thickness 0.25)
		(keepout
			(tracks allowed)
			(vias allowed)
			(pads allowed)
			(copperpour allowed)
			(footprints allowed)
		)
		(placement
			(enabled no)
			(sheetname "")
		)
		(fill
			(thermal_gap 0.5)
			(thermal_bridge_width 0.5)
			(island_removal_mode 0)
		)
		(polygon
			(pts
				(xy 74.308208 -144.963896) (xy 74.308208 -143.495776) (xy 74.923904 -143.495776) (xy 74.923904 -144.963896)
			)
		)
	)
	(zone
		(layer "In11.Cu")
		(hatch none 0.5)
		(connect_pads
			(clearance 0)
		)
		(min_thickness 0.25)
		(keepout
			(tracks allowed)
			(vias allowed)
			(pads allowed)
			(copperpour allowed)
			(footprints allowed)
		)
		(placement
			(enabled no)
			(sheetname "")
		)
		(fill
			(thermal_gap 0.5)
			(thermal_bridge_width 0.5)
			(island_removal_mode 0)
		)
		(polygon
			(pts
				(xy 421.010842 -294.164766) (xy 421.010842 -294.440356) (xy 420.452042 -294.440356) (xy 420.452042 -294.164766)
			)
		)
	)
	(zone
		(layer "In11.Cu")
		(hatch none 0.5)
		(connect_pads
			(clearance 0)
		)
		(min_thickness 0.25)
		(keepout
			(tracks allowed)
			(vias allowed)
			(pads allowed)
			(copperpour allowed)
			(footprints allowed)
		)
		(placement
			(enabled no)
			(sheetname "")
		)
		(fill
			(thermal_gap 0.5)
			(thermal_bridge_width 0.5)
			(island_removal_mode 0)
		)
		(polygon
			(pts
				(xy 46.646084 -286.846772) (xy 46.646084 -286.297116) (xy 47.276004 -286.297116) (xy 47.276004 -286.846772)
			)
		)
	)
	(zone
		(layer "In11.Cu")
		(hatch none 0.5)
		(connect_pads
			(clearance 0)
		)
		(min_thickness 0.25)
		(keepout
			(tracks allowed)
			(vias allowed)
			(pads allowed)
			(copperpour allowed)
			(footprints allowed)
		)
		(placement
			(enabled no)
			(sheetname "")
		)
		(fill
			(thermal_gap 0.5)
			(thermal_bridge_width 0.5)
			(island_removal_mode 0)
		)
		(polygon
			(pts
				(xy 451.186042 -224.464626) (xy 451.186042 -224.740216) (xy 450.627242 -224.740216) (xy 450.627242 -224.464626)
			)
		)
	)
	(zone
		(layer "In11.Cu")
		(hatch none 0.5)
		(connect_pads
			(clearance 0)
		)
		(min_thickness 0.25)
		(keepout
			(tracks allowed)
			(vias allowed)
			(pads allowed)
			(copperpour allowed)
			(footprints allowed)
		)
		(placement
			(enabled no)
			(sheetname "")
		)
		(fill
			(thermal_gap 0.5)
			(thermal_bridge_width 0.5)
			(island_removal_mode 0)
		)
		(polygon
			(pts
				(xy 191.708786 -282.368498) (xy 191.708786 -282.092908) (xy 192.267586 -282.092908) (xy 192.267586 -282.368498)
			)
		)
	)
	(zone
		(layer "In11.Cu")
		(hatch none 0.5)
		(connect_pads
			(clearance 0)
		)
		(min_thickness 0.25)
		(keepout
			(tracks allowed)
			(vias allowed)
			(pads allowed)
			(copperpour allowed)
			(footprints allowed)
		)
		(placement
			(enabled no)
			(sheetname "")
		)
		(fill
			(thermal_gap 0.5)
			(thermal_bridge_width 0.5)
			(island_removal_mode 0)
		)
		(polygon
			(pts
				(xy 416.69208 -170.777408) (xy 416.69208 -167.234108) (xy 417.18484 -166.741348) (xy 418.01542 -166.741348)
				(xy 418.97554 -167.701468) (xy 418.97554 -169.669968) (xy 417.83254 -170.812968) (xy 416.72764 -170.812968)
			)
		)
	)
	(zone
		(layer "In11.Cu")
		(hatch none 0.5)
		(connect_pads
			(clearance 0)
		)
		(min_thickness 0.25)
		(keepout
			(tracks allowed)
			(vias allowed)
			(pads allowed)
			(copperpour allowed)
			(footprints allowed)
		)
		(placement
			(enabled no)
			(sheetname "")
		)
		(fill
			(thermal_gap 0.5)
			(thermal_bridge_width 0.5)
			(island_removal_mode 0)
		)
		(polygon
			(pts
				(xy 420.461186 -200.768458) (xy 420.461186 -200.492868) (xy 421.019986 -200.492868) (xy 421.019986 -200.768458)
			)
		)
	)
	(zone
		(layer "In11.Cu")
		(hatch none 0.5)
		(connect_pads
			(clearance 0)
		)
		(min_thickness 0.25)
		(keepout
			(tracks allowed)
			(vias allowed)
			(pads allowed)
			(copperpour allowed)
			(footprints allowed)
		)
		(placement
			(enabled no)
			(sheetname "")
		)
		(fill
			(thermal_gap 0.5)
			(thermal_bridge_width 0.5)
			(island_removal_mode 0)
		)
		(polygon
			(pts
				(xy 335.29778 -341.765128) (xy 335.29778 -340.424008) (xy 337.10372 -340.424008) (xy 337.10372 -341.765128)
			)
		)
	)
	(zone
		(layer "In11.Cu")
		(hatch none 0.5)
		(connect_pads
			(clearance 0)
		)
		(min_thickness 0.25)
		(keepout
			(tracks allowed)
			(vias allowed)
			(pads allowed)
			(copperpour allowed)
			(footprints allowed)
		)
		(placement
			(enabled no)
			(sheetname "")
		)
		(fill
			(thermal_gap 0.5)
			(thermal_bridge_width 0.5)
			(island_removal_mode 0)
		)
		(polygon
			(pts
				(xy 294.586152 -266.446762) (xy 294.586152 -265.897106) (xy 295.216072 -265.897106) (xy 295.216072 -266.446762)
			)
		)
	)
	(zone
		(layer "In11.Cu")
		(hatch none 0.5)
		(connect_pads
			(clearance 0)
		)
		(min_thickness 0.25)
		(keepout
			(tracks allowed)
			(vias allowed)
			(pads allowed)
			(copperpour allowed)
			(footprints allowed)
		)
		(placement
			(enabled no)
			(sheetname "")
		)
		(fill
			(thermal_gap 0.5)
			(thermal_bridge_width 0.5)
			(island_removal_mode 0)
		)
		(polygon
			(pts
				(xy 191.708786 -262.818626) (xy 191.708786 -262.543036) (xy 192.267586 -262.543036) (xy 192.267586 -262.818626)
			)
		)
	)
	(zone
		(layer "In11.Cu")
		(hatch none 0.5)
		(connect_pads
			(clearance 0)
		)
		(min_thickness 0.25)
		(keepout
			(tracks allowed)
			(vias allowed)
			(pads allowed)
			(copperpour allowed)
			(footprints allowed)
		)
		(placement
			(enabled no)
			(sheetname "")
		)
		(fill
			(thermal_gap 0.5)
			(thermal_bridge_width 0.5)
			(island_removal_mode 0)
		)
		(polygon
			(pts
				(xy 420.934642 -261.864602) (xy 420.934642 -262.140192) (xy 420.375842 -262.140192) (xy 420.375842 -261.864602)
			)
		)
	)
	(zone
		(layer "In11.Cu")
		(hatch none 0.5)
		(connect_pads
			(clearance 0)
		)
		(min_thickness 0.25)
		(keepout
			(tracks allowed)
			(vias allowed)
			(pads allowed)
			(copperpour allowed)
			(footprints allowed)
		)
		(placement
			(enabled no)
			(sheetname "")
		)
		(fill
			(thermal_gap 0.5)
			(thermal_bridge_width 0.5)
			(island_removal_mode 0)
		)
		(polygon
			(pts
				(xy 451.186042 -306.064666) (xy 451.186042 -306.340256) (xy 450.627242 -306.340256) (xy 450.627242 -306.064666)
			)
		)
	)
	(zone
		(layer "In11.Cu")
		(hatch none 0.5)
		(connect_pads
			(clearance 0)
		)
		(min_thickness 0.25)
		(keepout
			(tracks allowed)
			(vias allowed)
			(pads allowed)
			(copperpour allowed)
			(footprints allowed)
		)
		(placement
			(enabled no)
			(sheetname "")
		)
		(fill
			(thermal_gap 0.5)
			(thermal_bridge_width 0.5)
			(island_removal_mode 0)
		)
		(polygon
			(pts
				(xy 176.621186 -296.818558) (xy 176.621186 -296.542968) (xy 177.179986 -296.542968) (xy 177.179986 -296.818558)
			)
		)
	)
	(zone
		(layer "In11.Cu")
		(hatch none 0.5)
		(connect_pads
			(clearance 0)
		)
		(min_thickness 0.25)
		(keepout
			(tracks allowed)
			(vias allowed)
			(pads allowed)
			(copperpour allowed)
			(footprints allowed)
		)
		(placement
			(enabled no)
			(sheetname "")
		)
		(fill
			(thermal_gap 0.5)
			(thermal_bridge_width 0.5)
			(island_removal_mode 0)
		)
		(polygon
			(pts
				(xy 298.71162 -289.396932) (xy 298.71162 -288.847276) (xy 299.34154 -288.847276) (xy 299.34154 -289.396932)
			)
		)
	)
	(zone
		(layer "In11.Cu")
		(hatch none 0.5)
		(connect_pads
			(clearance 0)
		)
		(min_thickness 0.25)
		(keepout
			(tracks allowed)
			(vias allowed)
			(pads allowed)
			(copperpour allowed)
			(footprints allowed)
		)
		(placement
			(enabled no)
			(sheetname "")
		)
		(fill
			(thermal_gap 0.5)
			(thermal_bridge_width 0.5)
			(island_removal_mode 0)
		)
		(polygon
			(pts
				(xy 176.621186 -283.218382) (xy 176.621186 -282.942792) (xy 177.179986 -282.942792) (xy 177.179986 -283.218382)
			)
		)
	)
	(zone
		(layer "In11.Cu")
		(hatch none 0.5)
		(connect_pads
			(clearance 0)
		)
		(min_thickness 0.25)
		(keepout
			(tracks allowed)
			(vias allowed)
			(pads allowed)
			(copperpour allowed)
			(footprints allowed)
		)
		(placement
			(enabled no)
			(sheetname "")
		)
		(fill
			(thermal_gap 0.5)
			(thermal_bridge_width 0.5)
			(island_removal_mode 0)
		)
		(polygon
			(pts
				(xy 425.11091 -236.36478) (xy 425.11091 -236.64037) (xy 424.55211 -236.64037) (xy 424.55211 -236.36478)
			)
		)
	)
	(zone
		(layer "In11.Cu")
		(hatch none 0.5)
		(connect_pads
			(clearance 0)
		)
		(min_thickness 0.25)
		(keepout
			(tracks allowed)
			(vias allowed)
			(pads allowed)
			(copperpour allowed)
			(footprints allowed)
		)
		(placement
			(enabled no)
			(sheetname "")
		)
		(fill
			(thermal_gap 0.5)
			(thermal_bridge_width 0.5)
			(island_removal_mode 0)
		)
		(polygon
			(pts
				(xy 298.68622 -248.596912) (xy 298.68622 -248.047256) (xy 299.31614 -248.047256) (xy 299.31614 -248.596912)
			)
		)
	)
	(zone
		(layer "In11.Cu")
		(hatch none 0.5)
		(connect_pads
			(clearance 0)
		)
		(min_thickness 0.25)
		(keepout
			(tracks allowed)
			(vias allowed)
			(pads allowed)
			(copperpour allowed)
			(footprints allowed)
		)
		(placement
			(enabled no)
			(sheetname "")
		)
		(fill
			(thermal_gap 0.5)
			(thermal_bridge_width 0.5)
			(island_removal_mode 0)
		)
		(polygon
			(pts
				(xy 177.170842 -314.564776) (xy 177.170842 -314.840366) (xy 176.612042 -314.840366) (xy 176.612042 -314.564776)
			)
		)
	)
	(zone
		(layer "In11.Cu")
		(hatch none 0.5)
		(connect_pads
			(clearance 0)
		)
		(min_thickness 0.25)
		(keepout
			(tracks allowed)
			(vias allowed)
			(pads allowed)
			(copperpour allowed)
			(footprints allowed)
		)
		(placement
			(enabled no)
			(sheetname "")
		)
		(fill
			(thermal_gap 0.5)
			(thermal_bridge_width 0.5)
			(island_removal_mode 0)
		)
		(polygon
			(pts
				(xy 187.608718 -227.968556) (xy 187.608718 -227.692966) (xy 188.167518 -227.692966) (xy 188.167518 -227.968556)
			)
		)
	)
	(zone
		(layer "In11.Cu")
		(hatch none 0.5)
		(connect_pads
			(clearance 0)
		)
		(min_thickness 0.25)
		(keepout
			(tracks allowed)
			(vias allowed)
			(pads allowed)
			(copperpour allowed)
			(footprints allowed)
		)
		(placement
			(enabled no)
			(sheetname "")
		)
		(fill
			(thermal_gap 0.5)
			(thermal_bridge_width 0.5)
			(island_removal_mode 0)
		)
		(polygon
			(pts
				(xy 450.636386 -274.442936) (xy 451.195186 -274.442936) (xy 451.195186 -274.718526) (xy 451.195186 -275.05787)
				(xy 450.517006 -275.05787) (xy 450.517006 -274.442936)
			)
		)
	)
	(zone
		(layer "In11.Cu")
		(hatch none 0.5)
		(connect_pads
			(clearance 0)
		)
		(min_thickness 0.25)
		(keepout
			(tracks allowed)
			(vias allowed)
			(pads allowed)
			(copperpour allowed)
			(footprints allowed)
		)
		(placement
			(enabled no)
			(sheetname "")
		)
		(fill
			(thermal_gap 0.5)
			(thermal_bridge_width 0.5)
			(island_removal_mode 0)
		)
		(polygon
			(pts
				(xy 176.621186 -281.51836) (xy 176.621186 -281.24277) (xy 177.179986 -281.24277) (xy 177.179986 -281.51836)
			)
		)
	)
	(zone
		(layer "In11.Cu")
		(hatch none 0.5)
		(connect_pads
			(clearance 0)
		)
		(min_thickness 0.25)
		(keepout
			(tracks allowed)
			(vias allowed)
			(pads allowed)
			(copperpour allowed)
			(footprints allowed)
		)
		(placement
			(enabled no)
			(sheetname "")
		)
		(fill
			(thermal_gap 0.5)
			(thermal_bridge_width 0.5)
			(island_removal_mode 0)
		)
		(polygon
			(pts
				(xy 46.646084 -215.446864) (xy 46.646084 -214.897208) (xy 47.276004 -214.897208) (xy 47.276004 -215.446864)
			)
		)
	)
	(zone
		(layer "In11.Cu")
		(hatch none 0.5)
		(connect_pads
			(clearance 0)
		)
		(min_thickness 0.25)
		(keepout
			(tracks allowed)
			(vias allowed)
			(pads allowed)
			(copperpour allowed)
			(footprints allowed)
		)
		(placement
			(enabled no)
			(sheetname "")
		)
		(fill
			(thermal_gap 0.5)
			(thermal_bridge_width 0.5)
			(island_removal_mode 0)
		)
		(polygon
			(pts
				(xy 50.746152 -222.246952) (xy 50.746152 -221.697296) (xy 51.376072 -221.697296) (xy 51.376072 -222.246952)
			)
		)
	)
	(zone
		(layer "In11.Cu")
		(hatch none 0.5)
		(connect_pads
			(clearance 0)
		)
		(min_thickness 0.25)
		(keepout
			(tracks allowed)
			(vias allowed)
			(pads allowed)
			(copperpour allowed)
			(footprints allowed)
		)
		(placement
			(enabled no)
			(sheetname "")
		)
		(fill
			(thermal_gap 0.5)
			(thermal_bridge_width 0.5)
			(island_removal_mode 0)
		)
		(polygon
			(pts
				(xy 425.11091 -282.264612) (xy 425.11091 -282.540202) (xy 424.55211 -282.540202) (xy 424.55211 -282.264612)
			)
		)
	)
	(zone
		(layer "In11.Cu")
		(hatch none 0.5)
		(connect_pads
			(clearance 0)
		)
		(min_thickness 0.25)
		(keepout
			(tracks allowed)
			(vias allowed)
			(pads allowed)
			(copperpour allowed)
			(footprints allowed)
		)
		(placement
			(enabled no)
			(sheetname "")
		)
		(fill
			(thermal_gap 0.5)
			(thermal_bridge_width 0.5)
			(island_removal_mode 0)
		)
		(polygon
			(pts
				(xy 20.61845 -297.042332) (xy 20.61845 -296.502074) (xy 21.186394 -296.502074) (xy 21.486876 -296.502074)
				(xy 21.591016 -296.606214) (xy 21.591016 -296.871644) (xy 21.420328 -297.042332) (xy 21.17725 -297.042332)
			)
		)
	)
	(zone
		(layer "In11.Cu")
		(hatch none 0.5)
		(connect_pads
			(clearance 0)
		)
		(min_thickness 0.25)
		(keepout
			(tracks allowed)
			(vias allowed)
			(pads allowed)
			(copperpour allowed)
			(footprints allowed)
		)
		(placement
			(enabled no)
			(sheetname "")
		)
		(fill
			(thermal_gap 0.5)
			(thermal_bridge_width 0.5)
			(island_removal_mode 0)
		)
		(polygon
			(pts
				(xy 424.561254 -199.068436) (xy 424.561254 -198.792846) (xy 425.120054 -198.792846) (xy 425.120054 -199.068436)
			)
		)
	)
	(zone
		(layer "In11.Cu")
		(hatch none 0.5)
		(connect_pads
			(clearance 0)
		)
		(min_thickness 0.25)
		(keepout
			(tracks allowed)
			(vias allowed)
			(pads allowed)
			(copperpour allowed)
			(footprints allowed)
		)
		(placement
			(enabled no)
			(sheetname "")
		)
		(fill
			(thermal_gap 0.5)
			(thermal_bridge_width 0.5)
			(island_removal_mode 0)
		)
		(polygon
			(pts
				(xy 298.71162 -300.446948) (xy 298.71162 -299.897292) (xy 299.34154 -299.897292) (xy 299.34154 -300.446948)
			)
		)
	)
	(zone
		(layer "In11.Cu")
		(hatch none 0.5)
		(connect_pads
			(clearance 0)
		)
		(min_thickness 0.25)
		(keepout
			(tracks allowed)
			(vias allowed)
			(pads allowed)
			(copperpour allowed)
			(footprints allowed)
		)
		(placement
			(enabled no)
			(sheetname "")
		)
		(fill
			(thermal_gap 0.5)
			(thermal_bridge_width 0.5)
			(island_removal_mode 0)
		)
		(polygon
			(pts
				(xy 421.010842 -199.814688) (xy 421.010842 -200.090278) (xy 420.452042 -200.090278) (xy 420.452042 -199.814688)
			)
		)
	)
	(zone
		(layer "In11.Cu")
		(hatch none 0.5)
		(connect_pads
			(clearance 0)
		)
		(min_thickness 0.25)
		(keepout
			(tracks allowed)
			(vias allowed)
			(pads allowed)
			(copperpour allowed)
			(footprints allowed)
		)
		(placement
			(enabled no)
			(sheetname "")
		)
		(fill
			(thermal_gap 0.5)
			(thermal_bridge_width 0.5)
			(island_removal_mode 0)
		)
		(polygon
			(pts
				(xy 294.586152 -200.996804) (xy 294.586152 -200.447148) (xy 295.216072 -200.447148) (xy 295.216072 -200.996804)
			)
		)
	)
	(zone
		(layer "In11.Cu")
		(hatch none 0.5)
		(connect_pads
			(clearance 0)
		)
		(min_thickness 0.25)
		(keepout
			(tracks allowed)
			(vias allowed)
			(pads allowed)
			(copperpour allowed)
			(footprints allowed)
		)
		(placement
			(enabled no)
			(sheetname "")
		)
		(fill
			(thermal_gap 0.5)
			(thermal_bridge_width 0.5)
			(island_removal_mode 0)
		)
		(polygon
			(pts
				(xy 420.384986 -264.518394) (xy 420.384986 -264.242804) (xy 420.943786 -264.242804) (xy 420.943786 -264.518394)
			)
		)
	)
	(zone
		(layer "In11.Cu")
		(hatch none 0.5)
		(connect_pads
			(clearance 0)
		)
		(min_thickness 0.25)
		(keepout
			(tracks allowed)
			(vias allowed)
			(pads allowed)
			(copperpour allowed)
			(footprints allowed)
		)
		(placement
			(enabled no)
			(sheetname "")
		)
		(fill
			(thermal_gap 0.5)
			(thermal_bridge_width 0.5)
			(island_removal_mode 0)
		)
		(polygon
			(pts
				(xy 424.561254 -290.01847) (xy 424.561254 -289.74288) (xy 425.120054 -289.74288) (xy 425.120054 -290.01847)
			)
		)
	)
	(zone
		(layer "In11.Cu")
		(hatch none 0.5)
		(connect_pads
			(clearance 0)
		)
		(min_thickness 0.25)
		(keepout
			(tracks allowed)
			(vias allowed)
			(pads allowed)
			(copperpour allowed)
			(footprints allowed)
		)
		(placement
			(enabled no)
			(sheetname "")
		)
		(fill
			(thermal_gap 0.5)
			(thermal_bridge_width 0.5)
			(island_removal_mode 0)
		)
		(polygon
			(pts
				(xy 294.586152 -296.196766) (xy 294.586152 -295.64711) (xy 295.216072 -295.64711) (xy 295.216072 -296.196766)
			)
		)
	)
	(zone
		(layer "In11.Cu")
		(hatch none 0.5)
		(connect_pads
			(clearance 0)
		)
		(min_thickness 0.25)
		(keepout
			(tracks allowed)
			(vias allowed)
			(pads allowed)
			(copperpour allowed)
			(footprints allowed)
		)
		(placement
			(enabled no)
			(sheetname "")
		)
		(fill
			(thermal_gap 0.5)
			(thermal_bridge_width 0.5)
			(island_removal_mode 0)
		)
		(polygon
			(pts
				(xy 360.284776 -362.020358) (xy 360.284776 -352.07194) (xy 362.687108 -352.07194) (xy 362.687108 -362.020358)
			)
		)
	)
	(zone
		(layer "In11.Cu")
		(hatch none 0.5)
		(connect_pads
			(clearance 0)
		)
		(min_thickness 0.25)
		(keepout
			(tracks allowed)
			(vias allowed)
			(pads allowed)
			(copperpour allowed)
			(footprints allowed)
		)
		(placement
			(enabled no)
			(sheetname "")
		)
		(fill
			(thermal_gap 0.5)
			(thermal_bridge_width 0.5)
			(island_removal_mode 0)
		)
		(polygon
			(pts
				(xy 425.11091 -201.51471) (xy 425.11091 -201.7903) (xy 424.55211 -201.7903) (xy 424.55211 -201.51471)
			)
		)
	)
	(zone
		(layer "In11.Cu")
		(hatch none 0.5)
		(connect_pads
			(clearance 0)
		)
		(min_thickness 0.25)
		(keepout
			(tracks allowed)
			(vias allowed)
			(pads allowed)
			(copperpour allowed)
			(footprints allowed)
		)
		(placement
			(enabled no)
			(sheetname "")
		)
		(fill
			(thermal_gap 0.5)
			(thermal_bridge_width 0.5)
			(island_removal_mode 0)
		)
		(polygon
			(pts
				(xy 450.636386 -273.868388) (xy 450.636386 -273.592798) (xy 451.195186 -273.592798) (xy 451.195186 -273.868388)
			)
		)
	)
	(zone
		(layer "In11.Cu")
		(hatch none 0.5)
		(connect_pads
			(clearance 0)
		)
		(min_thickness 0.25)
		(keepout
			(tracks allowed)
			(vias allowed)
			(pads allowed)
			(copperpour allowed)
			(footprints allowed)
		)
		(placement
			(enabled no)
			(sheetname "")
		)
		(fill
			(thermal_gap 0.5)
			(thermal_bridge_width 0.5)
			(island_removal_mode 0)
		)
		(polygon
			(pts
				(xy 294.586152 -297.896788) (xy 294.586152 -297.347132) (xy 295.216072 -297.347132) (xy 295.216072 -297.896788)
			)
		)
	)
	(zone
		(layer "In11.Cu")
		(hatch none 0.5)
		(connect_pads
			(clearance 0)
		)
		(min_thickness 0.25)
		(keepout
			(tracks allowed)
			(vias allowed)
			(pads allowed)
			(copperpour allowed)
			(footprints allowed)
		)
		(placement
			(enabled no)
			(sheetname "")
		)
		(fill
			(thermal_gap 0.5)
			(thermal_bridge_width 0.5)
			(island_removal_mode 0)
		)
		(polygon
			(pts
				(xy 451.186042 -284.814772) (xy 451.186042 -285.090362) (xy 450.627242 -285.090362) (xy 450.522086 -285.090362)
				(xy 450.522086 -283.79547) (xy 451.186042 -283.79547)
			)
		)
	)
	(zone
		(layer "In11.Cu")
		(hatch none 0.5)
		(connect_pads
			(clearance 0)
		)
		(min_thickness 0.25)
		(keepout
			(tracks allowed)
			(vias allowed)
			(pads allowed)
			(copperpour allowed)
			(footprints allowed)
		)
		(placement
			(enabled no)
			(sheetname "")
		)
		(fill
			(thermal_gap 0.5)
			(thermal_bridge_width 0.5)
			(island_removal_mode 0)
		)
		(polygon
			(pts
				(xy 16.524224 -266.450572) (xy 16.524224 -265.900154) (xy 17.083024 -265.900154) (xy 17.083024 -266.450572)
			)
		)
	)
	(zone
		(layer "In11.Cu")
		(hatch none 0.5)
		(connect_pads
			(clearance 0)
		)
		(min_thickness 0.25)
		(keepout
			(tracks allowed)
			(vias allowed)
			(pads allowed)
			(copperpour allowed)
			(footprints allowed)
		)
		(placement
			(enabled no)
			(sheetname "")
		)
		(fill
			(thermal_gap 0.5)
			(thermal_bridge_width 0.5)
			(island_removal_mode 0)
		)
		(polygon
			(pts
				(xy 424.561254 -278.968454) (xy 424.561254 -278.692864) (xy 425.120054 -278.692864) (xy 425.120054 -278.968454)
			)
		)
	)
	(zone
		(layer "In11.Cu")
		(hatch none 0.5)
		(connect_pads
			(clearance 0)
		)
		(min_thickness 0.25)
		(keepout
			(tracks allowed)
			(vias allowed)
			(pads allowed)
			(copperpour allowed)
			(footprints allowed)
		)
		(placement
			(enabled no)
			(sheetname "")
		)
		(fill
			(thermal_gap 0.5)
			(thermal_bridge_width 0.5)
			(island_removal_mode 0)
		)
		(polygon
			(pts
				(xy 421.010842 -313.714638) (xy 421.010842 -313.990228) (xy 420.452042 -313.990228) (xy 420.452042 -313.714638)
			)
		)
	)
	(zone
		(layer "In11.Cu")
		(hatch none 0.5)
		(connect_pads
			(clearance 0)
		)
		(min_thickness 0.25)
		(keepout
			(tracks allowed)
			(vias allowed)
			(pads allowed)
			(copperpour allowed)
			(footprints allowed)
		)
		(placement
			(enabled no)
			(sheetname "")
		)
		(fill
			(thermal_gap 0.5)
			(thermal_bridge_width 0.5)
			(island_removal_mode 0)
		)
		(polygon
			(pts
				(xy 46.646084 -280.896822) (xy 46.646084 -280.347166) (xy 47.276004 -280.347166) (xy 47.276004 -280.896822)
			)
		)
	)
	(zone
		(layer "In11.Cu")
		(hatch none 0.5)
		(connect_pads
			(clearance 0)
		)
		(min_thickness 0.25)
		(keepout
			(tracks allowed)
			(vias allowed)
			(pads allowed)
			(copperpour allowed)
			(footprints allowed)
		)
		(placement
			(enabled no)
			(sheetname "")
		)
		(fill
			(thermal_gap 0.5)
			(thermal_bridge_width 0.5)
			(island_removal_mode 0)
		)
		(polygon
			(pts
				(xy 20.624292 -272.400776) (xy 20.624292 -271.850358) (xy 21.183092 -271.850358) (xy 21.183092 -272.400776)
			)
		)
	)
	(zone
		(layer "In11.Cu")
		(hatch none 0.5)
		(connect_pads
			(clearance 0)
		)
		(min_thickness 0.25)
		(keepout
			(tracks allowed)
			(vias allowed)
			(pads allowed)
			(copperpour allowed)
			(footprints allowed)
		)
		(placement
			(enabled no)
			(sheetname "")
		)
		(fill
			(thermal_gap 0.5)
			(thermal_bridge_width 0.5)
			(island_removal_mode 0)
		)
		(polygon
			(pts
				(xy 176.621186 -217.768424) (xy 176.621186 -217.492834) (xy 177.179986 -217.492834) (xy 177.179986 -217.768424)
			)
		)
	)
	(zone
		(layer "In11.Cu")
		(hatch none 0.5)
		(connect_pads
			(clearance 0)
		)
		(min_thickness 0.25)
		(keepout
			(tracks allowed)
			(vias allowed)
			(pads allowed)
			(copperpour allowed)
			(footprints allowed)
		)
		(placement
			(enabled no)
			(sheetname "")
		)
		(fill
			(thermal_gap 0.5)
			(thermal_bridge_width 0.5)
			(island_removal_mode 0)
		)
		(polygon
			(pts
				(xy 46.646084 -274.946872) (xy 46.646084 -274.397216) (xy 47.276004 -274.397216) (xy 47.276004 -274.946872)
			)
		)
	)
	(zone
		(layer "In11.Cu")
		(hatch none 0.5)
		(connect_pads
			(clearance 0)
		)
		(min_thickness 0.25)
		(keepout
			(tracks allowed)
			(vias allowed)
			(pads allowed)
			(copperpour allowed)
			(footprints allowed)
		)
		(placement
			(enabled no)
			(sheetname "")
		)
		(fill
			(thermal_gap 0.5)
			(thermal_bridge_width 0.5)
			(island_removal_mode 0)
		)
		(polygon
			(pts
				(xy 450.636386 -287.468564) (xy 450.636386 -287.192974) (xy 451.195186 -287.192974) (xy 451.195186 -287.468564)
			)
		)
	)
	(zone
		(layer "In11.Cu")
		(hatch none 0.5)
		(connect_pads
			(clearance 0)
		)
		(min_thickness 0.25)
		(keepout
			(tracks allowed)
			(vias allowed)
			(pads allowed)
			(copperpour allowed)
			(footprints allowed)
		)
		(placement
			(enabled no)
			(sheetname "")
		)
		(fill
			(thermal_gap 0.5)
			(thermal_bridge_width 0.5)
			(island_removal_mode 0)
		)
		(polygon
			(pts
				(xy 294.586152 -241.796824) (xy 294.586152 -241.247168) (xy 295.216072 -241.247168) (xy 295.216072 -241.796824)
			)
		)
	)
	(zone
		(layer "In11.Cu")
		(hatch none 0.5)
		(connect_pads
			(clearance 0)
		)
		(min_thickness 0.25)
		(keepout
			(tracks not_allowed)
			(vias allowed)
			(pads allowed)
			(copperpour not_allowed)
			(footprints allowed)
		)
		(placement
			(enabled no)
			(sheetname "")
		)
		(fill
			(thermal_gap 0.5)
			(thermal_bridge_width 0.5)
			(island_removal_mode 0)
		)
		(polygon
			(pts
				(arc
					(start 135.242046 -428.960788)
					(mid 135.264364 -429.01467)
					(end 135.318246 -429.036988)
				)
				(arc
					(start 136.258046 -429.036988)
					(mid 136.311928 -429.01467)
					(end 136.334246 -428.960788)
				)
				(arc
					(start 136.334246 -426.419264)
					(mid 136.311928 -426.365382)
					(end 136.258046 -426.343064)
				)
				(arc
					(start 135.318246 -426.343064)
					(mid 135.264364 -426.365382)
					(end 135.242046 -426.419264)
				)
			)
		)
	)
	(zone
		(layer "In11.Cu")
		(hatch none 0.5)
		(connect_pads
			(clearance 0)
		)
		(min_thickness 0.25)
		(keepout
			(tracks allowed)
			(vias allowed)
			(pads allowed)
			(copperpour allowed)
			(footprints allowed)
		)
		(placement
			(enabled no)
			(sheetname "")
		)
		(fill
			(thermal_gap 0.5)
			(thermal_bridge_width 0.5)
			(island_removal_mode 0)
		)
		(polygon
			(pts
				(xy 192.182242 -267.814806) (xy 192.182242 -268.090396) (xy 191.623442 -268.090396) (xy 191.623442 -267.814806)
			)
		)
	)
	(zone
		(layer "In11.Cu")
		(hatch none 0.5)
		(connect_pads
			(clearance 0)
		)
		(min_thickness 0.25)
		(keepout
			(tracks allowed)
			(vias allowed)
			(pads allowed)
			(copperpour allowed)
			(footprints allowed)
		)
		(placement
			(enabled no)
			(sheetname "")
		)
		(fill
			(thermal_gap 0.5)
			(thermal_bridge_width 0.5)
			(island_removal_mode 0)
		)
		(polygon
			(pts
				(xy 203.245974 -301.814738) (xy 203.245974 -302.090328) (xy 202.687174 -302.090328) (xy 202.687174 -301.814738)
			)
		)
	)
	(zone
		(layer "In11.Cu")
		(hatch none 0.5)
		(connect_pads
			(clearance 0)
		)
		(min_thickness 0.25)
		(keepout
			(tracks allowed)
			(vias allowed)
			(pads allowed)
			(copperpour allowed)
			(footprints allowed)
		)
		(placement
			(enabled no)
			(sheetname "")
		)
		(fill
			(thermal_gap 0.5)
			(thermal_bridge_width 0.5)
			(island_removal_mode 0)
		)
		(polygon
			(pts
				(xy 176.621186 -195.668392) (xy 176.621186 -195.392802) (xy 177.179986 -195.392802) (xy 177.179986 -195.668392)
			)
		)
	)
	(zone
		(layer "In11.Cu")
		(hatch none 0.5)
		(connect_pads
			(clearance 0)
		)
		(min_thickness 0.25)
		(keepout
			(tracks allowed)
			(vias allowed)
			(pads allowed)
			(copperpour allowed)
			(footprints allowed)
		)
		(placement
			(enabled no)
			(sheetname "")
		)
		(fill
			(thermal_gap 0.5)
			(thermal_bridge_width 0.5)
			(island_removal_mode 0)
		)
		(polygon
			(pts
				(xy 424.561254 -274.718526) (xy 424.561254 -274.442936) (xy 425.120054 -274.442936) (xy 425.120054 -274.718526)
			)
		)
	)
	(zone
		(layer "In11.Cu")
		(hatch none 0.5)
		(connect_pads
			(clearance 0)
		)
		(min_thickness 0.25)
		(keepout
			(tracks not_allowed)
			(vias allowed)
			(pads allowed)
			(copperpour not_allowed)
			(footprints allowed)
		)
		(placement
			(enabled no)
			(sheetname "")
		)
		(fill
			(thermal_gap 0.5)
			(thermal_bridge_width 0.5)
			(island_removal_mode 0)
		)
		(polygon
			(pts
				(arc
					(start 395.242034 -428.960788)
					(mid 395.264352 -429.01467)
					(end 395.318234 -429.036988)
				)
				(arc
					(start 396.258034 -429.036988)
					(mid 396.311916 -429.01467)
					(end 396.334234 -428.960788)
				)
				(arc
					(start 396.334234 -426.419264)
					(mid 396.311916 -426.365382)
					(end 396.258034 -426.343064)
				)
				(arc
					(start 395.318234 -426.343064)
					(mid 395.264352 -426.365382)
					(end 395.242034 -426.419264)
				)
			)
		)
	)
	(zone
		(layer "In11.Cu")
		(hatch none 0.5)
		(connect_pads
			(clearance 0)
		)
		(min_thickness 0.25)
		(keepout
			(tracks allowed)
			(vias allowed)
			(pads allowed)
			(copperpour allowed)
			(footprints allowed)
		)
		(placement
			(enabled no)
			(sheetname "")
		)
		(fill
			(thermal_gap 0.5)
			(thermal_bridge_width 0.5)
			(island_removal_mode 0)
		)
		(polygon
			(pts
				(xy 177.170842 -300.9646) (xy 177.170842 -301.24019) (xy 176.612042 -301.24019) (xy 176.612042 -300.9646)
			)
		)
	)
	(zone
		(layer "In11.Cu")
		(hatch none 0.5)
		(connect_pads
			(clearance 0)
		)
		(min_thickness 0.25)
		(keepout
			(tracks allowed)
			(vias allowed)
			(pads allowed)
			(copperpour allowed)
			(footprints allowed)
		)
		(placement
			(enabled no)
			(sheetname "")
		)
		(fill
			(thermal_gap 0.5)
			(thermal_bridge_width 0.5)
			(island_removal_mode 0)
		)
		(polygon
			(pts
				(xy 172.521118 -241.568478) (xy 172.521118 -241.292888) (xy 173.079918 -241.292888) (xy 173.079918 -241.568478)
			)
		)
	)
	(zone
		(layer "In11.Cu")
		(hatch none 0.5)
		(connect_pads
			(clearance 0)
		)
		(min_thickness 0.25)
		(keepout
			(tracks allowed)
			(vias allowed)
			(pads allowed)
			(copperpour allowed)
			(footprints allowed)
		)
		(placement
			(enabled no)
			(sheetname "")
		)
		(fill
			(thermal_gap 0.5)
			(thermal_bridge_width 0.5)
			(island_removal_mode 0)
		)
		(polygon
			(pts
				(xy 436.098442 -280.564844) (xy 436.098442 -280.840434) (xy 435.539642 -280.840434) (xy 435.539642 -280.564844)
			)
		)
	)
	(zone
		(layer "In11.Cu")
		(hatch none 0.5)
		(connect_pads
			(clearance 0)
		)
		(min_thickness 0.25)
		(keepout
			(tracks allowed)
			(vias allowed)
			(pads allowed)
			(copperpour allowed)
			(footprints allowed)
		)
		(placement
			(enabled no)
			(sheetname "")
		)
		(fill
			(thermal_gap 0.5)
			(thermal_bridge_width 0.5)
			(island_removal_mode 0)
		)
		(polygon
			(pts
				(xy 50.746152 -201.846942) (xy 50.746152 -201.297286) (xy 51.376072 -201.297286) (xy 51.376072 -201.846942)
			)
		)
	)
	(zone
		(layer "In11.Cu")
		(hatch none 0.5)
		(connect_pads
			(clearance 0)
		)
		(min_thickness 0.25)
		(keepout
			(tracks allowed)
			(vias allowed)
			(pads allowed)
			(copperpour allowed)
			(footprints allowed)
		)
		(placement
			(enabled no)
			(sheetname "")
		)
		(fill
			(thermal_gap 0.5)
			(thermal_bridge_width 0.5)
			(island_removal_mode 0)
		)
		(polygon
			(pts
				(xy 425.11091 -196.414644) (xy 425.11091 -196.690234) (xy 424.55211 -196.690234) (xy 424.55211 -196.414644)
			)
		)
	)
	(zone
		(layer "In11.Cu")
		(hatch none 0.5)
		(connect_pads
			(clearance 0)
		)
		(min_thickness 0.25)
		(keepout
			(tracks allowed)
			(vias allowed)
			(pads allowed)
			(copperpour allowed)
			(footprints allowed)
		)
		(placement
			(enabled no)
			(sheetname "")
		)
		(fill
			(thermal_gap 0.5)
			(thermal_bridge_width 0.5)
			(island_removal_mode 0)
		)
		(polygon
			(pts
				(xy 298.71162 -311.496964) (xy 298.71162 -310.947308) (xy 299.34154 -310.947308) (xy 299.34154 -311.496964)
			)
		)
	)
	(zone
		(layer "In11.Cu")
		(hatch none 0.5)
		(connect_pads
			(clearance 0)
		)
		(min_thickness 0.25)
		(keepout
			(tracks allowed)
			(vias allowed)
			(pads allowed)
			(copperpour allowed)
			(footprints allowed)
		)
		(placement
			(enabled no)
			(sheetname "")
		)
		(fill
			(thermal_gap 0.5)
			(thermal_bridge_width 0.5)
			(island_removal_mode 0)
		)
		(polygon
			(pts
				(xy 50.746152 -287.69691) (xy 50.746152 -287.147254) (xy 51.376072 -287.147254) (xy 51.376072 -287.69691)
			)
		)
	)
	(zone
		(layer "In11.Cu")
		(hatch none 0.5)
		(connect_pads
			(clearance 0)
		)
		(min_thickness 0.25)
		(keepout
			(tracks allowed)
			(vias allowed)
			(pads allowed)
			(copperpour allowed)
			(footprints allowed)
		)
		(placement
			(enabled no)
			(sheetname "")
		)
		(fill
			(thermal_gap 0.5)
			(thermal_bridge_width 0.5)
			(island_removal_mode 0)
		)
		(polygon
			(pts
				(xy 162.083242 -223.614742) (xy 162.083242 -223.890332) (xy 161.524442 -223.890332) (xy 161.524442 -223.614742)
			)
		)
	)
	(zone
		(layer "In11.Cu")
		(hatch none 0.5)
		(connect_pads
			(clearance 0)
		)
		(min_thickness 0.25)
		(keepout
			(tracks allowed)
			(vias allowed)
			(pads allowed)
			(copperpour allowed)
			(footprints allowed)
		)
		(placement
			(enabled no)
			(sheetname "")
		)
		(fill
			(thermal_gap 0.5)
			(thermal_bridge_width 0.5)
			(island_removal_mode 0)
		)
		(polygon
			(pts
				(xy 177.170842 -306.064666) (xy 177.170842 -306.340256) (xy 176.612042 -306.340256) (xy 176.612042 -306.064666)
			)
		)
	)
	(zone
		(layer "In11.Cu")
		(hatch none 0.5)
		(connect_pads
			(clearance 0)
		)
		(min_thickness 0.25)
		(keepout
			(tracks allowed)
			(vias allowed)
			(pads allowed)
			(copperpour allowed)
			(footprints allowed)
		)
		(placement
			(enabled no)
			(sheetname "")
		)
		(fill
			(thermal_gap 0.5)
			(thermal_bridge_width 0.5)
			(island_removal_mode 0)
		)
		(polygon
			(pts
				(xy 268.56436 -272.400776) (xy 268.56436 -271.850358) (xy 269.12316 -271.850358) (xy 269.12316 -272.400776)
			)
		)
	)
	(zone
		(layer "In11.Cu")
		(hatch none 0.5)
		(connect_pads
			(clearance 0)
		)
		(min_thickness 0.25)
		(keepout
			(tracks allowed)
			(vias allowed)
			(pads allowed)
			(copperpour allowed)
			(footprints allowed)
		)
		(placement
			(enabled no)
			(sheetname "")
		)
		(fill
			(thermal_gap 0.5)
			(thermal_bridge_width 0.5)
			(island_removal_mode 0)
		)
		(polygon
			(pts
				(xy 202.696318 -231.3686) (xy 202.696318 -231.09301) (xy 203.255118 -231.09301) (xy 203.255118 -231.3686)
			)
		)
	)
	(zone
		(layer "In11.Cu")
		(hatch none 0.5)
		(connect_pads
			(clearance 0)
		)
		(min_thickness 0.25)
		(keepout
			(tracks allowed)
			(vias allowed)
			(pads allowed)
			(copperpour allowed)
			(footprints allowed)
		)
		(placement
			(enabled no)
			(sheetname "")
		)
		(fill
			(thermal_gap 0.5)
			(thermal_bridge_width 0.5)
			(island_removal_mode 0)
		)
		(polygon
			(pts
				(xy 268.56436 -276.650704) (xy 268.56436 -276.100286) (xy 269.12316 -276.100286) (xy 269.12316 -276.650704)
			)
		)
	)
	(zone
		(layer "In11.Cu")
		(hatch none 0.5)
		(connect_pads
			(clearance 0)
		)
		(min_thickness 0.25)
		(keepout
			(tracks allowed)
			(vias allowed)
			(pads allowed)
			(copperpour allowed)
			(footprints allowed)
		)
		(placement
			(enabled no)
			(sheetname "")
		)
		(fill
			(thermal_gap 0.5)
			(thermal_bridge_width 0.5)
			(island_removal_mode 0)
		)
		(polygon
			(pts
				(xy 202.696318 -307.018436) (xy 202.696318 -306.742846) (xy 203.255118 -306.742846) (xy 203.255118 -307.018436)
			)
		)
	)
	(zone
		(layer "In11.Cu")
		(hatch none 0.5)
		(connect_pads
			(clearance 0)
		)
		(min_thickness 0.25)
		(keepout
			(tracks allowed)
			(vias allowed)
			(pads allowed)
			(copperpour allowed)
			(footprints allowed)
		)
		(placement
			(enabled no)
			(sheetname "")
		)
		(fill
			(thermal_gap 0.5)
			(thermal_bridge_width 0.5)
			(island_removal_mode 0)
		)
		(polygon
			(pts
				(xy 450.636386 -204.168502) (xy 450.636386 -203.892912) (xy 451.195186 -203.892912) (xy 451.195186 -204.168502)
			)
		)
	)
	(zone
		(layer "In11.Cu")
		(hatch none 0.5)
		(connect_pads
			(clearance 0)
		)
		(min_thickness 0.25)
		(keepout
			(tracks allowed)
			(vias allowed)
			(pads allowed)
			(copperpour allowed)
			(footprints allowed)
		)
		(placement
			(enabled no)
			(sheetname "")
		)
		(fill
			(thermal_gap 0.5)
			(thermal_bridge_width 0.5)
			(island_removal_mode 0)
		)
		(polygon
			(pts
				(xy 173.070774 -223.614742) (xy 173.070774 -223.890332) (xy 172.511974 -223.890332) (xy 172.511974 -223.614742)
			)
		)
	)
	(zone
		(layer "In11.Cu")
		(hatch none 0.5)
		(connect_pads
			(clearance 0)
		)
		(min_thickness 0.25)
		(keepout
			(tracks allowed)
			(vias allowed)
			(pads allowed)
			(copperpour allowed)
			(footprints allowed)
		)
		(placement
			(enabled no)
			(sheetname "")
		)
		(fill
			(thermal_gap 0.5)
			(thermal_bridge_width 0.5)
			(island_removal_mode 0)
		)
		(polygon
			(pts
				(xy 46.646084 -213.746842) (xy 46.646084 -213.197186) (xy 47.276004 -213.197186) (xy 47.276004 -213.746842)
			)
		)
	)
	(zone
		(layer "In11.Cu")
		(hatch none 0.5)
		(connect_pads
			(clearance 0)
		)
		(min_thickness 0.25)
		(keepout
			(tracks allowed)
			(vias allowed)
			(pads allowed)
			(copperpour allowed)
			(footprints allowed)
		)
		(placement
			(enabled no)
			(sheetname "")
		)
		(fill
			(thermal_gap 0.5)
			(thermal_bridge_width 0.5)
			(island_removal_mode 0)
		)
		(polygon
			(pts
				(xy 203.245974 -227.014786) (xy 203.245974 -227.290376) (xy 202.687174 -227.290376) (xy 202.687174 -227.014786)
			)
		)
	)
	(zone
		(layer "In11.Cu")
		(hatch none 0.5)
		(connect_pads
			(clearance 0)
		)
		(min_thickness 0.25)
		(keepout
			(tracks allowed)
			(vias allowed)
			(pads allowed)
			(copperpour allowed)
			(footprints allowed)
		)
		(placement
			(enabled no)
			(sheetname "")
		)
		(fill
			(thermal_gap 0.5)
			(thermal_bridge_width 0.5)
			(island_removal_mode 0)
		)
		(polygon
			(pts
				(xy 172.994574 -260.164834) (xy 172.994574 -260.440424) (xy 172.435774 -260.440424) (xy 172.435774 -260.164834)
			)
		)
	)
	(zone
		(layer "In11.Cu")
		(hatch none 0.5)
		(connect_pads
			(clearance 0)
		)
		(min_thickness 0.25)
		(keepout
			(tracks allowed)
			(vias allowed)
			(pads allowed)
			(copperpour allowed)
			(footprints allowed)
		)
		(placement
			(enabled no)
			(sheetname "")
		)
		(fill
			(thermal_gap 0.5)
			(thermal_bridge_width 0.5)
			(island_removal_mode 0)
		)
		(polygon
			(pts
				(xy 283.636212 -269.019528) (xy 283.636212 -268.437868) (xy 284.195012 -268.437868) (xy 284.195012 -269.019528)
			)
		)
	)
	(zone
		(layer "In11.Cu")
		(hatch none 0.5)
		(connect_pads
			(clearance 0)
		)
		(min_thickness 0.25)
		(keepout
			(tracks allowed)
			(vias allowed)
			(pads allowed)
			(copperpour allowed)
			(footprints allowed)
		)
		(placement
			(enabled no)
			(sheetname "")
		)
		(fill
			(thermal_gap 0.5)
			(thermal_bridge_width 0.5)
			(island_removal_mode 0)
		)
		(polygon
			(pts
				(xy 268.56436 -298.750736) (xy 268.56436 -298.200318) (xy 269.12316 -298.200318) (xy 269.12316 -298.750736)
			)
		)
	)
	(zone
		(layer "In11.Cu")
		(hatch none 0.5)
		(connect_pads
			(clearance 0)
		)
		(min_thickness 0.25)
		(keepout
			(tracks allowed)
			(vias allowed)
			(pads allowed)
			(copperpour allowed)
			(footprints allowed)
		)
		(placement
			(enabled no)
			(sheetname "")
		)
		(fill
			(thermal_gap 0.5)
			(thermal_bridge_width 0.5)
			(island_removal_mode 0)
		)
		(polygon
			(pts
				(xy 202.696318 -223.718374) (xy 202.696318 -223.442784) (xy 203.255118 -223.442784) (xy 203.255118 -223.718374)
			)
		)
	)
	(zone
		(layer "In11.Cu")
		(hatch none 0.5)
		(connect_pads
			(clearance 0)
		)
		(min_thickness 0.25)
		(keepout
			(tracks allowed)
			(vias allowed)
			(pads allowed)
			(copperpour allowed)
			(footprints allowed)
		)
		(placement
			(enabled no)
			(sheetname "")
		)
		(fill
			(thermal_gap 0.5)
			(thermal_bridge_width 0.5)
			(island_removal_mode 0)
		)
		(polygon
			(pts
				(xy 177.170842 -289.0647) (xy 177.170842 -289.34029) (xy 176.612042 -289.34029) (xy 176.612042 -289.0647)
			)
		)
	)
	(zone
		(layer "In11.Cu")
		(hatch none 0.5)
		(connect_pads
			(clearance 0)
		)
		(min_thickness 0.25)
		(keepout
			(tracks allowed)
			(vias allowed)
			(pads allowed)
			(copperpour allowed)
			(footprints allowed)
		)
		(placement
			(enabled no)
			(sheetname "")
		)
		(fill
			(thermal_gap 0.5)
			(thermal_bridge_width 0.5)
			(island_removal_mode 0)
		)
		(polygon
			(pts
				(xy 50.746152 -203.546964) (xy 50.746152 -202.997308) (xy 51.376072 -202.997308) (xy 51.376072 -203.546964)
			)
		)
	)
	(zone
		(layer "In11.Cu")
		(hatch none 0.5)
		(connect_pads
			(clearance 0)
		)
		(min_thickness 0.25)
		(keepout
			(tracks allowed)
			(vias allowed)
			(pads allowed)
			(copperpour allowed)
			(footprints allowed)
		)
		(placement
			(enabled no)
			(sheetname "")
		)
		(fill
			(thermal_gap 0.5)
			(thermal_bridge_width 0.5)
			(island_removal_mode 0)
		)
		(polygon
			(pts
				(xy 450.636386 -201.618596) (xy 450.636386 -201.343006) (xy 451.195186 -201.343006) (xy 451.195186 -201.618596)
			)
		)
	)
	(zone
		(layer "In11.Cu")
		(hatch none 0.5)
		(connect_pads
			(clearance 0)
		)
		(min_thickness 0.25)
		(keepout
			(tracks allowed)
			(vias allowed)
			(pads allowed)
			(copperpour allowed)
			(footprints allowed)
		)
		(placement
			(enabled no)
			(sheetname "")
		)
		(fill
			(thermal_gap 0.5)
			(thermal_bridge_width 0.5)
			(island_removal_mode 0)
		)
		(polygon
			(pts
				(xy 202.696318 -274.442936) (xy 203.255118 -274.442936) (xy 203.255118 -274.718526) (xy 203.255118 -275.05787)
				(xy 202.576938 -275.05787) (xy 202.576938 -274.442936)
			)
		)
	)
	(zone
		(layer "In11.Cu")
		(hatch none 0.5)
		(connect_pads
			(clearance 0)
		)
		(min_thickness 0.25)
		(keepout
			(tracks allowed)
			(vias allowed)
			(pads allowed)
			(copperpour allowed)
			(footprints allowed)
		)
		(placement
			(enabled no)
			(sheetname "")
		)
		(fill
			(thermal_gap 0.5)
			(thermal_bridge_width 0.5)
			(island_removal_mode 0)
		)
		(polygon
			(pts
				(xy 172.521118 -290.868608) (xy 172.521118 -290.593018) (xy 173.079918 -290.593018) (xy 173.079918 -290.868608)
			)
		)
	)
	(zone
		(layer "In11.Cu")
		(hatch none 0.5)
		(connect_pads
			(clearance 0)
		)
		(min_thickness 0.25)
		(keepout
			(tracks allowed)
			(vias allowed)
			(pads allowed)
			(copperpour allowed)
			(footprints allowed)
		)
		(placement
			(enabled no)
			(sheetname "")
		)
		(fill
			(thermal_gap 0.5)
			(thermal_bridge_width 0.5)
			(island_removal_mode 0)
		)
		(polygon
			(pts
				(xy 428.004986 -268.768576) (xy 428.004986 -268.492986) (xy 428.563786 -268.492986) (xy 428.563786 -268.768576)
			)
		)
	)
	(zone
		(layer "In11.Cu")
		(hatch none 0.5)
		(connect_pads
			(clearance 0)
		)
		(min_thickness 0.25)
		(keepout
			(tracks allowed)
			(vias allowed)
			(pads allowed)
			(copperpour allowed)
			(footprints allowed)
		)
		(placement
			(enabled no)
			(sheetname "")
		)
		(fill
			(thermal_gap 0.5)
			(thermal_bridge_width 0.5)
			(island_removal_mode 0)
		)
		(polygon
			(pts
				(xy 424.561254 -246.668544) (xy 424.561254 -246.392954) (xy 425.120054 -246.392954) (xy 425.120054 -246.668544)
			)
		)
	)
	(zone
		(layer "In11.Cu")
		(hatch none 0.5)
		(connect_pads
			(clearance 0)
		)
		(min_thickness 0.25)
		(keepout
			(tracks allowed)
			(vias allowed)
			(pads allowed)
			(copperpour allowed)
			(footprints allowed)
		)
		(placement
			(enabled no)
			(sheetname "")
		)
		(fill
			(thermal_gap 0.5)
			(thermal_bridge_width 0.5)
			(island_removal_mode 0)
		)
		(polygon
			(pts
				(xy 421.010842 -312.014616) (xy 421.010842 -312.290206) (xy 420.452042 -312.290206) (xy 420.452042 -312.014616)
			)
		)
	)
	(zone
		(layer "In11.Cu")
		(hatch none 0.5)
		(connect_pads
			(clearance 0)
		)
		(min_thickness 0.25)
		(keepout
			(tracks allowed)
			(vias allowed)
			(pads allowed)
			(copperpour allowed)
			(footprints allowed)
		)
		(placement
			(enabled no)
			(sheetname "")
		)
		(fill
			(thermal_gap 0.5)
			(thermal_bridge_width 0.5)
			(island_removal_mode 0)
		)
		(polygon
			(pts
				(xy 46.646084 -307.246782) (xy 46.646084 -306.697126) (xy 47.276004 -306.697126) (xy 47.276004 -307.246782)
			)
		)
	)
	(zone
		(layer "In11.Cu")
		(hatch none 0.5)
		(connect_pads
			(clearance 0)
		)
		(min_thickness 0.25)
		(keepout
			(tracks allowed)
			(vias allowed)
			(pads allowed)
			(copperpour allowed)
			(footprints allowed)
		)
		(placement
			(enabled no)
			(sheetname "")
		)
		(fill
			(thermal_gap 0.5)
			(thermal_bridge_width 0.5)
			(island_removal_mode 0)
		)
		(polygon
			(pts
				(xy 20.570952 -218.846908) (xy 20.570952 -218.297252) (xy 21.200872 -218.297252) (xy 21.200872 -218.846908)
			)
		)
	)
	(zone
		(layer "In11.Cu")
		(hatch none 0.5)
		(connect_pads
			(clearance 0)
		)
		(min_thickness 0.25)
		(keepout
			(tracks allowed)
			(vias allowed)
			(pads allowed)
			(copperpour allowed)
			(footprints allowed)
		)
		(placement
			(enabled no)
			(sheetname "")
		)
		(fill
			(thermal_gap 0.5)
			(thermal_bridge_width 0.5)
			(island_removal_mode 0)
		)
		(polygon
			(pts
				(xy 428.554642 -245.714774) (xy 428.554642 -245.990364) (xy 427.995842 -245.990364) (xy 427.995842 -245.714774)
			)
		)
	)
	(zone
		(layer "In11.Cu")
		(hatch none 0.5)
		(connect_pads
			(clearance 0)
		)
		(min_thickness 0.25)
		(keepout
			(tracks allowed)
			(vias allowed)
			(pads allowed)
			(copperpour allowed)
			(footprints allowed)
		)
		(placement
			(enabled no)
			(sheetname "")
		)
		(fill
			(thermal_gap 0.5)
			(thermal_bridge_width 0.5)
			(island_removal_mode 0)
		)
		(polygon
			(pts
				(xy 104.04348 -352.229928) (xy 104.04348 -351.137728) (xy 105.83672 -351.137728) (xy 105.83672 -352.229928)
			)
		)
	)
	(zone
		(layer "In11.Cu")
		(hatch none 0.5)
		(connect_pads
			(clearance 0)
		)
		(min_thickness 0.25)
		(keepout
			(tracks allowed)
			(vias allowed)
			(pads allowed)
			(copperpour allowed)
			(footprints allowed)
		)
		(placement
			(enabled no)
			(sheetname "")
		)
		(fill
			(thermal_gap 0.5)
			(thermal_bridge_width 0.5)
			(island_removal_mode 0)
		)
		(polygon
			(pts
				(xy 421.010842 -227.86467) (xy 421.010842 -228.14026) (xy 420.452042 -228.14026) (xy 420.452042 -227.86467)
			)
		)
	)
	(zone
		(layer "In11.Cu")
		(hatch none 0.5)
		(connect_pads
			(clearance 0)
		)
		(min_thickness 0.25)
		(keepout
			(tracks allowed)
			(vias allowed)
			(pads allowed)
			(copperpour allowed)
			(footprints allowed)
		)
		(placement
			(enabled no)
			(sheetname "")
		)
		(fill
			(thermal_gap 0.5)
			(thermal_bridge_width 0.5)
			(island_removal_mode 0)
		)
		(polygon
			(pts
				(xy 46.646084 -314.896754) (xy 46.646084 -314.347098) (xy 47.276004 -314.347098) (xy 47.276004 -314.896754)
			)
		)
	)
	(zone
		(layer "In11.Cu")
		(hatch none 0.5)
		(connect_pads
			(clearance 0)
		)
		(min_thickness 0.25)
		(keepout
			(tracks allowed)
			(vias allowed)
			(pads allowed)
			(copperpour allowed)
			(footprints allowed)
		)
		(placement
			(enabled no)
			(sheetname "")
		)
		(fill
			(thermal_gap 0.5)
			(thermal_bridge_width 0.5)
			(island_removal_mode 0)
		)
		(polygon
			(pts
				(xy 421.010842 -299.264832) (xy 421.010842 -299.540422) (xy 420.452042 -299.540422) (xy 420.452042 -299.264832)
			)
		)
	)
	(zone
		(layer "In11.Cu")
		(hatch none 0.5)
		(connect_pads
			(clearance 0)
		)
		(min_thickness 0.25)
		(keepout
			(tracks allowed)
			(vias allowed)
			(pads allowed)
			(copperpour allowed)
			(footprints allowed)
		)
		(placement
			(enabled no)
			(sheetname "")
		)
		(fill
			(thermal_gap 0.5)
			(thermal_bridge_width 0.5)
			(island_removal_mode 0)
		)
		(polygon
			(pts
				(xy 188.158374 -211.714842) (xy 188.158374 -211.990432) (xy 187.599574 -211.990432) (xy 187.599574 -211.714842)
			)
		)
	)
	(zone
		(layer "In11.Cu")
		(hatch none 0.5)
		(connect_pads
			(clearance 0)
		)
		(min_thickness 0.25)
		(keepout
			(tracks allowed)
			(vias allowed)
			(pads allowed)
			(copperpour allowed)
			(footprints allowed)
		)
		(placement
			(enabled no)
			(sheetname "")
		)
		(fill
			(thermal_gap 0.5)
			(thermal_bridge_width 0.5)
			(island_removal_mode 0)
		)
		(polygon
			(pts
				(xy 173.070774 -279.714706) (xy 173.070774 -279.990296) (xy 172.511974 -279.990296) (xy 172.511974 -279.714706)
			)
		)
	)
	(zone
		(layer "In11.Cu")
		(hatch none 0.5)
		(connect_pads
			(clearance 0)
		)
		(min_thickness 0.25)
		(keepout
			(tracks allowed)
			(vias allowed)
			(pads allowed)
			(copperpour allowed)
			(footprints allowed)
		)
		(placement
			(enabled no)
			(sheetname "")
		)
		(fill
			(thermal_gap 0.5)
			(thermal_bridge_width 0.5)
			(island_removal_mode 0)
		)
		(polygon
			(pts
				(xy 202.696318 -280.668476) (xy 202.696318 -280.392886) (xy 203.255118 -280.392886) (xy 203.255118 -280.668476)
			)
		)
	)
	(zone
		(layer "In11.Cu")
		(hatch none 0.5)
		(connect_pads
			(clearance 0)
		)
		(min_thickness 0.25)
		(keepout
			(tracks allowed)
			(vias allowed)
			(pads allowed)
			(copperpour allowed)
			(footprints allowed)
		)
		(placement
			(enabled no)
			(sheetname "")
		)
		(fill
			(thermal_gap 0.5)
			(thermal_bridge_width 0.5)
			(island_removal_mode 0)
		)
		(polygon
			(pts
				(xy 268.56436 -274.100544) (xy 268.56436 -273.550126) (xy 269.12316 -273.550126) (xy 269.12316 -274.100544)
			)
		)
	)
	(zone
		(layer "In11.Cu")
		(hatch none 0.5)
		(connect_pads
			(clearance 0)
		)
		(min_thickness 0.25)
		(keepout
			(tracks allowed)
			(vias allowed)
			(pads allowed)
			(copperpour allowed)
			(footprints allowed)
		)
		(placement
			(enabled no)
			(sheetname "")
		)
		(fill
			(thermal_gap 0.5)
			(thermal_bridge_width 0.5)
			(island_removal_mode 0)
		)
		(polygon
			(pts
				(xy 172.521118 -287.468564) (xy 172.521118 -287.192974) (xy 173.079918 -287.192974) (xy 173.079918 -287.468564)
			)
		)
	)
	(zone
		(layer "In11.Cu")
		(hatch none 0.5)
		(connect_pads
			(clearance 0)
		)
		(min_thickness 0.25)
		(keepout
			(tracks allowed)
			(vias allowed)
			(pads allowed)
			(copperpour allowed)
			(footprints allowed)
		)
		(placement
			(enabled no)
			(sheetname "")
		)
		(fill
			(thermal_gap 0.5)
			(thermal_bridge_width 0.5)
			(island_removal_mode 0)
		)
		(polygon
			(pts
				(xy 176.621186 -199.068436) (xy 176.621186 -198.792846) (xy 177.179986 -198.792846) (xy 177.179986 -199.068436)
			)
		)
	)
	(zone
		(layer "In11.Cu")
		(hatch none 0.5)
		(connect_pads
			(clearance 0)
		)
		(min_thickness 0.25)
		(keepout
			(tracks allowed)
			(vias allowed)
			(pads allowed)
			(copperpour allowed)
			(footprints allowed)
		)
		(placement
			(enabled no)
			(sheetname "")
		)
		(fill
			(thermal_gap 0.5)
			(thermal_bridge_width 0.5)
			(island_removal_mode 0)
		)
		(polygon
			(pts
				(xy 203.245974 -198.964804) (xy 203.245974 -199.240394) (xy 202.687174 -199.240394) (xy 202.687174 -198.964804)
			)
		)
	)
	(zone
		(layer "In11.Cu")
		(hatch none 0.5)
		(connect_pads
			(clearance 0)
		)
		(min_thickness 0.25)
		(keepout
			(tracks allowed)
			(vias allowed)
			(pads allowed)
			(copperpour allowed)
			(footprints allowed)
		)
		(placement
			(enabled no)
			(sheetname "")
		)
		(fill
			(thermal_gap 0.5)
			(thermal_bridge_width 0.5)
			(island_removal_mode 0)
		)
		(polygon
			(pts
				(xy 425.11091 -299.264578) (xy 425.11091 -299.540168) (xy 424.55211 -299.540168) (xy 424.55211 -299.264578)
			)
		)
	)
	(zone
		(layer "In11.Cu")
		(hatch none 0.5)
		(connect_pads
			(clearance 0)
		)
		(min_thickness 0.25)
		(keepout
			(tracks allowed)
			(vias allowed)
			(pads allowed)
			(copperpour allowed)
			(footprints allowed)
		)
		(placement
			(enabled no)
			(sheetname "")
		)
		(fill
			(thermal_gap 0.5)
			(thermal_bridge_width 0.5)
			(island_removal_mode 0)
		)
		(polygon
			(pts
				(xy 268.56436 -274.950682) (xy 268.56436 -274.400264) (xy 269.12316 -274.400264) (xy 269.12316 -274.950682)
			)
		)
	)
	(zone
		(layer "In11.Cu")
		(hatch none 0.5)
		(connect_pads
			(clearance 0)
		)
		(min_thickness 0.25)
		(keepout
			(tracks allowed)
			(vias allowed)
			(pads allowed)
			(copperpour allowed)
			(footprints allowed)
		)
		(placement
			(enabled no)
			(sheetname "")
		)
		(fill
			(thermal_gap 0.5)
			(thermal_bridge_width 0.5)
			(island_removal_mode 0)
		)
		(polygon
			(pts
				(xy 173.070774 -227.86467) (xy 173.070774 -228.14026) (xy 172.511974 -228.14026) (xy 172.511974 -227.86467)
			)
		)
	)
	(zone
		(layer "In11.Cu")
		(hatch none 0.5)
		(connect_pads
			(clearance 0)
		)
		(min_thickness 0.25)
		(keepout
			(tracks allowed)
			(vias allowed)
			(pads allowed)
			(copperpour allowed)
			(footprints allowed)
		)
		(placement
			(enabled no)
			(sheetname "")
		)
		(fill
			(thermal_gap 0.5)
			(thermal_bridge_width 0.5)
			(island_removal_mode 0)
		)
		(polygon
			(pts
				(xy 177.170842 -309.46471) (xy 177.170842 -309.7403) (xy 176.612042 -309.7403) (xy 176.612042 -309.46471)
			)
		)
	)
	(zone
		(layer "In11.Cu")
		(hatch none 0.5)
		(connect_pads
			(clearance 0)
		)
		(min_thickness 0.25)
		(keepout
			(tracks allowed)
			(vias allowed)
			(pads allowed)
			(copperpour allowed)
			(footprints allowed)
		)
		(placement
			(enabled no)
			(sheetname "")
		)
		(fill
			(thermal_gap 0.5)
			(thermal_bridge_width 0.5)
			(island_removal_mode 0)
		)
		(polygon
			(pts
				(xy 168.0845 -358.569768) (xy 168.0845 -356.796848) (xy 172.4279 -356.796848) (xy 172.4279 -358.569768)
			)
		)
	)
	(zone
		(layer "In11.Cu")
		(hatch none 0.5)
		(connect_pads
			(clearance 0)
		)
		(min_thickness 0.25)
		(keepout
			(tracks allowed)
			(vias allowed)
			(pads allowed)
			(copperpour allowed)
			(footprints allowed)
		)
		(placement
			(enabled no)
			(sheetname "")
		)
		(fill
			(thermal_gap 0.5)
			(thermal_bridge_width 0.5)
			(island_removal_mode 0)
		)
		(polygon
			(pts
				(xy 50.746152 -248.596912) (xy 50.746152 -248.047256) (xy 51.376072 -248.047256) (xy 51.376072 -248.596912)
			)
		)
	)
	(zone
		(layer "In11.Cu")
		(hatch none 0.5)
		(connect_pads
			(clearance 0)
		)
		(min_thickness 0.25)
		(keepout
			(tracks allowed)
			(vias allowed)
			(pads allowed)
			(copperpour allowed)
			(footprints allowed)
		)
		(placement
			(enabled no)
			(sheetname "")
		)
		(fill
			(thermal_gap 0.5)
			(thermal_bridge_width 0.5)
			(island_removal_mode 0)
		)
		(polygon
			(pts
				(xy 50.771552 -289.396932) (xy 50.771552 -288.847276) (xy 51.401472 -288.847276) (xy 51.401472 -289.396932)
			)
		)
	)
	(zone
		(layer "In11.Cu")
		(hatch none 0.5)
		(connect_pads
			(clearance 0)
		)
		(min_thickness 0.25)
		(keepout
			(tracks allowed)
			(vias allowed)
			(pads allowed)
			(copperpour allowed)
			(footprints allowed)
		)
		(placement
			(enabled no)
			(sheetname "")
		)
		(fill
			(thermal_gap 0.5)
			(thermal_bridge_width 0.5)
			(island_removal_mode 0)
		)
		(polygon
			(pts
				(xy 294.586152 -273.24685) (xy 294.586152 -272.697194) (xy 295.216072 -272.697194) (xy 295.216072 -273.24685)
			)
		)
	)
	(zone
		(layer "In11.Cu")
		(hatch none 0.5)
		(connect_pads
			(clearance 0)
		)
		(min_thickness 0.25)
		(keepout
			(tracks allowed)
			(vias allowed)
			(pads allowed)
			(copperpour allowed)
			(footprints allowed)
		)
		(placement
			(enabled no)
			(sheetname "")
		)
		(fill
			(thermal_gap 0.5)
			(thermal_bridge_width 0.5)
			(island_removal_mode 0)
		)
		(polygon
			(pts
				(xy 172.521118 -248.368566) (xy 172.521118 -248.092976) (xy 173.079918 -248.092976) (xy 173.079918 -248.368566)
			)
		)
	)
	(zone
		(layer "In11.Cu")
		(hatch none 0.5)
		(connect_pads
			(clearance 0)
		)
		(min_thickness 0.25)
		(keepout
			(tracks allowed)
			(vias allowed)
			(pads allowed)
			(copperpour allowed)
			(footprints allowed)
		)
		(placement
			(enabled no)
			(sheetname "")
		)
		(fill
			(thermal_gap 0.5)
			(thermal_bridge_width 0.5)
			(island_removal_mode 0)
		)
		(polygon
			(pts
				(xy 176.621186 -207.568546) (xy 176.621186 -207.292956) (xy 177.179986 -207.292956) (xy 177.179986 -207.568546)
			)
		)
	)
	(zone
		(layer "In11.Cu")
		(hatch none 0.5)
		(connect_pads
			(clearance 0)
		)
		(min_thickness 0.25)
		(keepout
			(tracks allowed)
			(vias allowed)
			(pads allowed)
			(copperpour allowed)
			(footprints allowed)
		)
		(placement
			(enabled no)
			(sheetname "")
		)
		(fill
			(thermal_gap 0.5)
			(thermal_bridge_width 0.5)
			(island_removal_mode 0)
		)
		(polygon
			(pts
				(xy 173.070774 -225.314764) (xy 173.070774 -225.590354) (xy 172.511974 -225.590354) (xy 172.511974 -225.314764)
			)
		)
	)
	(zone
		(layer "In11.Cu")
		(hatch none 0.5)
		(connect_pads
			(clearance 0)
		)
		(min_thickness 0.25)
		(keepout
			(tracks allowed)
			(vias allowed)
			(pads allowed)
			(copperpour allowed)
			(footprints allowed)
		)
		(placement
			(enabled no)
			(sheetname "")
		)
		(fill
			(thermal_gap 0.5)
			(thermal_bridge_width 0.5)
			(island_removal_mode 0)
		)
		(polygon
			(pts
				(xy 268.51102 -227.346764) (xy 268.51102 -226.797108) (xy 269.14094 -226.797108) (xy 269.14094 -227.346764)
			)
		)
	)
	(zone
		(layer "In11.Cu")
		(hatch none 0.5)
		(connect_pads
			(clearance 0)
		)
		(min_thickness 0.25)
		(keepout
			(tracks allowed)
			(vias allowed)
			(pads allowed)
			(copperpour allowed)
			(footprints allowed)
		)
		(placement
			(enabled no)
			(sheetname "")
		)
		(fill
			(thermal_gap 0.5)
			(thermal_bridge_width 0.5)
			(island_removal_mode 0)
		)
		(polygon
			(pts
				(xy 298.68622 -287.69691) (xy 298.68622 -287.147254) (xy 299.31614 -287.147254) (xy 299.31614 -287.69691)
			)
		)
	)
	(zone
		(layer "In11.Cu")
		(hatch none 0.5)
		(connect_pads
			(clearance 0)
		)
		(min_thickness 0.25)
		(keepout
			(tracks allowed)
			(vias allowed)
			(pads allowed)
			(copperpour allowed)
			(footprints allowed)
		)
		(placement
			(enabled no)
			(sheetname "")
		)
		(fill
			(thermal_gap 0.5)
			(thermal_bridge_width 0.5)
			(island_removal_mode 0)
		)
		(polygon
			(pts
				(xy 172.521118 -298.51858) (xy 172.521118 -298.24299) (xy 173.079918 -298.24299) (xy 173.079918 -298.51858)
			)
		)
	)
	(zone
		(layer "In11.Cu")
		(hatch none 0.5)
		(connect_pads
			(clearance 0)
		)
		(min_thickness 0.25)
		(keepout
			(tracks allowed)
			(vias allowed)
			(pads allowed)
			(copperpour allowed)
			(footprints allowed)
		)
		(placement
			(enabled no)
			(sheetname "")
		)
		(fill
			(thermal_gap 0.5)
			(thermal_bridge_width 0.5)
			(island_removal_mode 0)
		)
		(polygon
			(pts
				(xy 294.586152 -229.046786) (xy 294.586152 -228.49713) (xy 295.216072 -228.49713) (xy 295.216072 -229.046786)
			)
		)
	)
	(zone
		(layer "In11.Cu")
		(hatch none 0.5)
		(connect_pads
			(clearance 0)
		)
		(min_thickness 0.25)
		(keepout
			(tracks allowed)
			(vias allowed)
			(pads allowed)
			(copperpour allowed)
			(footprints allowed)
		)
		(placement
			(enabled no)
			(sheetname "")
		)
		(fill
			(thermal_gap 0.5)
			(thermal_bridge_width 0.5)
			(island_removal_mode 0)
		)
		(polygon
			(pts
				(xy 425.11091 -230.41483) (xy 425.11091 -230.69042) (xy 424.55211 -230.69042) (xy 424.55211 -230.41483)
			)
		)
	)
	(zone
		(layer "In11.Cu")
		(hatch none 0.5)
		(connect_pads
			(clearance 0)
		)
		(min_thickness 0.25)
		(keepout
			(tracks allowed)
			(vias allowed)
			(pads allowed)
			(copperpour allowed)
			(footprints allowed)
		)
		(placement
			(enabled no)
			(sheetname "")
		)
		(fill
			(thermal_gap 0.5)
			(thermal_bridge_width 0.5)
			(island_removal_mode 0)
		)
		(polygon
			(pts
				(xy 420.461186 -203.318618) (xy 420.461186 -203.043028) (xy 421.019986 -203.043028) (xy 421.019986 -203.318618)
			)
		)
	)
	(zone
		(layer "In11.Cu")
		(hatch none 0.5)
		(connect_pads
			(clearance 0)
		)
		(min_thickness 0.25)
		(keepout
			(tracks allowed)
			(vias allowed)
			(pads allowed)
			(copperpour allowed)
			(footprints allowed)
		)
		(placement
			(enabled no)
			(sheetname "")
		)
		(fill
			(thermal_gap 0.5)
			(thermal_bridge_width 0.5)
			(island_removal_mode 0)
		)
		(polygon
			(pts
				(xy 451.186042 -211.714842) (xy 451.186042 -211.990432) (xy 450.627242 -211.990432) (xy 450.627242 -211.714842)
			)
		)
	)
	(zone
		(layer "In11.Cu")
		(hatch none 0.5)
		(connect_pads
			(clearance 0)
		)
		(min_thickness 0.25)
		(keepout
			(tracks allowed)
			(vias allowed)
			(pads allowed)
			(copperpour allowed)
			(footprints allowed)
		)
		(placement
			(enabled no)
			(sheetname "")
		)
		(fill
			(thermal_gap 0.5)
			(thermal_bridge_width 0.5)
			(island_removal_mode 0)
		)
		(polygon
			(pts
				(xy 126.32182 -342.237568) (xy 126.32182 -339.570568) (xy 130.20802 -339.570568) (xy 130.20802 -342.237568)
			)
		)
	)
	(zone
		(layer "In11.Cu")
		(hatch none 0.5)
		(connect_pads
			(clearance 0)
		)
		(min_thickness 0.25)
		(keepout
			(tracks allowed)
			(vias allowed)
			(pads allowed)
			(copperpour allowed)
			(footprints allowed)
		)
		(placement
			(enabled no)
			(sheetname "")
		)
		(fill
			(thermal_gap 0.5)
			(thermal_bridge_width 0.5)
			(island_removal_mode 0)
		)
		(polygon
			(pts
				(xy 191.708786 -279.818592) (xy 191.708786 -279.543002) (xy 192.267586 -279.543002) (xy 192.267586 -279.818592)
			)
		)
	)
	(zone
		(layer "In11.Cu")
		(hatch none 0.5)
		(connect_pads
			(clearance 0)
		)
		(min_thickness 0.25)
		(keepout
			(tracks allowed)
			(vias allowed)
			(pads allowed)
			(copperpour allowed)
			(footprints allowed)
		)
		(placement
			(enabled no)
			(sheetname "")
		)
		(fill
			(thermal_gap 0.5)
			(thermal_bridge_width 0.5)
			(island_removal_mode 0)
		)
		(polygon
			(pts
				(xy 454.736454 -267.918438) (xy 454.736454 -267.642848) (xy 455.295254 -267.642848) (xy 455.295254 -267.918438)
			)
		)
	)
	(zone
		(layer "In11.Cu")
		(hatch none 0.5)
		(connect_pads
			(clearance 0)
		)
		(min_thickness 0.25)
		(keepout
			(tracks allowed)
			(vias allowed)
			(pads allowed)
			(copperpour allowed)
			(footprints allowed)
		)
		(placement
			(enabled no)
			(sheetname "")
		)
		(fill
			(thermal_gap 0.5)
			(thermal_bridge_width 0.5)
			(island_removal_mode 0)
		)
		(polygon
			(pts
				(xy 268.558518 -287.692338) (xy 268.558518 -287.15208) (xy 269.126462 -287.15208) (xy 269.426944 -287.15208)
				(xy 269.531084 -287.25622) (xy 269.531084 -287.52165) (xy 269.360396 -287.692338) (xy 269.117318 -287.692338)
			)
		)
	)
	(zone
		(layer "In11.Cu")
		(hatch none 0.5)
		(connect_pads
			(clearance 0)
		)
		(min_thickness 0.25)
		(keepout
			(tracks allowed)
			(vias allowed)
			(pads allowed)
			(copperpour allowed)
			(footprints allowed)
		)
		(placement
			(enabled no)
			(sheetname "")
		)
		(fill
			(thermal_gap 0.5)
			(thermal_bridge_width 0.5)
			(island_removal_mode 0)
		)
		(polygon
			(pts
				(xy 172.521118 -306.168552) (xy 172.521118 -305.892962) (xy 173.079918 -305.892962) (xy 173.079918 -306.168552)
			)
		)
	)
	(zone
		(layer "In11.Cu")
		(hatch none 0.5)
		(connect_pads
			(clearance 0)
		)
		(min_thickness 0.25)
		(keepout
			(tracks allowed)
			(vias allowed)
			(pads allowed)
			(copperpour allowed)
			(footprints allowed)
		)
		(placement
			(enabled no)
			(sheetname "")
		)
		(fill
			(thermal_gap 0.5)
			(thermal_bridge_width 0.5)
			(island_removal_mode 0)
		)
		(polygon
			(pts
				(xy 202.696318 -198.218552) (xy 202.696318 -197.942962) (xy 203.255118 -197.942962) (xy 203.255118 -198.218552)
			)
		)
	)
	(zone
		(layer "In11.Cu")
		(hatch none 0.5)
		(connect_pads
			(clearance 0)
		)
		(min_thickness 0.25)
		(keepout
			(tracks not_allowed)
			(vias allowed)
			(pads allowed)
			(copperpour not_allowed)
			(footprints allowed)
		)
		(placement
			(enabled no)
			(sheetname "")
		)
		(fill
			(thermal_gap 0.5)
			(thermal_bridge_width 0.5)
			(island_removal_mode 0)
		)
		(polygon
			(pts
				(arc
					(start 324.1421 -428.960788)
					(mid 324.164418 -429.01467)
					(end 324.2183 -429.036988)
				)
				(arc
					(start 325.1581 -429.036988)
					(mid 325.211982 -429.01467)
					(end 325.2343 -428.960788)
				)
				(arc
					(start 325.2343 -426.419264)
					(mid 325.211982 -426.365382)
					(end 325.1581 -426.343064)
				)
				(arc
					(start 324.2183 -426.343064)
					(mid 324.164418 -426.365382)
					(end 324.1421 -426.419264)
				)
			)
		)
	)
	(zone
		(layer "In11.Cu")
		(hatch none 0.5)
		(connect_pads
			(clearance 0)
		)
		(min_thickness 0.25)
		(keepout
			(tracks allowed)
			(vias allowed)
			(pads allowed)
			(copperpour allowed)
			(footprints allowed)
		)
		(placement
			(enabled no)
			(sheetname "")
		)
		(fill
			(thermal_gap 0.5)
			(thermal_bridge_width 0.5)
			(island_removal_mode 0)
		)
		(polygon
			(pts
				(xy 451.186042 -249.964702) (xy 451.186042 -250.240292) (xy 450.627242 -250.240292) (xy 450.627242 -249.964702)
			)
		)
	)
	(zone
		(layer "In11.Cu")
		(hatch none 0.5)
		(connect_pads
			(clearance 0)
		)
		(min_thickness 0.25)
		(keepout
			(tracks allowed)
			(vias allowed)
			(pads allowed)
			(copperpour allowed)
			(footprints allowed)
		)
		(placement
			(enabled no)
			(sheetname "")
		)
		(fill
			(thermal_gap 0.5)
			(thermal_bridge_width 0.5)
			(island_removal_mode 0)
		)
		(polygon
			(pts
				(xy 173.070774 -249.114818) (xy 173.070774 -249.390408) (xy 172.511974 -249.390408) (xy 172.511974 -249.114818)
			)
		)
	)
	(zone
		(layer "In11.Cu")
		(hatch none 0.5)
		(connect_pads
			(clearance 0)
		)
		(min_thickness 0.25)
		(keepout
			(tracks allowed)
			(vias allowed)
			(pads allowed)
			(copperpour allowed)
			(footprints allowed)
		)
		(placement
			(enabled no)
			(sheetname "")
		)
		(fill
			(thermal_gap 0.5)
			(thermal_bridge_width 0.5)
			(island_removal_mode 0)
		)
		(polygon
			(pts
				(xy 420.384986 -262.818372) (xy 420.384986 -262.542782) (xy 420.943786 -262.542782) (xy 420.943786 -262.818372)
			)
		)
	)
	(zone
		(layer "In11.Cu")
		(hatch none 0.5)
		(connect_pads
			(clearance 0)
		)
		(min_thickness 0.25)
		(keepout
			(tracks allowed)
			(vias allowed)
			(pads allowed)
			(copperpour allowed)
			(footprints allowed)
		)
		(placement
			(enabled no)
			(sheetname "")
		)
		(fill
			(thermal_gap 0.5)
			(thermal_bridge_width 0.5)
			(island_removal_mode 0)
		)
		(polygon
			(pts
				(xy 420.934642 -260.164834) (xy 420.934642 -260.440424) (xy 420.375842 -260.440424) (xy 420.375842 -260.164834)
			)
		)
	)
	(zone
		(layer "In11.Cu")
		(hatch none 0.5)
		(connect_pads
			(clearance 0)
		)
		(min_thickness 0.25)
		(keepout
			(tracks allowed)
			(vias allowed)
			(pads allowed)
			(copperpour allowed)
			(footprints allowed)
		)
		(placement
			(enabled no)
			(sheetname "")
		)
		(fill
			(thermal_gap 0.5)
			(thermal_bridge_width 0.5)
			(island_removal_mode 0)
		)
		(polygon
			(pts
				(xy 294.586152 -284.296866) (xy 294.586152 -283.74721) (xy 295.216072 -283.74721) (xy 295.216072 -284.296866)
			)
		)
	)
	(zone
		(layer "In11.Cu")
		(hatch none 0.5)
		(connect_pads
			(clearance 0)
		)
		(min_thickness 0.25)
		(keepout
			(tracks allowed)
			(vias allowed)
			(pads allowed)
			(copperpour allowed)
			(footprints allowed)
		)
		(placement
			(enabled no)
			(sheetname "")
		)
		(fill
			(thermal_gap 0.5)
			(thermal_bridge_width 0.5)
			(island_removal_mode 0)
		)
		(polygon
			(pts
				(xy 424.561254 -227.968556) (xy 424.561254 -227.692966) (xy 425.120054 -227.692966) (xy 425.120054 -227.968556)
			)
		)
	)
	(zone
		(layer "In11.Cu")
		(hatch none 0.5)
		(connect_pads
			(clearance 0)
		)
		(min_thickness 0.25)
		(keepout
			(tracks allowed)
			(vias allowed)
			(pads allowed)
			(copperpour allowed)
			(footprints allowed)
		)
		(placement
			(enabled no)
			(sheetname "")
		)
		(fill
			(thermal_gap 0.5)
			(thermal_bridge_width 0.5)
			(island_removal_mode 0)
		)
		(polygon
			(pts
				(xy 420.461186 -306.168552) (xy 420.461186 -305.892962) (xy 421.019986 -305.892962) (xy 421.019986 -306.168552)
			)
		)
	)
	(zone
		(layer "In11.Cu")
		(hatch none 0.5)
		(connect_pads
			(clearance 0)
		)
		(min_thickness 0.25)
		(keepout
			(tracks allowed)
			(vias allowed)
			(pads allowed)
			(copperpour allowed)
			(footprints allowed)
		)
		(placement
			(enabled no)
			(sheetname "")
		)
		(fill
			(thermal_gap 0.5)
			(thermal_bridge_width 0.5)
			(island_removal_mode 0)
		)
		(polygon
			(pts
				(xy 298.68622 -231.596946) (xy 298.68622 -231.04729) (xy 299.31614 -231.04729) (xy 299.31614 -231.596946)
			)
		)
	)
	(zone
		(layer "In11.Cu")
		(hatch none 0.5)
		(connect_pads
			(clearance 0)
		)
		(min_thickness 0.25)
		(keepout
			(tracks allowed)
			(vias allowed)
			(pads allowed)
			(copperpour allowed)
			(footprints allowed)
		)
		(placement
			(enabled no)
			(sheetname "")
		)
		(fill
			(thermal_gap 0.5)
			(thermal_bridge_width 0.5)
			(island_removal_mode 0)
		)
		(polygon
			(pts
				(xy 176.621186 -308.718458) (xy 176.621186 -308.442868) (xy 177.179986 -308.442868) (xy 177.179986 -308.718458)
			)
		)
	)
	(zone
		(layer "In11.Cu")
		(hatch none 0.5)
		(connect_pads
			(clearance 0)
		)
		(min_thickness 0.25)
		(keepout
			(tracks allowed)
			(vias allowed)
			(pads allowed)
			(copperpour allowed)
			(footprints allowed)
		)
		(placement
			(enabled no)
			(sheetname "")
		)
		(fill
			(thermal_gap 0.5)
			(thermal_bridge_width 0.5)
			(island_removal_mode 0)
		)
		(polygon
			(pts
				(xy 176.621186 -261.118604) (xy 176.621186 -260.843014) (xy 177.179986 -260.843014) (xy 177.179986 -261.118604)
			)
		)
	)
	(zone
		(layer "In11.Cu")
		(hatch none 0.5)
		(connect_pads
			(clearance 0)
		)
		(min_thickness 0.25)
		(keepout
			(tracks allowed)
			(vias allowed)
			(pads allowed)
			(copperpour allowed)
			(footprints allowed)
		)
		(placement
			(enabled no)
			(sheetname "")
		)
		(fill
			(thermal_gap 0.5)
			(thermal_bridge_width 0.5)
			(island_removal_mode 0)
		)
		(polygon
			(pts
				(xy 424.561254 -205.868524) (xy 424.561254 -205.592934) (xy 425.120054 -205.592934) (xy 425.120054 -205.868524)
			)
		)
	)
	(zone
		(layer "In11.Cu")
		(hatch none 0.5)
		(connect_pads
			(clearance 0)
		)
		(min_thickness 0.25)
		(keepout
			(tracks allowed)
			(vias allowed)
			(pads allowed)
			(copperpour allowed)
			(footprints allowed)
		)
		(placement
			(enabled no)
			(sheetname "")
		)
		(fill
			(thermal_gap 0.5)
			(thermal_bridge_width 0.5)
			(island_removal_mode 0)
		)
		(polygon
			(pts
				(xy 420.461186 -206.718408) (xy 420.461186 -206.442818) (xy 421.019986 -206.442818) (xy 421.019986 -206.718408)
			)
		)
	)
	(zone
		(layer "In11.Cu")
		(hatch none 0.5)
		(connect_pads
			(clearance 0)
		)
		(min_thickness 0.25)
		(keepout
			(tracks allowed)
			(vias allowed)
			(pads allowed)
			(copperpour allowed)
			(footprints allowed)
		)
		(placement
			(enabled no)
			(sheetname "")
		)
		(fill
			(thermal_gap 0.5)
			(thermal_bridge_width 0.5)
			(island_removal_mode 0)
		)
		(polygon
			(pts
				(xy 176.621186 -246.668544) (xy 176.621186 -246.392954) (xy 177.179986 -246.392954) (xy 177.179986 -246.668544)
			)
		)
	)
	(zone
		(layer "In11.Cu")
		(hatch none 0.5)
		(connect_pads
			(clearance 0)
		)
		(min_thickness 0.25)
		(keepout
			(tracks allowed)
			(vias allowed)
			(pads allowed)
			(copperpour allowed)
			(footprints allowed)
		)
		(placement
			(enabled no)
			(sheetname "")
		)
		(fill
			(thermal_gap 0.5)
			(thermal_bridge_width 0.5)
			(island_removal_mode 0)
		)
		(polygon
			(pts
				(xy 268.51102 -229.896924) (xy 268.51102 -229.347268) (xy 269.14094 -229.347268) (xy 269.14094 -229.896924)
			)
		)
	)
	(zone
		(layer "In11.Cu")
		(hatch none 0.5)
		(connect_pads
			(clearance 0)
		)
		(min_thickness 0.25)
		(keepout
			(tracks allowed)
			(vias allowed)
			(pads allowed)
			(copperpour allowed)
			(footprints allowed)
		)
		(placement
			(enabled no)
			(sheetname "")
		)
		(fill
			(thermal_gap 0.5)
			(thermal_bridge_width 0.5)
			(island_removal_mode 0)
		)
		(polygon
			(pts
				(xy 425.11091 -294.164766) (xy 425.11091 -294.440356) (xy 424.55211 -294.440356) (xy 424.55211 -294.164766)
			)
		)
	)
	(zone
		(layer "In11.Cu")
		(hatch none 0.5)
		(connect_pads
			(clearance 0)
		)
		(min_thickness 0.25)
		(keepout
			(tracks allowed)
			(vias allowed)
			(pads allowed)
			(copperpour allowed)
			(footprints allowed)
		)
		(placement
			(enabled no)
			(sheetname "")
		)
		(fill
			(thermal_gap 0.5)
			(thermal_bridge_width 0.5)
			(island_removal_mode 0)
		)
		(polygon
			(pts
				(xy 176.621186 -288.318448) (xy 176.621186 -288.042858) (xy 177.179986 -288.042858) (xy 177.179986 -288.318448)
			)
		)
	)
	(zone
		(layer "In11.Cu")
		(hatch none 0.5)
		(connect_pads
			(clearance 0)
		)
		(min_thickness 0.25)
		(keepout
			(tracks allowed)
			(vias allowed)
			(pads allowed)
			(copperpour allowed)
			(footprints allowed)
		)
		(placement
			(enabled no)
			(sheetname "")
		)
		(fill
			(thermal_gap 0.5)
			(thermal_bridge_width 0.5)
			(island_removal_mode 0)
		)
		(polygon
			(pts
				(xy 294.586152 -230.746808) (xy 294.586152 -230.197152) (xy 295.216072 -230.197152) (xy 295.216072 -230.746808)
			)
		)
	)
	(zone
		(layer "In11.Cu")
		(hatch none 0.5)
		(connect_pads
			(clearance 0)
		)
		(min_thickness 0.25)
		(keepout
			(tracks allowed)
			(vias allowed)
			(pads allowed)
			(copperpour allowed)
			(footprints allowed)
		)
		(placement
			(enabled no)
			(sheetname "")
		)
		(fill
			(thermal_gap 0.5)
			(thermal_bridge_width 0.5)
			(island_removal_mode 0)
		)
		(polygon
			(pts
				(xy 192.258442 -281.414728) (xy 192.258442 -281.690318) (xy 191.699642 -281.690318) (xy 191.699642 -281.414728)
			)
		)
	)
	(zone
		(layer "In11.Cu")
		(hatch none 0.5)
		(connect_pads
			(clearance 0)
		)
		(min_thickness 0.25)
		(keepout
			(tracks allowed)
			(vias allowed)
			(pads allowed)
			(copperpour allowed)
			(footprints allowed)
		)
		(placement
			(enabled no)
			(sheetname "")
		)
		(fill
			(thermal_gap 0.5)
			(thermal_bridge_width 0.5)
			(island_removal_mode 0)
		)
		(polygon
			(pts
				(xy 177.170842 -208.314798) (xy 177.170842 -208.590388) (xy 176.612042 -208.590388) (xy 176.612042 -208.314798)
			)
		)
	)
	(zone
		(layers "In12.Cu" "In14.Cu")
		(hatch none 0.5)
		(connect_pads
			(clearance 0)
		)
		(min_thickness 0.25)
		(keepout
			(tracks not_allowed)
			(vias allowed)
			(pads allowed)
			(copperpour not_allowed)
			(footprints allowed)
		)
		(placement
			(enabled no)
			(sheetname "")
		)
		(fill yes
			(thermal_gap 0.5)
			(thermal_bridge_width 0.5)
			(island_removal_mode 0)
		)
		(polygon
			(pts
				(arc
					(start 142.242032 -435.16042)
					(mid 142.26435 -435.214302)
					(end 142.318232 -435.23662)
				)
				(arc
					(start 143.258032 -435.23662)
					(mid 143.311914 -435.214302)
					(end 143.334232 -435.16042)
				)
				(arc
					(start 143.334232 -432.618896)
					(mid 143.311914 -432.565014)
					(end 143.258032 -432.542696)
				)
				(arc
					(start 142.318232 -432.542696)
					(mid 142.26435 -432.565014)
					(end 142.242032 -432.618896)
				)
				(arc
					(start 142.242032 -433.346352)
					(mid 142.244031 -433.363693)
					(end 142.249906 -433.380134)
				)
				(arc
					(start 142.483332 -433.856384)
					(mid 142.491115 -433.889912)
					(end 142.483332 -433.92344)
				)
				(arc
					(start 142.249906 -434.39969)
					(mid 142.244011 -434.416126)
					(end 142.242032 -434.433472)
				)
			)
		)
	)
	(zone
		(layers "In12.Cu" "In14.Cu")
		(hatch none 0.5)
		(connect_pads
			(clearance 0)
		)
		(min_thickness 0.25)
		(keepout
			(tracks not_allowed)
			(vias allowed)
			(pads allowed)
			(copperpour not_allowed)
			(footprints allowed)
		)
		(placement
			(enabled no)
			(sheetname "")
		)
		(fill yes
			(thermal_gap 0.5)
			(thermal_bridge_width 0.5)
			(island_removal_mode 0)
		)
		(polygon
			(pts
				(arc
					(start 341.142066 -439.760614)
					(mid 341.164384 -439.814496)
					(end 341.218266 -439.836814)
				)
				(arc
					(start 342.158066 -439.836814)
					(mid 342.211948 -439.814496)
					(end 342.234266 -439.760614)
				)
				(arc
					(start 342.234266 -437.21909)
					(mid 342.211948 -437.165208)
					(end 342.158066 -437.14289)
				)
				(arc
					(start 341.218266 -437.14289)
					(mid 341.164384 -437.165208)
					(end 341.142066 -437.21909)
				)
				(arc
					(start 341.142066 -437.946546)
					(mid 341.144065 -437.963887)
					(end 341.14994 -437.980328)
				)
				(arc
					(start 341.383366 -438.456578)
					(mid 341.391149 -438.490106)
					(end 341.383366 -438.523634)
				)
				(arc
					(start 341.14994 -438.999884)
					(mid 341.144045 -439.01632)
					(end 341.142066 -439.033666)
				)
			)
		)
	)
	(zone
		(layers "In12.Cu" "In14.Cu")
		(hatch none 0.5)
		(connect_pads
			(clearance 0)
		)
		(min_thickness 0.25)
		(keepout
			(tracks not_allowed)
			(vias allowed)
			(pads allowed)
			(copperpour not_allowed)
			(footprints allowed)
		)
		(placement
			(enabled no)
			(sheetname "")
		)
		(fill yes
			(thermal_gap 0.5)
			(thermal_bridge_width 0.5)
			(island_removal_mode 0)
		)
		(polygon
			(pts
				(arc
					(start 64.142112 -439.760614)
					(mid 64.16443 -439.814496)
					(end 64.218312 -439.836814)
				)
				(arc
					(start 65.158112 -439.836814)
					(mid 65.211994 -439.814496)
					(end 65.234312 -439.760614)
				)
				(arc
					(start 65.234312 -437.21909)
					(mid 65.211994 -437.165208)
					(end 65.158112 -437.14289)
				)
				(arc
					(start 64.218312 -437.14289)
					(mid 64.16443 -437.165208)
					(end 64.142112 -437.21909)
				)
				(arc
					(start 64.142112 -437.946546)
					(mid 64.144111 -437.963887)
					(end 64.149986 -437.980328)
				)
				(arc
					(start 64.383412 -438.456578)
					(mid 64.391195 -438.490106)
					(end 64.383412 -438.523634)
				)
				(arc
					(start 64.149986 -438.999884)
					(mid 64.144091 -439.01632)
					(end 64.142112 -439.033666)
				)
			)
		)
	)
	(zone
		(layers "In12.Cu" "In14.Cu")
		(hatch none 0.5)
		(connect_pads
			(clearance 0)
		)
		(min_thickness 0.25)
		(keepout
			(tracks not_allowed)
			(vias allowed)
			(pads allowed)
			(copperpour not_allowed)
			(footprints allowed)
		)
		(placement
			(enabled no)
			(sheetname "")
		)
		(fill yes
			(thermal_gap 0.5)
			(thermal_bridge_width 0.5)
			(island_removal_mode 0)
		)
		(polygon
			(pts
				(arc
					(start 381.242062 -435.16042)
					(mid 381.26438 -435.214302)
					(end 381.318262 -435.23662)
				)
				(arc
					(start 382.258062 -435.23662)
					(mid 382.311944 -435.214302)
					(end 382.334262 -435.16042)
				)
				(arc
					(start 382.334262 -432.618896)
					(mid 382.311944 -432.565014)
					(end 382.258062 -432.542696)
				)
				(arc
					(start 381.318262 -432.542696)
					(mid 381.26438 -432.565014)
					(end 381.242062 -432.618896)
				)
				(arc
					(start 381.242062 -433.346352)
					(mid 381.244061 -433.363693)
					(end 381.249936 -433.380134)
				)
				(arc
					(start 381.483362 -433.856384)
					(mid 381.491145 -433.889912)
					(end 381.483362 -433.92344)
				)
				(arc
					(start 381.249936 -434.39969)
					(mid 381.244041 -434.416126)
					(end 381.242062 -434.433472)
				)
			)
		)
	)
	(zone
		(layers "In12.Cu" "In14.Cu")
		(hatch none 0.5)
		(connect_pads
			(clearance 0)
		)
		(min_thickness 0.25)
		(keepout
			(tracks not_allowed)
			(vias allowed)
			(pads allowed)
			(copperpour not_allowed)
			(footprints allowed)
		)
		(placement
			(enabled no)
			(sheetname "")
		)
		(fill yes
			(thermal_gap 0.5)
			(thermal_bridge_width 0.5)
			(island_removal_mode 0)
		)
		(polygon
			(pts
				(arc
					(start 410.242004 -435.16042)
					(mid 410.264322 -435.214302)
					(end 410.318204 -435.23662)
				)
				(arc
					(start 411.258004 -435.23662)
					(mid 411.311886 -435.214302)
					(end 411.334204 -435.16042)
				)
				(arc
					(start 411.334204 -432.618896)
					(mid 411.311886 -432.565014)
					(end 411.258004 -432.542696)
				)
				(arc
					(start 410.318204 -432.542696)
					(mid 410.264322 -432.565014)
					(end 410.242004 -432.618896)
				)
				(arc
					(start 410.242004 -433.346352)
					(mid 410.244003 -433.363693)
					(end 410.249878 -433.380134)
				)
				(arc
					(start 410.483304 -433.856384)
					(mid 410.491087 -433.889912)
					(end 410.483304 -433.92344)
				)
				(arc
					(start 410.249878 -434.39969)
					(mid 410.243983 -434.416126)
					(end 410.242004 -434.433472)
				)
			)
		)
	)
	(zone
		(layers "In12.Cu" "In14.Cu")
		(hatch none 0.5)
		(connect_pads
			(clearance 0)
		)
		(min_thickness 0.25)
		(keepout
			(tracks not_allowed)
			(vias allowed)
			(pads allowed)
			(copperpour not_allowed)
			(footprints allowed)
		)
		(placement
			(enabled no)
			(sheetname "")
		)
		(fill yes
			(thermal_gap 0.5)
			(thermal_bridge_width 0.5)
			(island_removal_mode 0)
		)
		(polygon
			(pts
				(arc
					(start 389.242046 -435.16042)
					(mid 389.264364 -435.214302)
					(end 389.318246 -435.23662)
				)
				(arc
					(start 390.258046 -435.23662)
					(mid 390.311928 -435.214302)
					(end 390.334246 -435.16042)
				)
				(arc
					(start 390.334246 -432.618896)
					(mid 390.311928 -432.565014)
					(end 390.258046 -432.542696)
				)
				(arc
					(start 389.318246 -432.542696)
					(mid 389.264364 -432.565014)
					(end 389.242046 -432.618896)
				)
				(arc
					(start 389.242046 -433.346352)
					(mid 389.244045 -433.363693)
					(end 389.24992 -433.380134)
				)
				(arc
					(start 389.483346 -433.856384)
					(mid 389.491129 -433.889912)
					(end 389.483346 -433.92344)
				)
				(arc
					(start 389.24992 -434.39969)
					(mid 389.244025 -434.416126)
					(end 389.242046 -434.433472)
				)
			)
		)
	)
	(zone
		(layers "In12.Cu" "In14.Cu")
		(hatch none 0.5)
		(connect_pads
			(clearance 0)
		)
		(min_thickness 0.25)
		(keepout
			(tracks not_allowed)
			(vias allowed)
			(pads allowed)
			(copperpour not_allowed)
			(footprints allowed)
		)
		(placement
			(enabled no)
			(sheetname "")
		)
		(fill yes
			(thermal_gap 0.5)
			(thermal_bridge_width 0.5)
			(island_removal_mode 0)
		)
		(polygon
			(pts
				(arc
					(start 387.24205 -436.160418)
					(mid 387.264368 -436.2143)
					(end 387.31825 -436.236618)
				)
				(arc
					(start 388.25805 -436.236618)
					(mid 388.311932 -436.2143)
					(end 388.33425 -436.160418)
				)
				(arc
					(start 388.33425 -433.618894)
					(mid 388.311932 -433.565012)
					(end 388.25805 -433.542694)
				)
				(arc
					(start 387.31825 -433.542694)
					(mid 387.264368 -433.565012)
					(end 387.24205 -433.618894)
				)
				(arc
					(start 387.24205 -434.34635)
					(mid 387.244049 -434.363691)
					(end 387.249924 -434.380132)
				)
				(arc
					(start 387.48335 -434.856382)
					(mid 387.491133 -434.88991)
					(end 387.48335 -434.923438)
				)
				(arc
					(start 387.249924 -435.399688)
					(mid 387.244029 -435.416124)
					(end 387.24205 -435.43347)
				)
			)
		)
	)
	(zone
		(layers "In12.Cu" "In14.Cu")
		(hatch none 0.5)
		(connect_pads
			(clearance 0)
		)
		(min_thickness 0.25)
		(keepout
			(tracks not_allowed)
			(vias allowed)
			(pads allowed)
			(copperpour not_allowed)
			(footprints allowed)
		)
		(placement
			(enabled no)
			(sheetname "")
		)
		(fill yes
			(thermal_gap 0.5)
			(thermal_bridge_width 0.5)
			(island_removal_mode 0)
		)
		(polygon
			(pts
				(arc
					(start 135.242046 -436.160418)
					(mid 135.264364 -436.2143)
					(end 135.318246 -436.236618)
				)
				(arc
					(start 136.258046 -436.236618)
					(mid 136.311928 -436.2143)
					(end 136.334246 -436.160418)
				)
				(arc
					(start 136.334246 -433.618894)
					(mid 136.311928 -433.565012)
					(end 136.258046 -433.542694)
				)
				(arc
					(start 135.318246 -433.542694)
					(mid 135.264364 -433.565012)
					(end 135.242046 -433.618894)
				)
				(arc
					(start 135.242046 -434.34635)
					(mid 135.244045 -434.363691)
					(end 135.24992 -434.380132)
				)
				(arc
					(start 135.483346 -434.856382)
					(mid 135.491129 -434.88991)
					(end 135.483346 -434.923438)
				)
				(arc
					(start 135.24992 -435.399688)
					(mid 135.244025 -435.416124)
					(end 135.242046 -435.43347)
				)
			)
		)
	)
	(zone
		(layers "In12.Cu" "In14.Cu")
		(hatch none 0.5)
		(connect_pads
			(clearance 0)
		)
		(min_thickness 0.25)
		(keepout
			(tracks not_allowed)
			(vias allowed)
			(pads allowed)
			(copperpour not_allowed)
			(footprints allowed)
		)
		(placement
			(enabled no)
			(sheetname "")
		)
		(fill yes
			(thermal_gap 0.5)
			(thermal_bridge_width 0.5)
			(island_removal_mode 0)
		)
		(polygon
			(pts
				(arc
					(start 146.242024 -435.16042)
					(mid 146.264342 -435.214302)
					(end 146.318224 -435.23662)
				)
				(arc
					(start 147.258024 -435.23662)
					(mid 147.311906 -435.214302)
					(end 147.334224 -435.16042)
				)
				(arc
					(start 147.334224 -432.618896)
					(mid 147.311906 -432.565014)
					(end 147.258024 -432.542696)
				)
				(arc
					(start 146.318224 -432.542696)
					(mid 146.264342 -432.565014)
					(end 146.242024 -432.618896)
				)
				(arc
					(start 146.242024 -433.346352)
					(mid 146.244023 -433.363693)
					(end 146.249898 -433.380134)
				)
				(arc
					(start 146.483324 -433.856384)
					(mid 146.491107 -433.889912)
					(end 146.483324 -433.92344)
				)
				(arc
					(start 146.249898 -434.39969)
					(mid 146.244003 -434.416126)
					(end 146.242024 -434.433472)
				)
			)
		)
	)
	(zone
		(layers "In12.Cu" "In14.Cu")
		(hatch none 0.5)
		(connect_pads
			(clearance 0)
		)
		(min_thickness 0.25)
		(keepout
			(tracks not_allowed)
			(vias allowed)
			(pads allowed)
			(copperpour not_allowed)
			(footprints allowed)
		)
		(placement
			(enabled no)
			(sheetname "")
		)
		(fill yes
			(thermal_gap 0.5)
			(thermal_bridge_width 0.5)
			(island_removal_mode 0)
		)
		(polygon
			(pts
				(arc
					(start 139.242038 -436.160418)
					(mid 139.264356 -436.2143)
					(end 139.318238 -436.236618)
				)
				(arc
					(start 140.258038 -436.236618)
					(mid 140.31192 -436.2143)
					(end 140.334238 -436.160418)
				)
				(arc
					(start 140.334238 -433.618894)
					(mid 140.31192 -433.565012)
					(end 140.258038 -433.542694)
				)
				(arc
					(start 139.318238 -433.542694)
					(mid 139.264356 -433.565012)
					(end 139.242038 -433.618894)
				)
				(arc
					(start 139.242038 -434.34635)
					(mid 139.244037 -434.363691)
					(end 139.249912 -434.380132)
				)
				(arc
					(start 139.483338 -434.856382)
					(mid 139.491121 -434.88991)
					(end 139.483338 -434.923438)
				)
				(arc
					(start 139.249912 -435.399688)
					(mid 139.244017 -435.416124)
					(end 139.242038 -435.43347)
				)
			)
		)
	)
	(zone
		(layers "In12.Cu" "In14.Cu")
		(hatch none 0.5)
		(connect_pads
			(clearance 0)
		)
		(min_thickness 0.25)
		(keepout
			(tracks not_allowed)
			(vias allowed)
			(pads allowed)
			(copperpour not_allowed)
			(footprints allowed)
		)
		(placement
			(enabled no)
			(sheetname "")
		)
		(fill yes
			(thermal_gap 0.5)
			(thermal_bridge_width 0.5)
			(island_removal_mode 0)
		)
		(polygon
			(pts
				(arc
					(start 77.142086 -439.760614)
					(mid 77.164404 -439.814496)
					(end 77.218286 -439.836814)
				)
				(arc
					(start 78.158086 -439.836814)
					(mid 78.211968 -439.814496)
					(end 78.234286 -439.760614)
				)
				(arc
					(start 78.234286 -437.21909)
					(mid 78.211968 -437.165208)
					(end 78.158086 -437.14289)
				)
				(arc
					(start 77.218286 -437.14289)
					(mid 77.164404 -437.165208)
					(end 77.142086 -437.21909)
				)
				(arc
					(start 77.142086 -437.946546)
					(mid 77.144085 -437.963887)
					(end 77.14996 -437.980328)
				)
				(arc
					(start 77.383386 -438.456578)
					(mid 77.391169 -438.490106)
					(end 77.383386 -438.523634)
				)
				(arc
					(start 77.14996 -438.999884)
					(mid 77.144065 -439.01632)
					(end 77.142086 -439.033666)
				)
			)
		)
	)
	(zone
		(layers "In12.Cu" "In14.Cu")
		(hatch none 0.5)
		(connect_pads
			(clearance 0)
		)
		(min_thickness 0.25)
		(keepout
			(tracks not_allowed)
			(vias allowed)
			(pads allowed)
			(copperpour not_allowed)
			(footprints allowed)
		)
		(placement
			(enabled no)
			(sheetname "")
		)
		(fill yes
			(thermal_gap 0.5)
			(thermal_bridge_width 0.5)
			(island_removal_mode 0)
		)
		(polygon
			(pts
				(arc
					(start 89.142062 -439.760614)
					(mid 89.16438 -439.814496)
					(end 89.218262 -439.836814)
				)
				(arc
					(start 90.158062 -439.836814)
					(mid 90.211944 -439.814496)
					(end 90.234262 -439.760614)
				)
				(arc
					(start 90.234262 -437.21909)
					(mid 90.211944 -437.165208)
					(end 90.158062 -437.14289)
				)
				(arc
					(start 89.218262 -437.14289)
					(mid 89.16438 -437.165208)
					(end 89.142062 -437.21909)
				)
				(arc
					(start 89.142062 -437.946546)
					(mid 89.144061 -437.963887)
					(end 89.149936 -437.980328)
				)
				(arc
					(start 89.383362 -438.456578)
					(mid 89.391145 -438.490106)
					(end 89.383362 -438.523634)
				)
				(arc
					(start 89.149936 -438.999884)
					(mid 89.144041 -439.01632)
					(end 89.142062 -439.033666)
				)
			)
		)
	)
	(zone
		(layers "In12.Cu" "In14.Cu")
		(hatch none 0.5)
		(connect_pads
			(clearance 0)
		)
		(min_thickness 0.25)
		(keepout
			(tracks not_allowed)
			(vias allowed)
			(pads allowed)
			(copperpour not_allowed)
			(footprints allowed)
		)
		(placement
			(enabled no)
			(sheetname "")
		)
		(fill yes
			(thermal_gap 0.5)
			(thermal_bridge_width 0.5)
			(island_removal_mode 0)
		)
		(polygon
			(pts
				(arc
					(start 395.242034 -436.160418)
					(mid 395.264352 -436.2143)
					(end 395.318234 -436.236618)
				)
				(arc
					(start 396.258034 -436.236618)
					(mid 396.311916 -436.2143)
					(end 396.334234 -436.160418)
				)
				(arc
					(start 396.334234 -433.618894)
					(mid 396.311916 -433.565012)
					(end 396.258034 -433.542694)
				)
				(arc
					(start 395.318234 -433.542694)
					(mid 395.264352 -433.565012)
					(end 395.242034 -433.618894)
				)
				(arc
					(start 395.242034 -434.34635)
					(mid 395.244033 -434.363691)
					(end 395.249908 -434.380132)
				)
				(arc
					(start 395.483334 -434.856382)
					(mid 395.491117 -434.88991)
					(end 395.483334 -434.923438)
				)
				(arc
					(start 395.249908 -435.399688)
					(mid 395.244013 -435.416124)
					(end 395.242034 -435.43347)
				)
			)
		)
	)
	(zone
		(layers "In12.Cu" "In14.Cu")
		(hatch none 0.5)
		(connect_pads
			(clearance 0)
		)
		(min_thickness 0.25)
		(keepout
			(tracks not_allowed)
			(vias allowed)
			(pads allowed)
			(copperpour not_allowed)
			(footprints allowed)
		)
		(placement
			(enabled no)
			(sheetname "")
		)
		(fill yes
			(thermal_gap 0.5)
			(thermal_bridge_width 0.5)
			(island_removal_mode 0)
		)
		(polygon
			(pts
				(arc
					(start 406.242012 -435.16042)
					(mid 406.26433 -435.214302)
					(end 406.318212 -435.23662)
				)
				(arc
					(start 407.258012 -435.23662)
					(mid 407.311894 -435.214302)
					(end 407.334212 -435.16042)
				)
				(arc
					(start 407.334212 -432.618896)
					(mid 407.311894 -432.565014)
					(end 407.258012 -432.542696)
				)
				(arc
					(start 406.318212 -432.542696)
					(mid 406.26433 -432.565014)
					(end 406.242012 -432.618896)
				)
				(arc
					(start 406.242012 -433.346352)
					(mid 406.244011 -433.363693)
					(end 406.249886 -433.380134)
				)
				(arc
					(start 406.483312 -433.856384)
					(mid 406.491095 -433.889912)
					(end 406.483312 -433.92344)
				)
				(arc
					(start 406.249886 -434.39969)
					(mid 406.243991 -434.416126)
					(end 406.242012 -434.433472)
				)
			)
		)
	)
	(zone
		(layers "In12.Cu" "In14.Cu")
		(hatch none 0.5)
		(connect_pads
			(clearance 0)
		)
		(min_thickness 0.25)
		(keepout
			(tracks not_allowed)
			(vias allowed)
			(pads allowed)
			(copperpour not_allowed)
			(footprints allowed)
		)
		(placement
			(enabled no)
			(sheetname "")
		)
		(fill yes
			(thermal_gap 0.5)
			(thermal_bridge_width 0.5)
			(island_removal_mode 0)
		)
		(polygon
			(pts
				(arc
					(start 79.142082 -438.760616)
					(mid 79.1644 -438.814498)
					(end 79.218282 -438.836816)
				)
				(arc
					(start 80.158082 -438.836816)
					(mid 80.211964 -438.814498)
					(end 80.234282 -438.760616)
				)
				(arc
					(start 80.234282 -436.219092)
					(mid 80.211964 -436.16521)
					(end 80.158082 -436.142892)
				)
				(arc
					(start 79.218282 -436.142892)
					(mid 79.1644 -436.16521)
					(end 79.142082 -436.219092)
				)
				(arc
					(start 79.142082 -436.946548)
					(mid 79.144081 -436.963889)
					(end 79.149956 -436.98033)
				)
				(arc
					(start 79.383382 -437.45658)
					(mid 79.391165 -437.490108)
					(end 79.383382 -437.523636)
				)
				(arc
					(start 79.149956 -437.999886)
					(mid 79.144061 -438.016322)
					(end 79.142082 -438.033668)
				)
			)
		)
	)
	(zone
		(layers "In12.Cu" "In14.Cu")
		(hatch none 0.5)
		(connect_pads
			(clearance 0)
		)
		(min_thickness 0.25)
		(keepout
			(tracks not_allowed)
			(vias allowed)
			(pads allowed)
			(copperpour not_allowed)
			(footprints allowed)
		)
		(placement
			(enabled no)
			(sheetname "")
		)
		(fill yes
			(thermal_gap 0.5)
			(thermal_bridge_width 0.5)
			(island_removal_mode 0)
		)
		(polygon
			(pts
				(arc
					(start 131.242054 -436.160418)
					(mid 131.264372 -436.2143)
					(end 131.318254 -436.236618)
				)
				(arc
					(start 132.258054 -436.236618)
					(mid 132.311936 -436.2143)
					(end 132.334254 -436.160418)
				)
				(arc
					(start 132.334254 -433.618894)
					(mid 132.311936 -433.565012)
					(end 132.258054 -433.542694)
				)
				(arc
					(start 131.318254 -433.542694)
					(mid 131.264372 -433.565012)
					(end 131.242054 -433.618894)
				)
				(arc
					(start 131.242054 -434.34635)
					(mid 131.244053 -434.363691)
					(end 131.249928 -434.380132)
				)
				(arc
					(start 131.483354 -434.856382)
					(mid 131.491137 -434.88991)
					(end 131.483354 -434.923438)
				)
				(arc
					(start 131.249928 -435.399688)
					(mid 131.244033 -435.416124)
					(end 131.242054 -435.43347)
				)
			)
		)
	)
	(zone
		(layers "In12.Cu" "In14.Cu")
		(hatch none 0.5)
		(connect_pads
			(clearance 0)
		)
		(min_thickness 0.25)
		(keepout
			(tracks not_allowed)
			(vias allowed)
			(pads allowed)
			(copperpour not_allowed)
			(footprints allowed)
		)
		(placement
			(enabled no)
			(sheetname "")
		)
		(fill yes
			(thermal_gap 0.5)
			(thermal_bridge_width 0.5)
			(island_removal_mode 0)
		)
		(polygon
			(pts
				(arc
					(start 393.242038 -435.16042)
					(mid 393.264356 -435.214302)
					(end 393.318238 -435.23662)
				)
				(arc
					(start 394.258038 -435.23662)
					(mid 394.31192 -435.214302)
					(end 394.334238 -435.16042)
				)
				(arc
					(start 394.334238 -432.618896)
					(mid 394.31192 -432.565014)
					(end 394.258038 -432.542696)
				)
				(arc
					(start 393.318238 -432.542696)
					(mid 393.264356 -432.565014)
					(end 393.242038 -432.618896)
				)
				(arc
					(start 393.242038 -433.346352)
					(mid 393.244037 -433.363693)
					(end 393.249912 -433.380134)
				)
				(arc
					(start 393.483338 -433.856384)
					(mid 393.491121 -433.889912)
					(end 393.483338 -433.92344)
				)
				(arc
					(start 393.249912 -434.39969)
					(mid 393.244017 -434.416126)
					(end 393.242038 -434.433472)
				)
			)
		)
	)
	(zone
		(layers "In12.Cu" "In14.Cu")
		(hatch none 0.5)
		(connect_pads
			(clearance 0)
		)
		(min_thickness 0.25)
		(keepout
			(tracks not_allowed)
			(vias allowed)
			(pads allowed)
			(copperpour not_allowed)
			(footprints allowed)
		)
		(placement
			(enabled no)
			(sheetname "")
		)
		(fill yes
			(thermal_gap 0.5)
			(thermal_bridge_width 0.5)
			(island_removal_mode 0)
		)
		(polygon
			(pts
				(arc
					(start 70.1421 -438.760616)
					(mid 70.164418 -438.814498)
					(end 70.2183 -438.836816)
				)
				(arc
					(start 71.1581 -438.836816)
					(mid 71.211982 -438.814498)
					(end 71.2343 -438.760616)
				)
				(arc
					(start 71.2343 -436.219092)
					(mid 71.211982 -436.16521)
					(end 71.1581 -436.142892)
				)
				(arc
					(start 70.2183 -436.142892)
					(mid 70.164418 -436.16521)
					(end 70.1421 -436.219092)
				)
				(arc
					(start 70.1421 -436.946548)
					(mid 70.144099 -436.963889)
					(end 70.149974 -436.98033)
				)
				(arc
					(start 70.3834 -437.45658)
					(mid 70.391183 -437.490108)
					(end 70.3834 -437.523636)
				)
				(arc
					(start 70.149974 -437.999886)
					(mid 70.144079 -438.016322)
					(end 70.1421 -438.033668)
				)
			)
		)
	)
	(zone
		(layers "In12.Cu" "In14.Cu")
		(hatch none 0.5)
		(connect_pads
			(clearance 0)
		)
		(min_thickness 0.25)
		(keepout
			(tracks not_allowed)
			(vias allowed)
			(pads allowed)
			(copperpour not_allowed)
			(footprints allowed)
		)
		(placement
			(enabled no)
			(sheetname "")
		)
		(fill yes
			(thermal_gap 0.5)
			(thermal_bridge_width 0.5)
			(island_removal_mode 0)
		)
		(polygon
			(pts
				(arc
					(start 333.142082 -439.760614)
					(mid 333.1644 -439.814496)
					(end 333.218282 -439.836814)
				)
				(arc
					(start 334.158082 -439.836814)
					(mid 334.211964 -439.814496)
					(end 334.234282 -439.760614)
				)
				(arc
					(start 334.234282 -437.21909)
					(mid 334.211964 -437.165208)
					(end 334.158082 -437.14289)
				)
				(arc
					(start 333.218282 -437.14289)
					(mid 333.1644 -437.165208)
					(end 333.142082 -437.21909)
				)
				(arc
					(start 333.142082 -437.946546)
					(mid 333.144081 -437.963887)
					(end 333.149956 -437.980328)
				)
				(arc
					(start 333.383382 -438.456578)
					(mid 333.391165 -438.490106)
					(end 333.383382 -438.523634)
				)
				(arc
					(start 333.149956 -438.999884)
					(mid 333.144061 -439.01632)
					(end 333.142082 -439.033666)
				)
			)
		)
	)
	(zone
		(layers "In12.Cu" "In14.Cu")
		(hatch none 0.5)
		(connect_pads
			(clearance 0)
		)
		(min_thickness 0.25)
		(keepout
			(tracks not_allowed)
			(vias allowed)
			(pads allowed)
			(copperpour not_allowed)
			(footprints allowed)
		)
		(placement
			(enabled no)
			(sheetname "")
		)
		(fill yes
			(thermal_gap 0.5)
			(thermal_bridge_width 0.5)
			(island_removal_mode 0)
		)
		(polygon
			(pts
				(arc
					(start 385.242054 -435.16042)
					(mid 385.264372 -435.214302)
					(end 385.318254 -435.23662)
				)
				(arc
					(start 386.258054 -435.23662)
					(mid 386.311936 -435.214302)
					(end 386.334254 -435.16042)
				)
				(arc
					(start 386.334254 -432.618896)
					(mid 386.311936 -432.565014)
					(end 386.258054 -432.542696)
				)
				(arc
					(start 385.318254 -432.542696)
					(mid 385.264372 -432.565014)
					(end 385.242054 -432.618896)
				)
				(arc
					(start 385.242054 -433.346352)
					(mid 385.244053 -433.363693)
					(end 385.249928 -433.380134)
				)
				(arc
					(start 385.483354 -433.856384)
					(mid 385.491137 -433.889912)
					(end 385.483354 -433.92344)
				)
				(arc
					(start 385.249928 -434.39969)
					(mid 385.244033 -434.416126)
					(end 385.242054 -434.433472)
				)
			)
		)
	)
	(zone
		(layers "In12.Cu" "In14.Cu")
		(hatch none 0.5)
		(connect_pads
			(clearance 0)
		)
		(min_thickness 0.25)
		(keepout
			(tracks not_allowed)
			(vias allowed)
			(pads allowed)
			(copperpour not_allowed)
			(footprints allowed)
		)
		(placement
			(enabled no)
			(sheetname "")
		)
		(fill yes
			(thermal_gap 0.5)
			(thermal_bridge_width 0.5)
			(island_removal_mode 0)
		)
		(polygon
			(pts
				(arc
					(start 81.142078 -439.760614)
					(mid 81.164396 -439.814496)
					(end 81.218278 -439.836814)
				)
				(arc
					(start 82.158078 -439.836814)
					(mid 82.21196 -439.814496)
					(end 82.234278 -439.760614)
				)
				(arc
					(start 82.234278 -437.21909)
					(mid 82.21196 -437.165208)
					(end 82.158078 -437.14289)
				)
				(arc
					(start 81.218278 -437.14289)
					(mid 81.164396 -437.165208)
					(end 81.142078 -437.21909)
				)
				(arc
					(start 81.142078 -437.946546)
					(mid 81.144077 -437.963887)
					(end 81.149952 -437.980328)
				)
				(arc
					(start 81.383378 -438.456578)
					(mid 81.391161 -438.490106)
					(end 81.383378 -438.523634)
				)
				(arc
					(start 81.149952 -438.999884)
					(mid 81.144057 -439.01632)
					(end 81.142078 -439.033666)
				)
			)
		)
	)
	(zone
		(layers "In12.Cu" "In14.Cu")
		(hatch none 0.5)
		(connect_pads
			(clearance 0)
		)
		(min_thickness 0.25)
		(keepout
			(tracks not_allowed)
			(vias allowed)
			(pads allowed)
			(copperpour not_allowed)
			(footprints allowed)
		)
		(placement
			(enabled no)
			(sheetname "")
		)
		(fill yes
			(thermal_gap 0.5)
			(thermal_bridge_width 0.5)
			(island_removal_mode 0)
		)
		(polygon
			(pts
				(arc
					(start 383.242058 -436.160418)
					(mid 383.264376 -436.2143)
					(end 383.318258 -436.236618)
				)
				(arc
					(start 384.258058 -436.236618)
					(mid 384.31194 -436.2143)
					(end 384.334258 -436.160418)
				)
				(arc
					(start 384.334258 -433.618894)
					(mid 384.31194 -433.565012)
					(end 384.258058 -433.542694)
				)
				(arc
					(start 383.318258 -433.542694)
					(mid 383.264376 -433.565012)
					(end 383.242058 -433.618894)
				)
				(arc
					(start 383.242058 -434.34635)
					(mid 383.244057 -434.363691)
					(end 383.249932 -434.380132)
				)
				(arc
					(start 383.483358 -434.856382)
					(mid 383.491141 -434.88991)
					(end 383.483358 -434.923438)
				)
				(arc
					(start 383.249932 -435.399688)
					(mid 383.244037 -435.416124)
					(end 383.242058 -435.43347)
				)
			)
		)
	)
	(zone
		(layers "In12.Cu" "In14.Cu")
		(hatch none 0.5)
		(connect_pads
			(clearance 0)
		)
		(min_thickness 0.25)
		(keepout
			(tracks not_allowed)
			(vias allowed)
			(pads allowed)
			(copperpour not_allowed)
			(footprints allowed)
		)
		(placement
			(enabled no)
			(sheetname "")
		)
		(fill yes
			(thermal_gap 0.5)
			(thermal_bridge_width 0.5)
			(island_removal_mode 0)
		)
		(polygon
			(pts
				(arc
					(start 133.24205 -435.16042)
					(mid 133.264368 -435.214302)
					(end 133.31825 -435.23662)
				)
				(arc
					(start 134.25805 -435.23662)
					(mid 134.311932 -435.214302)
					(end 134.33425 -435.16042)
				)
				(arc
					(start 134.33425 -432.618896)
					(mid 134.311932 -432.565014)
					(end 134.25805 -432.542696)
				)
				(arc
					(start 133.31825 -432.542696)
					(mid 133.264368 -432.565014)
					(end 133.24205 -432.618896)
				)
				(arc
					(start 133.24205 -433.346352)
					(mid 133.244049 -433.363693)
					(end 133.249924 -433.380134)
				)
				(arc
					(start 133.48335 -433.856384)
					(mid 133.491133 -433.889912)
					(end 133.48335 -433.92344)
				)
				(arc
					(start 133.249924 -434.39969)
					(mid 133.244029 -434.416126)
					(end 133.24205 -434.433472)
				)
			)
		)
	)
	(zone
		(layers "In12.Cu" "In14.Cu")
		(hatch none 0.5)
		(connect_pads
			(clearance 0)
		)
		(min_thickness 0.25)
		(keepout
			(tracks not_allowed)
			(vias allowed)
			(pads allowed)
			(copperpour not_allowed)
			(footprints allowed)
		)
		(placement
			(enabled no)
			(sheetname "")
		)
		(fill yes
			(thermal_gap 0.5)
			(thermal_bridge_width 0.5)
			(island_removal_mode 0)
		)
		(polygon
			(pts
				(arc
					(start 60.14212 -439.760614)
					(mid 60.164438 -439.814496)
					(end 60.21832 -439.836814)
				)
				(arc
					(start 61.15812 -439.836814)
					(mid 61.212002 -439.814496)
					(end 61.23432 -439.760614)
				)
				(arc
					(start 61.23432 -437.21909)
					(mid 61.212002 -437.165208)
					(end 61.15812 -437.14289)
				)
				(arc
					(start 60.21832 -437.14289)
					(mid 60.164438 -437.165208)
					(end 60.14212 -437.21909)
				)
				(arc
					(start 60.14212 -437.946546)
					(mid 60.144119 -437.963887)
					(end 60.149994 -437.980328)
				)
				(arc
					(start 60.38342 -438.456578)
					(mid 60.391203 -438.490106)
					(end 60.38342 -438.523634)
				)
				(arc
					(start 60.149994 -438.999884)
					(mid 60.144099 -439.01632)
					(end 60.14212 -439.033666)
				)
			)
		)
	)
	(zone
		(layers "In12.Cu" "In14.Cu")
		(hatch none 0.5)
		(connect_pads
			(clearance 0)
		)
		(min_thickness 0.25)
		(keepout
			(tracks not_allowed)
			(vias allowed)
			(pads allowed)
			(copperpour not_allowed)
			(footprints allowed)
		)
		(placement
			(enabled no)
			(sheetname "")
		)
		(fill yes
			(thermal_gap 0.5)
			(thermal_bridge_width 0.5)
			(island_removal_mode 0)
		)
		(polygon
			(pts
				(arc
					(start 335.142078 -438.760616)
					(mid 335.164396 -438.814498)
					(end 335.218278 -438.836816)
				)
				(arc
					(start 336.158078 -438.836816)
					(mid 336.21196 -438.814498)
					(end 336.234278 -438.760616)
				)
				(arc
					(start 336.234278 -436.219092)
					(mid 336.21196 -436.16521)
					(end 336.158078 -436.142892)
				)
				(arc
					(start 335.218278 -436.142892)
					(mid 335.164396 -436.16521)
					(end 335.142078 -436.219092)
				)
				(arc
					(start 335.142078 -436.946548)
					(mid 335.144077 -436.963889)
					(end 335.149952 -436.98033)
				)
				(arc
					(start 335.383378 -437.45658)
					(mid 335.391161 -437.490108)
					(end 335.383378 -437.523636)
				)
				(arc
					(start 335.149952 -437.999886)
					(mid 335.144057 -438.016322)
					(end 335.142078 -438.033668)
				)
			)
		)
	)
	(zone
		(layers "In12.Cu" "In14.Cu")
		(hatch none 0.5)
		(connect_pads
			(clearance 0)
		)
		(min_thickness 0.25)
		(keepout
			(tracks not_allowed)
			(vias allowed)
			(pads allowed)
			(copperpour not_allowed)
			(footprints allowed)
		)
		(placement
			(enabled no)
			(sheetname "")
		)
		(fill yes
			(thermal_gap 0.5)
			(thermal_bridge_width 0.5)
			(island_removal_mode 0)
		)
		(polygon
			(pts
				(arc
					(start 391.242042 -436.160418)
					(mid 391.26436 -436.2143)
					(end 391.318242 -436.236618)
				)
				(arc
					(start 392.258042 -436.236618)
					(mid 392.311924 -436.2143)
					(end 392.334242 -436.160418)
				)
				(arc
					(start 392.334242 -433.618894)
					(mid 392.311924 -433.565012)
					(end 392.258042 -433.542694)
				)
				(arc
					(start 391.318242 -433.542694)
					(mid 391.26436 -433.565012)
					(end 391.242042 -433.618894)
				)
				(arc
					(start 391.242042 -434.34635)
					(mid 391.244041 -434.363691)
					(end 391.249916 -434.380132)
				)
				(arc
					(start 391.483342 -434.856382)
					(mid 391.491125 -434.88991)
					(end 391.483342 -434.923438)
				)
				(arc
					(start 391.249916 -435.399688)
					(mid 391.244021 -435.416124)
					(end 391.242042 -435.43347)
				)
			)
		)
	)
	(zone
		(layers "In12.Cu" "In14.Cu")
		(hatch none 0.5)
		(connect_pads
			(clearance 0)
		)
		(min_thickness 0.25)
		(keepout
			(tracks not_allowed)
			(vias allowed)
			(pads allowed)
			(copperpour not_allowed)
			(footprints allowed)
		)
		(placement
			(enabled no)
			(sheetname "")
		)
		(fill yes
			(thermal_gap 0.5)
			(thermal_bridge_width 0.5)
			(island_removal_mode 0)
		)
		(polygon
			(pts
				(arc
					(start 404.242016 -436.160418)
					(mid 404.264334 -436.2143)
					(end 404.318216 -436.236618)
				)
				(arc
					(start 405.258016 -436.236618)
					(mid 405.311898 -436.2143)
					(end 405.334216 -436.160418)
				)
				(arc
					(start 405.334216 -433.618894)
					(mid 405.311898 -433.565012)
					(end 405.258016 -433.542694)
				)
				(arc
					(start 404.318216 -433.542694)
					(mid 404.264334 -433.565012)
					(end 404.242016 -433.618894)
				)
				(arc
					(start 404.242016 -434.34635)
					(mid 404.244015 -434.363691)
					(end 404.24989 -434.380132)
				)
				(arc
					(start 404.483316 -434.856382)
					(mid 404.491099 -434.88991)
					(end 404.483316 -434.923438)
				)
				(arc
					(start 404.24989 -435.399688)
					(mid 404.243995 -435.416124)
					(end 404.242016 -435.43347)
				)
			)
		)
	)
	(zone
		(layers "In12.Cu" "In14.Cu")
		(hatch none 0.5)
		(connect_pads
			(clearance 0)
		)
		(min_thickness 0.25)
		(keepout
			(tracks not_allowed)
			(vias allowed)
			(pads allowed)
			(copperpour not_allowed)
			(footprints allowed)
		)
		(placement
			(enabled no)
			(sheetname "")
		)
		(fill yes
			(thermal_gap 0.5)
			(thermal_bridge_width 0.5)
			(island_removal_mode 0)
		)
		(polygon
			(pts
				(arc
					(start 83.142074 -438.760616)
					(mid 83.164392 -438.814498)
					(end 83.218274 -438.836816)
				)
				(arc
					(start 84.158074 -438.836816)
					(mid 84.211956 -438.814498)
					(end 84.234274 -438.760616)
				)
				(arc
					(start 84.234274 -436.219092)
					(mid 84.211956 -436.16521)
					(end 84.158074 -436.142892)
				)
				(arc
					(start 83.218274 -436.142892)
					(mid 83.164392 -436.16521)
					(end 83.142074 -436.219092)
				)
				(arc
					(start 83.142074 -436.946548)
					(mid 83.144073 -436.963889)
					(end 83.149948 -436.98033)
				)
				(arc
					(start 83.383374 -437.45658)
					(mid 83.391157 -437.490108)
					(end 83.383374 -437.523636)
				)
				(arc
					(start 83.149948 -437.999886)
					(mid 83.144053 -438.016322)
					(end 83.142074 -438.033668)
				)
			)
		)
	)
	(zone
		(layers "In12.Cu" "In14.Cu")
		(hatch none 0.5)
		(connect_pads
			(clearance 0)
		)
		(min_thickness 0.25)
		(keepout
			(tracks not_allowed)
			(vias allowed)
			(pads allowed)
			(copperpour not_allowed)
			(footprints allowed)
		)
		(placement
			(enabled no)
			(sheetname "")
		)
		(fill yes
			(thermal_gap 0.5)
			(thermal_bridge_width 0.5)
			(island_removal_mode 0)
		)
		(polygon
			(pts
				(arc
					(start 129.242058 -435.16042)
					(mid 129.264376 -435.214302)
					(end 129.318258 -435.23662)
				)
				(arc
					(start 130.258058 -435.23662)
					(mid 130.31194 -435.214302)
					(end 130.334258 -435.16042)
				)
				(arc
					(start 130.334258 -432.618896)
					(mid 130.31194 -432.565014)
					(end 130.258058 -432.542696)
				)
				(arc
					(start 129.318258 -432.542696)
					(mid 129.264376 -432.565014)
					(end 129.242058 -432.618896)
				)
				(arc
					(start 129.242058 -433.346352)
					(mid 129.244057 -433.363693)
					(end 129.249932 -433.380134)
				)
				(arc
					(start 129.483358 -433.856384)
					(mid 129.491141 -433.889912)
					(end 129.483358 -433.92344)
				)
				(arc
					(start 129.249932 -434.39969)
					(mid 129.244037 -434.416126)
					(end 129.242058 -434.433472)
				)
			)
		)
	)
	(zone
		(layers "In12.Cu" "In14.Cu")
		(hatch none 0.5)
		(connect_pads
			(clearance 0)
		)
		(min_thickness 0.25)
		(keepout
			(tracks not_allowed)
			(vias allowed)
			(pads allowed)
			(copperpour not_allowed)
			(footprints allowed)
		)
		(placement
			(enabled no)
			(sheetname "")
		)
		(fill yes
			(thermal_gap 0.5)
			(thermal_bridge_width 0.5)
			(island_removal_mode 0)
		)
		(polygon
			(pts
				(arc
					(start 58.142124 -438.760616)
					(mid 58.164442 -438.814498)
					(end 58.218324 -438.836816)
				)
				(arc
					(start 59.158124 -438.836816)
					(mid 59.212006 -438.814498)
					(end 59.234324 -438.760616)
				)
				(arc
					(start 59.234324 -436.219092)
					(mid 59.212006 -436.16521)
					(end 59.158124 -436.142892)
				)
				(arc
					(start 58.218324 -436.142892)
					(mid 58.164442 -436.16521)
					(end 58.142124 -436.219092)
				)
				(arc
					(start 58.142124 -436.946548)
					(mid 58.144123 -436.963889)
					(end 58.149998 -436.98033)
				)
				(arc
					(start 58.383424 -437.45658)
					(mid 58.391207 -437.490108)
					(end 58.383424 -437.523636)
				)
				(arc
					(start 58.149998 -437.999886)
					(mid 58.144103 -438.016322)
					(end 58.142124 -438.033668)
				)
			)
		)
	)
	(zone
		(layers "In12.Cu" "In14.Cu")
		(hatch none 0.5)
		(connect_pads
			(clearance 0)
		)
		(min_thickness 0.25)
		(keepout
			(tracks not_allowed)
			(vias allowed)
			(pads allowed)
			(copperpour not_allowed)
			(footprints allowed)
		)
		(placement
			(enabled no)
			(sheetname "")
		)
		(fill yes
			(thermal_gap 0.5)
			(thermal_bridge_width 0.5)
			(island_removal_mode 0)
		)
		(polygon
			(pts
				(arc
					(start 66.142108 -438.760616)
					(mid 66.164426 -438.814498)
					(end 66.218308 -438.836816)
				)
				(arc
					(start 67.158108 -438.836816)
					(mid 67.21199 -438.814498)
					(end 67.234308 -438.760616)
				)
				(arc
					(start 67.234308 -436.219092)
					(mid 67.21199 -436.16521)
					(end 67.158108 -436.142892)
				)
				(arc
					(start 66.218308 -436.142892)
					(mid 66.164426 -436.16521)
					(end 66.142108 -436.219092)
				)
				(arc
					(start 66.142108 -436.946548)
					(mid 66.144107 -436.963889)
					(end 66.149982 -436.98033)
				)
				(arc
					(start 66.383408 -437.45658)
					(mid 66.391191 -437.490108)
					(end 66.383408 -437.523636)
				)
				(arc
					(start 66.149982 -437.999886)
					(mid 66.144087 -438.016322)
					(end 66.142108 -438.033668)
				)
			)
		)
	)
	(zone
		(layers "In12.Cu" "In14.Cu")
		(hatch none 0.5)
		(connect_pads
			(clearance 0)
		)
		(min_thickness 0.25)
		(keepout
			(tracks not_allowed)
			(vias allowed)
			(pads allowed)
			(copperpour not_allowed)
			(footprints allowed)
		)
		(placement
			(enabled no)
			(sheetname "")
		)
		(fill yes
			(thermal_gap 0.5)
			(thermal_bridge_width 0.5)
			(island_removal_mode 0)
		)
		(polygon
			(pts
				(arc
					(start 339.14207 -438.760616)
					(mid 339.164388 -438.814498)
					(end 339.21827 -438.836816)
				)
				(arc
					(start 340.15807 -438.836816)
					(mid 340.211952 -438.814498)
					(end 340.23427 -438.760616)
				)
				(arc
					(start 340.23427 -436.219092)
					(mid 340.211952 -436.16521)
					(end 340.15807 -436.142892)
				)
				(arc
					(start 339.21827 -436.142892)
					(mid 339.164388 -436.16521)
					(end 339.14207 -436.219092)
				)
				(arc
					(start 339.14207 -436.946548)
					(mid 339.144069 -436.963889)
					(end 339.149944 -436.98033)
				)
				(arc
					(start 339.38337 -437.45658)
					(mid 339.391153 -437.490108)
					(end 339.38337 -437.523636)
				)
				(arc
					(start 339.149944 -437.999886)
					(mid 339.144049 -438.016322)
					(end 339.14207 -438.033668)
				)
			)
		)
	)
	(zone
		(layers "In12.Cu" "In14.Cu")
		(hatch none 0.5)
		(connect_pads
			(clearance 0)
		)
		(min_thickness 0.25)
		(keepout
			(tracks not_allowed)
			(vias allowed)
			(pads allowed)
			(copperpour not_allowed)
			(footprints allowed)
		)
		(placement
			(enabled no)
			(sheetname "")
		)
		(fill yes
			(thermal_gap 0.5)
			(thermal_bridge_width 0.5)
			(island_removal_mode 0)
		)
		(polygon
			(pts
				(arc
					(start 148.24202 -436.160418)
					(mid 148.264338 -436.2143)
					(end 148.31822 -436.236618)
				)
				(arc
					(start 149.25802 -436.236618)
					(mid 149.311902 -436.2143)
					(end 149.33422 -436.160418)
				)
				(arc
					(start 149.33422 -433.618894)
					(mid 149.311902 -433.565012)
					(end 149.25802 -433.542694)
				)
				(arc
					(start 148.31822 -433.542694)
					(mid 148.264338 -433.565012)
					(end 148.24202 -433.618894)
				)
				(arc
					(start 148.24202 -434.34635)
					(mid 148.244019 -434.363691)
					(end 148.249894 -434.380132)
				)
				(arc
					(start 148.48332 -434.856382)
					(mid 148.491103 -434.88991)
					(end 148.48332 -434.923438)
				)
				(arc
					(start 148.249894 -435.399688)
					(mid 148.243999 -435.416124)
					(end 148.24202 -435.43347)
				)
			)
		)
	)
	(zone
		(layers "In12.Cu" "In14.Cu")
		(hatch none 0.5)
		(connect_pads
			(clearance 0)
		)
		(min_thickness 0.25)
		(keepout
			(tracks not_allowed)
			(vias allowed)
			(pads allowed)
			(copperpour not_allowed)
			(footprints allowed)
		)
		(placement
			(enabled no)
			(sheetname "")
		)
		(fill yes
			(thermal_gap 0.5)
			(thermal_bridge_width 0.5)
			(island_removal_mode 0)
		)
		(polygon
			(pts
				(arc
					(start 326.142096 -438.760616)
					(mid 326.164414 -438.814498)
					(end 326.218296 -438.836816)
				)
				(arc
					(start 327.158096 -438.836816)
					(mid 327.211978 -438.814498)
					(end 327.234296 -438.760616)
				)
				(arc
					(start 327.234296 -436.219092)
					(mid 327.211978 -436.16521)
					(end 327.158096 -436.142892)
				)
				(arc
					(start 326.218296 -436.142892)
					(mid 326.164414 -436.16521)
					(end 326.142096 -436.219092)
				)
				(arc
					(start 326.142096 -436.946548)
					(mid 326.144095 -436.963889)
					(end 326.14997 -436.98033)
				)
				(arc
					(start 326.383396 -437.45658)
					(mid 326.391179 -437.490108)
					(end 326.383396 -437.523636)
				)
				(arc
					(start 326.14997 -437.999886)
					(mid 326.144075 -438.016322)
					(end 326.142096 -438.033668)
				)
			)
		)
	)
	(zone
		(layers "In12.Cu" "In14.Cu")
		(hatch none 0.5)
		(connect_pads
			(clearance 0)
		)
		(min_thickness 0.25)
		(keepout
			(tracks not_allowed)
			(vias allowed)
			(pads allowed)
			(copperpour not_allowed)
			(footprints allowed)
		)
		(placement
			(enabled no)
			(sheetname "")
		)
		(fill yes
			(thermal_gap 0.5)
			(thermal_bridge_width 0.5)
			(island_removal_mode 0)
		)
		(polygon
			(pts
				(arc
					(start 408.242008 -436.160418)
					(mid 408.264326 -436.2143)
					(end 408.318208 -436.236618)
				)
				(arc
					(start 409.258008 -436.236618)
					(mid 409.31189 -436.2143)
					(end 409.334208 -436.160418)
				)
				(arc
					(start 409.334208 -433.618894)
					(mid 409.31189 -433.565012)
					(end 409.258008 -433.542694)
				)
				(arc
					(start 408.318208 -433.542694)
					(mid 408.264326 -433.565012)
					(end 408.242008 -433.618894)
				)
				(arc
					(start 408.242008 -434.34635)
					(mid 408.244007 -434.363691)
					(end 408.249882 -434.380132)
				)
				(arc
					(start 408.483308 -434.856382)
					(mid 408.491091 -434.88991)
					(end 408.483308 -434.923438)
				)
				(arc
					(start 408.249882 -435.399688)
					(mid 408.243987 -435.416124)
					(end 408.242008 -435.43347)
				)
			)
		)
	)
	(zone
		(layers "In12.Cu" "In14.Cu")
		(hatch none 0.5)
		(connect_pads
			(clearance 0)
		)
		(min_thickness 0.25)
		(keepout
			(tracks not_allowed)
			(vias allowed)
			(pads allowed)
			(copperpour not_allowed)
			(footprints allowed)
		)
		(placement
			(enabled no)
			(sheetname "")
		)
		(fill yes
			(thermal_gap 0.5)
			(thermal_bridge_width 0.5)
			(island_removal_mode 0)
		)
		(polygon
			(pts
				(arc
					(start 314.14212 -438.760616)
					(mid 314.164438 -438.814498)
					(end 314.21832 -438.836816)
				)
				(arc
					(start 315.15812 -438.836816)
					(mid 315.212002 -438.814498)
					(end 315.23432 -438.760616)
				)
				(arc
					(start 315.23432 -436.219092)
					(mid 315.212002 -436.16521)
					(end 315.15812 -436.142892)
				)
				(arc
					(start 314.21832 -436.142892)
					(mid 314.164438 -436.16521)
					(end 314.14212 -436.219092)
				)
				(arc
					(start 314.14212 -436.946548)
					(mid 314.144119 -436.963889)
					(end 314.149994 -436.98033)
				)
				(arc
					(start 314.38342 -437.45658)
					(mid 314.391203 -437.490108)
					(end 314.38342 -437.523636)
				)
				(arc
					(start 314.149994 -437.999886)
					(mid 314.144099 -438.016322)
					(end 314.14212 -438.033668)
				)
			)
		)
	)
	(zone
		(layers "In12.Cu" "In14.Cu")
		(hatch none 0.5)
		(connect_pads
			(clearance 0)
		)
		(min_thickness 0.25)
		(keepout
			(tracks not_allowed)
			(vias allowed)
			(pads allowed)
			(copperpour not_allowed)
			(footprints allowed)
		)
		(placement
			(enabled no)
			(sheetname "")
		)
		(fill yes
			(thermal_gap 0.5)
			(thermal_bridge_width 0.5)
			(island_removal_mode 0)
		)
		(polygon
			(pts
				(arc
					(start 156.242004 -436.160418)
					(mid 156.264322 -436.2143)
					(end 156.318204 -436.236618)
				)
				(arc
					(start 157.258004 -436.236618)
					(mid 157.311886 -436.2143)
					(end 157.334204 -436.160418)
				)
				(arc
					(start 157.334204 -433.618894)
					(mid 157.311886 -433.565012)
					(end 157.258004 -433.542694)
				)
				(arc
					(start 156.318204 -433.542694)
					(mid 156.264322 -433.565012)
					(end 156.242004 -433.618894)
				)
				(arc
					(start 156.242004 -434.34635)
					(mid 156.244003 -434.363691)
					(end 156.249878 -434.380132)
				)
				(arc
					(start 156.483304 -434.856382)
					(mid 156.491087 -434.88991)
					(end 156.483304 -434.923438)
				)
				(arc
					(start 156.249878 -435.399688)
					(mid 156.243983 -435.416124)
					(end 156.242004 -435.43347)
				)
			)
		)
	)
	(zone
		(layers "In12.Cu" "In14.Cu")
		(hatch none 0.5)
		(connect_pads
			(clearance 0)
		)
		(min_thickness 0.25)
		(keepout
			(tracks not_allowed)
			(vias allowed)
			(pads allowed)
			(copperpour not_allowed)
			(footprints allowed)
		)
		(placement
			(enabled no)
			(sheetname "")
		)
		(fill yes
			(thermal_gap 0.5)
			(thermal_bridge_width 0.5)
			(island_removal_mode 0)
		)
		(polygon
			(pts
				(arc
					(start 318.142112 -438.760616)
					(mid 318.16443 -438.814498)
					(end 318.218312 -438.836816)
				)
				(arc
					(start 319.158112 -438.836816)
					(mid 319.211994 -438.814498)
					(end 319.234312 -438.760616)
				)
				(arc
					(start 319.234312 -436.219092)
					(mid 319.211994 -436.16521)
					(end 319.158112 -436.142892)
				)
				(arc
					(start 318.218312 -436.142892)
					(mid 318.16443 -436.16521)
					(end 318.142112 -436.219092)
				)
				(arc
					(start 318.142112 -436.946548)
					(mid 318.144111 -436.963889)
					(end 318.149986 -436.98033)
				)
				(arc
					(start 318.383412 -437.45658)
					(mid 318.391195 -437.490108)
					(end 318.383412 -437.523636)
				)
				(arc
					(start 318.149986 -437.999886)
					(mid 318.144091 -438.016322)
					(end 318.142112 -438.033668)
				)
			)
		)
	)
	(zone
		(layers "In12.Cu" "In14.Cu")
		(hatch none 0.5)
		(connect_pads
			(clearance 0)
		)
		(min_thickness 0.25)
		(keepout
			(tracks not_allowed)
			(vias allowed)
			(pads allowed)
			(copperpour not_allowed)
			(footprints allowed)
		)
		(placement
			(enabled no)
			(sheetname "")
		)
		(fill yes
			(thermal_gap 0.5)
			(thermal_bridge_width 0.5)
			(island_removal_mode 0)
		)
		(polygon
			(pts
				(arc
					(start 331.142086 -438.760616)
					(mid 331.164404 -438.814498)
					(end 331.218286 -438.836816)
				)
				(arc
					(start 332.158086 -438.836816)
					(mid 332.211968 -438.814498)
					(end 332.234286 -438.760616)
				)
				(arc
					(start 332.234286 -436.219092)
					(mid 332.211968 -436.16521)
					(end 332.158086 -436.142892)
				)
				(arc
					(start 331.218286 -436.142892)
					(mid 331.164404 -436.16521)
					(end 331.142086 -436.219092)
				)
				(arc
					(start 331.142086 -436.946548)
					(mid 331.144085 -436.963889)
					(end 331.14996 -436.98033)
				)
				(arc
					(start 331.383386 -437.45658)
					(mid 331.391169 -437.490108)
					(end 331.383386 -437.523636)
				)
				(arc
					(start 331.14996 -437.999886)
					(mid 331.144065 -438.016322)
					(end 331.142086 -438.033668)
				)
			)
		)
	)
	(zone
		(layers "In12.Cu" "In14.Cu")
		(hatch none 0.5)
		(connect_pads
			(clearance 0)
		)
		(min_thickness 0.25)
		(keepout
			(tracks not_allowed)
			(vias allowed)
			(pads allowed)
			(copperpour not_allowed)
			(footprints allowed)
		)
		(placement
			(enabled no)
			(sheetname "")
		)
		(fill yes
			(thermal_gap 0.5)
			(thermal_bridge_width 0.5)
			(island_removal_mode 0)
		)
		(polygon
			(pts
				(arc
					(start 343.142062 -438.760616)
					(mid 343.16438 -438.814498)
					(end 343.218262 -438.836816)
				)
				(arc
					(start 344.158062 -438.836816)
					(mid 344.211944 -438.814498)
					(end 344.234262 -438.760616)
				)
				(arc
					(start 344.234262 -436.219092)
					(mid 344.211944 -436.16521)
					(end 344.158062 -436.142892)
				)
				(arc
					(start 343.218262 -436.142892)
					(mid 343.16438 -436.16521)
					(end 343.142062 -436.219092)
				)
				(arc
					(start 343.142062 -436.946548)
					(mid 343.144061 -436.963889)
					(end 343.149936 -436.98033)
				)
				(arc
					(start 343.383362 -437.45658)
					(mid 343.391145 -437.490108)
					(end 343.383362 -437.523636)
				)
				(arc
					(start 343.149936 -437.999886)
					(mid 343.144041 -438.016322)
					(end 343.142062 -438.033668)
				)
			)
		)
	)
	(zone
		(layers "In12.Cu" "In14.Cu")
		(hatch none 0.5)
		(connect_pads
			(clearance 0)
		)
		(min_thickness 0.25)
		(keepout
			(tracks not_allowed)
			(vias allowed)
			(pads allowed)
			(copperpour not_allowed)
			(footprints allowed)
		)
		(placement
			(enabled no)
			(sheetname "")
		)
		(fill yes
			(thermal_gap 0.5)
			(thermal_bridge_width 0.5)
			(island_removal_mode 0)
		)
		(polygon
			(pts
				(arc
					(start 72.142096 -439.760614)
					(mid 72.164414 -439.814496)
					(end 72.218296 -439.836814)
				)
				(arc
					(start 73.158096 -439.836814)
					(mid 73.211978 -439.814496)
					(end 73.234296 -439.760614)
				)
				(arc
					(start 73.234296 -437.21909)
					(mid 73.211978 -437.165208)
					(end 73.158096 -437.14289)
				)
				(arc
					(start 72.218296 -437.14289)
					(mid 72.164414 -437.165208)
					(end 72.142096 -437.21909)
				)
				(arc
					(start 72.142096 -437.946546)
					(mid 72.144095 -437.963887)
					(end 72.14997 -437.980328)
				)
				(arc
					(start 72.383396 -438.456578)
					(mid 72.391179 -438.490106)
					(end 72.383396 -438.523634)
				)
				(arc
					(start 72.14997 -438.999884)
					(mid 72.144075 -439.01632)
					(end 72.142096 -439.033666)
				)
			)
		)
	)
	(zone
		(layers "In12.Cu" "In14.Cu")
		(hatch none 0.5)
		(connect_pads
			(clearance 0)
		)
		(min_thickness 0.25)
		(keepout
			(tracks not_allowed)
			(vias allowed)
			(pads allowed)
			(copperpour not_allowed)
			(footprints allowed)
		)
		(placement
			(enabled no)
			(sheetname "")
		)
		(fill yes
			(thermal_gap 0.5)
			(thermal_bridge_width 0.5)
			(island_removal_mode 0)
		)
		(polygon
			(pts
				(arc
					(start 316.142116 -439.760614)
					(mid 316.164434 -439.814496)
					(end 316.218316 -439.836814)
				)
				(arc
					(start 317.158116 -439.836814)
					(mid 317.211998 -439.814496)
					(end 317.234316 -439.760614)
				)
				(arc
					(start 317.234316 -437.21909)
					(mid 317.211998 -437.165208)
					(end 317.158116 -437.14289)
				)
				(arc
					(start 316.218316 -437.14289)
					(mid 316.164434 -437.165208)
					(end 316.142116 -437.21909)
				)
				(arc
					(start 316.142116 -437.946546)
					(mid 316.144115 -437.963887)
					(end 316.14999 -437.980328)
				)
				(arc
					(start 316.383416 -438.456578)
					(mid 316.391199 -438.490106)
					(end 316.383416 -438.523634)
				)
				(arc
					(start 316.14999 -438.999884)
					(mid 316.144095 -439.01632)
					(end 316.142116 -439.033666)
				)
			)
		)
	)
	(zone
		(layers "In12.Cu" "In14.Cu")
		(hatch none 0.5)
		(connect_pads
			(clearance 0)
		)
		(min_thickness 0.25)
		(keepout
			(tracks not_allowed)
			(vias allowed)
			(pads allowed)
			(copperpour not_allowed)
			(footprints allowed)
		)
		(placement
			(enabled no)
			(sheetname "")
		)
		(fill yes
			(thermal_gap 0.5)
			(thermal_bridge_width 0.5)
			(island_removal_mode 0)
		)
		(polygon
			(pts
				(arc
					(start 75.14209 -438.760616)
					(mid 75.164408 -438.814498)
					(end 75.21829 -438.836816)
				)
				(arc
					(start 76.15809 -438.836816)
					(mid 76.211972 -438.814498)
					(end 76.23429 -438.760616)
				)
				(arc
					(start 76.23429 -436.219092)
					(mid 76.211972 -436.16521)
					(end 76.15809 -436.142892)
				)
				(arc
					(start 75.21829 -436.142892)
					(mid 75.164408 -436.16521)
					(end 75.14209 -436.219092)
				)
				(arc
					(start 75.14209 -436.946548)
					(mid 75.144089 -436.963889)
					(end 75.149964 -436.98033)
				)
				(arc
					(start 75.38339 -437.45658)
					(mid 75.391173 -437.490108)
					(end 75.38339 -437.523636)
				)
				(arc
					(start 75.149964 -437.999886)
					(mid 75.144069 -438.016322)
					(end 75.14209 -438.033668)
				)
			)
		)
	)
	(zone
		(layers "In12.Cu" "In14.Cu")
		(hatch none 0.5)
		(connect_pads
			(clearance 0)
		)
		(min_thickness 0.25)
		(keepout
			(tracks not_allowed)
			(vias allowed)
			(pads allowed)
			(copperpour not_allowed)
			(footprints allowed)
		)
		(placement
			(enabled no)
			(sheetname "")
		)
		(fill yes
			(thermal_gap 0.5)
			(thermal_bridge_width 0.5)
			(island_removal_mode 0)
		)
		(polygon
			(pts
				(arc
					(start 127.242062 -436.160418)
					(mid 127.26438 -436.2143)
					(end 127.318262 -436.236618)
				)
				(arc
					(start 128.258062 -436.236618)
					(mid 128.311944 -436.2143)
					(end 128.334262 -436.160418)
				)
				(arc
					(start 128.334262 -433.618894)
					(mid 128.311944 -433.565012)
					(end 128.258062 -433.542694)
				)
				(arc
					(start 127.318262 -433.542694)
					(mid 127.26438 -433.565012)
					(end 127.242062 -433.618894)
				)
				(arc
					(start 127.242062 -434.34635)
					(mid 127.244061 -434.363691)
					(end 127.249936 -434.380132)
				)
				(arc
					(start 127.483362 -434.856382)
					(mid 127.491145 -434.88991)
					(end 127.483362 -434.923438)
				)
				(arc
					(start 127.249936 -435.399688)
					(mid 127.244041 -435.416124)
					(end 127.242062 -435.43347)
				)
			)
		)
	)
	(zone
		(layers "In12.Cu" "In14.Cu")
		(hatch none 0.5)
		(connect_pads
			(clearance 0)
		)
		(min_thickness 0.25)
		(keepout
			(tracks not_allowed)
			(vias allowed)
			(pads allowed)
			(copperpour not_allowed)
			(footprints allowed)
		)
		(placement
			(enabled no)
			(sheetname "")
		)
		(fill yes
			(thermal_gap 0.5)
			(thermal_bridge_width 0.5)
			(island_removal_mode 0)
		)
		(polygon
			(pts
				(arc
					(start 328.142092 -439.760614)
					(mid 328.16441 -439.814496)
					(end 328.218292 -439.836814)
				)
				(arc
					(start 329.158092 -439.836814)
					(mid 329.211974 -439.814496)
					(end 329.234292 -439.760614)
				)
				(arc
					(start 329.234292 -437.21909)
					(mid 329.211974 -437.165208)
					(end 329.158092 -437.14289)
				)
				(arc
					(start 328.218292 -437.14289)
					(mid 328.16441 -437.165208)
					(end 328.142092 -437.21909)
				)
				(arc
					(start 328.142092 -437.946546)
					(mid 328.144091 -437.963887)
					(end 328.149966 -437.980328)
				)
				(arc
					(start 328.383392 -438.456578)
					(mid 328.391175 -438.490106)
					(end 328.383392 -438.523634)
				)
				(arc
					(start 328.149966 -438.999884)
					(mid 328.144071 -439.01632)
					(end 328.142092 -439.033666)
				)
			)
		)
	)
	(zone
		(layers "In12.Cu" "In14.Cu")
		(hatch none 0.5)
		(connect_pads
			(clearance 0)
		)
		(min_thickness 0.25)
		(keepout
			(tracks not_allowed)
			(vias allowed)
			(pads allowed)
			(copperpour not_allowed)
			(footprints allowed)
		)
		(placement
			(enabled no)
			(sheetname "")
		)
		(fill yes
			(thermal_gap 0.5)
			(thermal_bridge_width 0.5)
			(island_removal_mode 0)
		)
		(polygon
			(pts
				(arc
					(start 125.242066 -435.16042)
					(mid 125.264384 -435.214302)
					(end 125.318266 -435.23662)
				)
				(arc
					(start 126.258066 -435.23662)
					(mid 126.311948 -435.214302)
					(end 126.334266 -435.16042)
				)
				(arc
					(start 126.334266 -432.618896)
					(mid 126.311948 -432.565014)
					(end 126.258066 -432.542696)
				)
				(arc
					(start 125.318266 -432.542696)
					(mid 125.264384 -432.565014)
					(end 125.242066 -432.618896)
				)
				(arc
					(start 125.242066 -433.346352)
					(mid 125.244065 -433.363693)
					(end 125.24994 -433.380134)
				)
				(arc
					(start 125.483366 -433.856384)
					(mid 125.491149 -433.889912)
					(end 125.483366 -433.92344)
				)
				(arc
					(start 125.24994 -434.39969)
					(mid 125.244045 -434.416126)
					(end 125.242066 -434.433472)
				)
			)
		)
	)
	(zone
		(layers "In12.Cu" "In14.Cu")
		(hatch none 0.5)
		(connect_pads
			(clearance 0)
		)
		(min_thickness 0.25)
		(keepout
			(tracks not_allowed)
			(vias allowed)
			(pads allowed)
			(copperpour not_allowed)
			(footprints allowed)
		)
		(placement
			(enabled no)
			(sheetname "")
		)
		(fill yes
			(thermal_gap 0.5)
			(thermal_bridge_width 0.5)
			(island_removal_mode 0)
		)
		(polygon
			(pts
				(arc
					(start 62.142116 -438.760616)
					(mid 62.164434 -438.814498)
					(end 62.218316 -438.836816)
				)
				(arc
					(start 63.158116 -438.836816)
					(mid 63.211998 -438.814498)
					(end 63.234316 -438.760616)
				)
				(arc
					(start 63.234316 -436.219092)
					(mid 63.211998 -436.16521)
					(end 63.158116 -436.142892)
				)
				(arc
					(start 62.218316 -436.142892)
					(mid 62.164434 -436.16521)
					(end 62.142116 -436.219092)
				)
				(arc
					(start 62.142116 -436.946548)
					(mid 62.144115 -436.963889)
					(end 62.14999 -436.98033)
				)
				(arc
					(start 62.383416 -437.45658)
					(mid 62.391199 -437.490108)
					(end 62.383416 -437.523636)
				)
				(arc
					(start 62.14999 -437.999886)
					(mid 62.144095 -438.016322)
					(end 62.142116 -438.033668)
				)
			)
		)
	)
	(zone
		(layers "In12.Cu" "In14.Cu")
		(hatch none 0.5)
		(connect_pads
			(clearance 0)
		)
		(min_thickness 0.25)
		(keepout
			(tracks not_allowed)
			(vias allowed)
			(pads allowed)
			(copperpour not_allowed)
			(footprints allowed)
		)
		(placement
			(enabled no)
			(sheetname "")
		)
		(fill yes
			(thermal_gap 0.5)
			(thermal_bridge_width 0.5)
			(island_removal_mode 0)
		)
		(polygon
			(pts
				(arc
					(start 87.142066 -438.760616)
					(mid 87.164384 -438.814498)
					(end 87.218266 -438.836816)
				)
				(arc
					(start 88.158066 -438.836816)
					(mid 88.211948 -438.814498)
					(end 88.234266 -438.760616)
				)
				(arc
					(start 88.234266 -436.219092)
					(mid 88.211948 -436.16521)
					(end 88.158066 -436.142892)
				)
				(arc
					(start 87.218266 -436.142892)
					(mid 87.164384 -436.16521)
					(end 87.142066 -436.219092)
				)
				(arc
					(start 87.142066 -436.946548)
					(mid 87.144065 -436.963889)
					(end 87.14994 -436.98033)
				)
				(arc
					(start 87.383366 -437.45658)
					(mid 87.391149 -437.490108)
					(end 87.383366 -437.523636)
				)
				(arc
					(start 87.14994 -437.999886)
					(mid 87.144045 -438.016322)
					(end 87.142066 -438.033668)
				)
			)
		)
	)
	(zone
		(layers "In12.Cu" "In14.Cu")
		(hatch none 0.5)
		(connect_pads
			(clearance 0)
		)
		(min_thickness 0.25)
		(keepout
			(tracks not_allowed)
			(vias allowed)
			(pads allowed)
			(copperpour not_allowed)
			(footprints allowed)
		)
		(placement
			(enabled no)
			(sheetname "")
		)
		(fill yes
			(thermal_gap 0.5)
			(thermal_bridge_width 0.5)
			(island_removal_mode 0)
		)
		(polygon
			(pts
				(arc
					(start 150.242016 -435.16042)
					(mid 150.264334 -435.214302)
					(end 150.318216 -435.23662)
				)
				(arc
					(start 151.258016 -435.23662)
					(mid 151.311898 -435.214302)
					(end 151.334216 -435.16042)
				)
				(arc
					(start 151.334216 -432.618896)
					(mid 151.311898 -432.565014)
					(end 151.258016 -432.542696)
				)
				(arc
					(start 150.318216 -432.542696)
					(mid 150.264334 -432.565014)
					(end 150.242016 -432.618896)
				)
				(arc
					(start 150.242016 -433.346352)
					(mid 150.244015 -433.363693)
					(end 150.24989 -433.380134)
				)
				(arc
					(start 150.483316 -433.856384)
					(mid 150.491099 -433.889912)
					(end 150.483316 -433.92344)
				)
				(arc
					(start 150.24989 -434.39969)
					(mid 150.243995 -434.416126)
					(end 150.242016 -434.433472)
				)
			)
		)
	)
	(zone
		(layers "In12.Cu" "In14.Cu")
		(hatch none 0.5)
		(connect_pads
			(clearance 0)
		)
		(min_thickness 0.25)
		(keepout
			(tracks not_allowed)
			(vias allowed)
			(pads allowed)
			(copperpour not_allowed)
			(footprints allowed)
		)
		(placement
			(enabled no)
			(sheetname "")
		)
		(fill yes
			(thermal_gap 0.5)
			(thermal_bridge_width 0.5)
			(island_removal_mode 0)
		)
		(polygon
			(pts
				(arc
					(start 400.242024 -436.160418)
					(mid 400.264342 -436.2143)
					(end 400.318224 -436.236618)
				)
				(arc
					(start 401.258024 -436.236618)
					(mid 401.311906 -436.2143)
					(end 401.334224 -436.160418)
				)
				(arc
					(start 401.334224 -433.618894)
					(mid 401.311906 -433.565012)
					(end 401.258024 -433.542694)
				)
				(arc
					(start 400.318224 -433.542694)
					(mid 400.264342 -433.565012)
					(end 400.242024 -433.618894)
				)
				(arc
					(start 400.242024 -434.34635)
					(mid 400.244023 -434.363691)
					(end 400.249898 -434.380132)
				)
				(arc
					(start 400.483324 -434.856382)
					(mid 400.491107 -434.88991)
					(end 400.483324 -434.923438)
				)
				(arc
					(start 400.249898 -435.399688)
					(mid 400.244003 -435.416124)
					(end 400.242024 -435.43347)
				)
			)
		)
	)
	(zone
		(layers "In12.Cu" "In14.Cu")
		(hatch none 0.5)
		(connect_pads
			(clearance 0)
		)
		(min_thickness 0.25)
		(keepout
			(tracks not_allowed)
			(vias allowed)
			(pads allowed)
			(copperpour not_allowed)
			(footprints allowed)
		)
		(placement
			(enabled no)
			(sheetname "")
		)
		(fill yes
			(thermal_gap 0.5)
			(thermal_bridge_width 0.5)
			(island_removal_mode 0)
		)
		(polygon
			(pts
				(arc
					(start 85.14207 -439.760614)
					(mid 85.164388 -439.814496)
					(end 85.21827 -439.836814)
				)
				(arc
					(start 86.15807 -439.836814)
					(mid 86.211952 -439.814496)
					(end 86.23427 -439.760614)
				)
				(arc
					(start 86.23427 -437.21909)
					(mid 86.211952 -437.165208)
					(end 86.15807 -437.14289)
				)
				(arc
					(start 85.21827 -437.14289)
					(mid 85.164388 -437.165208)
					(end 85.14207 -437.21909)
				)
				(arc
					(start 85.14207 -437.946546)
					(mid 85.144069 -437.963887)
					(end 85.149944 -437.980328)
				)
				(arc
					(start 85.38337 -438.456578)
					(mid 85.391153 -438.490106)
					(end 85.38337 -438.523634)
				)
				(arc
					(start 85.149944 -438.999884)
					(mid 85.144049 -439.01632)
					(end 85.14207 -439.033666)
				)
			)
		)
	)
	(zone
		(layers "In12.Cu" "In14.Cu")
		(hatch none 0.5)
		(connect_pads
			(clearance 0)
		)
		(min_thickness 0.25)
		(keepout
			(tracks not_allowed)
			(vias allowed)
			(pads allowed)
			(copperpour not_allowed)
			(footprints allowed)
		)
		(placement
			(enabled no)
			(sheetname "")
		)
		(fill yes
			(thermal_gap 0.5)
			(thermal_bridge_width 0.5)
			(island_removal_mode 0)
		)
		(polygon
			(pts
				(arc
					(start 402.24202 -435.16042)
					(mid 402.264338 -435.214302)
					(end 402.31822 -435.23662)
				)
				(arc
					(start 403.25802 -435.23662)
					(mid 403.311902 -435.214302)
					(end 403.33422 -435.16042)
				)
				(arc
					(start 403.33422 -432.618896)
					(mid 403.311902 -432.565014)
					(end 403.25802 -432.542696)
				)
				(arc
					(start 402.31822 -432.542696)
					(mid 402.264338 -432.565014)
					(end 402.24202 -432.618896)
				)
				(arc
					(start 402.24202 -433.346352)
					(mid 402.244019 -433.363693)
					(end 402.249894 -433.380134)
				)
				(arc
					(start 402.48332 -433.856384)
					(mid 402.491103 -433.889912)
					(end 402.48332 -433.92344)
				)
				(arc
					(start 402.249894 -434.39969)
					(mid 402.243999 -434.416126)
					(end 402.24202 -434.433472)
				)
			)
		)
	)
	(zone
		(layers "In12.Cu" "In14.Cu")
		(hatch none 0.5)
		(connect_pads
			(clearance 0)
		)
		(min_thickness 0.25)
		(keepout
			(tracks not_allowed)
			(vias allowed)
			(pads allowed)
			(copperpour not_allowed)
			(footprints allowed)
		)
		(placement
			(enabled no)
			(sheetname "")
		)
		(fill yes
			(thermal_gap 0.5)
			(thermal_bridge_width 0.5)
			(island_removal_mode 0)
		)
		(polygon
			(pts
				(arc
					(start 154.242008 -435.16042)
					(mid 154.264326 -435.214302)
					(end 154.318208 -435.23662)
				)
				(arc
					(start 155.258008 -435.23662)
					(mid 155.31189 -435.214302)
					(end 155.334208 -435.16042)
				)
				(arc
					(start 155.334208 -432.618896)
					(mid 155.31189 -432.565014)
					(end 155.258008 -432.542696)
				)
				(arc
					(start 154.318208 -432.542696)
					(mid 154.264326 -432.565014)
					(end 154.242008 -432.618896)
				)
				(arc
					(start 154.242008 -433.346352)
					(mid 154.244007 -433.363693)
					(end 154.249882 -433.380134)
				)
				(arc
					(start 154.483308 -433.856384)
					(mid 154.491091 -433.889912)
					(end 154.483308 -433.92344)
				)
				(arc
					(start 154.249882 -434.39969)
					(mid 154.243987 -434.416126)
					(end 154.242008 -434.433472)
				)
			)
		)
	)
	(zone
		(layers "In12.Cu" "In14.Cu")
		(hatch none 0.5)
		(connect_pads
			(clearance 0)
		)
		(min_thickness 0.25)
		(keepout
			(tracks not_allowed)
			(vias allowed)
			(pads allowed)
			(copperpour not_allowed)
			(footprints allowed)
		)
		(placement
			(enabled no)
			(sheetname "")
		)
		(fill yes
			(thermal_gap 0.5)
			(thermal_bridge_width 0.5)
			(island_removal_mode 0)
		)
		(polygon
			(pts
				(arc
					(start 398.242028 -435.16042)
					(mid 398.264346 -435.214302)
					(end 398.318228 -435.23662)
				)
				(arc
					(start 399.258028 -435.23662)
					(mid 399.31191 -435.214302)
					(end 399.334228 -435.16042)
				)
				(arc
					(start 399.334228 -432.618896)
					(mid 399.31191 -432.565014)
					(end 399.258028 -432.542696)
				)
				(arc
					(start 398.318228 -432.542696)
					(mid 398.264346 -432.565014)
					(end 398.242028 -432.618896)
				)
				(arc
					(start 398.242028 -433.346352)
					(mid 398.244027 -433.363693)
					(end 398.249902 -433.380134)
				)
				(arc
					(start 398.483328 -433.856384)
					(mid 398.491111 -433.889912)
					(end 398.483328 -433.92344)
				)
				(arc
					(start 398.249902 -434.39969)
					(mid 398.244007 -434.416126)
					(end 398.242028 -434.433472)
				)
			)
		)
	)
	(zone
		(layers "In12.Cu" "In14.Cu")
		(hatch none 0.5)
		(connect_pads
			(clearance 0)
		)
		(min_thickness 0.25)
		(keepout
			(tracks not_allowed)
			(vias allowed)
			(pads allowed)
			(copperpour not_allowed)
			(footprints allowed)
		)
		(placement
			(enabled no)
			(sheetname "")
		)
		(fill yes
			(thermal_gap 0.5)
			(thermal_bridge_width 0.5)
			(island_removal_mode 0)
		)
		(polygon
			(pts
				(arc
					(start 320.142108 -439.760614)
					(mid 320.164426 -439.814496)
					(end 320.218308 -439.836814)
				)
				(arc
					(start 321.158108 -439.836814)
					(mid 321.21199 -439.814496)
					(end 321.234308 -439.760614)
				)
				(arc
					(start 321.234308 -437.21909)
					(mid 321.21199 -437.165208)
					(end 321.158108 -437.14289)
				)
				(arc
					(start 320.218308 -437.14289)
					(mid 320.164426 -437.165208)
					(end 320.142108 -437.21909)
				)
				(arc
					(start 320.142108 -437.946546)
					(mid 320.144107 -437.963887)
					(end 320.149982 -437.980328)
				)
				(arc
					(start 320.383408 -438.456578)
					(mid 320.391191 -438.490106)
					(end 320.383408 -438.523634)
				)
				(arc
					(start 320.149982 -438.999884)
					(mid 320.144087 -439.01632)
					(end 320.142108 -439.033666)
				)
			)
		)
	)
	(zone
		(layers "In12.Cu" "In14.Cu")
		(hatch none 0.5)
		(connect_pads
			(clearance 0)
		)
		(min_thickness 0.25)
		(keepout
			(tracks not_allowed)
			(vias allowed)
			(pads allowed)
			(copperpour not_allowed)
			(footprints allowed)
		)
		(placement
			(enabled no)
			(sheetname "")
		)
		(fill yes
			(thermal_gap 0.5)
			(thermal_bridge_width 0.5)
			(island_removal_mode 0)
		)
		(polygon
			(pts
				(arc
					(start 412.242 -436.160418)
					(mid 412.264318 -436.2143)
					(end 412.3182 -436.236618)
				)
				(arc
					(start 413.258 -436.236618)
					(mid 413.311882 -436.2143)
					(end 413.3342 -436.160418)
				)
				(arc
					(start 413.3342 -433.618894)
					(mid 413.311882 -433.565012)
					(end 413.258 -433.542694)
				)
				(arc
					(start 412.3182 -433.542694)
					(mid 412.264318 -433.565012)
					(end 412.242 -433.618894)
				)
				(arc
					(start 412.242 -434.34635)
					(mid 412.243999 -434.363691)
					(end 412.249874 -434.380132)
				)
				(arc
					(start 412.4833 -434.856382)
					(mid 412.491083 -434.88991)
					(end 412.4833 -434.923438)
				)
				(arc
					(start 412.249874 -435.399688)
					(mid 412.243979 -435.416124)
					(end 412.242 -435.43347)
				)
			)
		)
	)
	(zone
		(layers "In12.Cu" "In14.Cu")
		(hatch none 0.5)
		(connect_pads
			(clearance 0)
		)
		(min_thickness 0.25)
		(keepout
			(tracks not_allowed)
			(vias allowed)
			(pads allowed)
			(copperpour not_allowed)
			(footprints allowed)
		)
		(placement
			(enabled no)
			(sheetname "")
		)
		(fill yes
			(thermal_gap 0.5)
			(thermal_bridge_width 0.5)
			(island_removal_mode 0)
		)
		(polygon
			(pts
				(arc
					(start 144.242028 -436.160418)
					(mid 144.264346 -436.2143)
					(end 144.318228 -436.236618)
				)
				(arc
					(start 145.258028 -436.236618)
					(mid 145.31191 -436.2143)
					(end 145.334228 -436.160418)
				)
				(arc
					(start 145.334228 -433.618894)
					(mid 145.31191 -433.565012)
					(end 145.258028 -433.542694)
				)
				(arc
					(start 144.318228 -433.542694)
					(mid 144.264346 -433.565012)
					(end 144.242028 -433.618894)
				)
				(arc
					(start 144.242028 -434.34635)
					(mid 144.244027 -434.363691)
					(end 144.249902 -434.380132)
				)
				(arc
					(start 144.483328 -434.856382)
					(mid 144.491111 -434.88991)
					(end 144.483328 -434.923438)
				)
				(arc
					(start 144.249902 -435.399688)
					(mid 144.244007 -435.416124)
					(end 144.242028 -435.43347)
				)
			)
		)
	)
	(zone
		(layers "In12.Cu" "In14.Cu")
		(hatch none 0.5)
		(connect_pads
			(clearance 0)
		)
		(min_thickness 0.25)
		(keepout
			(tracks not_allowed)
			(vias allowed)
			(pads allowed)
			(copperpour not_allowed)
			(footprints allowed)
		)
		(placement
			(enabled no)
			(sheetname "")
		)
		(fill yes
			(thermal_gap 0.5)
			(thermal_bridge_width 0.5)
			(island_removal_mode 0)
		)
		(polygon
			(pts
				(arc
					(start 322.142104 -438.760616)
					(mid 322.164422 -438.814498)
					(end 322.218304 -438.836816)
				)
				(arc
					(start 323.158104 -438.836816)
					(mid 323.211986 -438.814498)
					(end 323.234304 -438.760616)
				)
				(arc
					(start 323.234304 -436.219092)
					(mid 323.211986 -436.16521)
					(end 323.158104 -436.142892)
				)
				(arc
					(start 322.218304 -436.142892)
					(mid 322.164422 -436.16521)
					(end 322.142104 -436.219092)
				)
				(arc
					(start 322.142104 -436.946548)
					(mid 322.144103 -436.963889)
					(end 322.149978 -436.98033)
				)
				(arc
					(start 322.383404 -437.45658)
					(mid 322.391187 -437.490108)
					(end 322.383404 -437.523636)
				)
				(arc
					(start 322.149978 -437.999886)
					(mid 322.144083 -438.016322)
					(end 322.142104 -438.033668)
				)
			)
		)
	)
	(zone
		(layers "In12.Cu" "In14.Cu")
		(hatch none 0.5)
		(connect_pads
			(clearance 0)
		)
		(min_thickness 0.25)
		(keepout
			(tracks not_allowed)
			(vias allowed)
			(pads allowed)
			(copperpour not_allowed)
			(footprints allowed)
		)
		(placement
			(enabled no)
			(sheetname "")
		)
		(fill yes
			(thermal_gap 0.5)
			(thermal_bridge_width 0.5)
			(island_removal_mode 0)
		)
		(polygon
			(pts
				(arc
					(start 324.1421 -439.760614)
					(mid 324.164418 -439.814496)
					(end 324.2183 -439.836814)
				)
				(arc
					(start 325.1581 -439.836814)
					(mid 325.211982 -439.814496)
					(end 325.2343 -439.760614)
				)
				(arc
					(start 325.2343 -437.21909)
					(mid 325.211982 -437.165208)
					(end 325.1581 -437.14289)
				)
				(arc
					(start 324.2183 -437.14289)
					(mid 324.164418 -437.165208)
					(end 324.1421 -437.21909)
				)
				(arc
					(start 324.1421 -437.946546)
					(mid 324.144099 -437.963887)
					(end 324.149974 -437.980328)
				)
				(arc
					(start 324.3834 -438.456578)
					(mid 324.391183 -438.490106)
					(end 324.3834 -438.523634)
				)
				(arc
					(start 324.149974 -438.999884)
					(mid 324.144079 -439.01632)
					(end 324.1421 -439.033666)
				)
			)
		)
	)
	(zone
		(layers "In12.Cu" "In14.Cu")
		(hatch none 0.5)
		(connect_pads
			(clearance 0)
		)
		(min_thickness 0.25)
		(keepout
			(tracks not_allowed)
			(vias allowed)
			(pads allowed)
			(copperpour not_allowed)
			(footprints allowed)
		)
		(placement
			(enabled no)
			(sheetname "")
		)
		(fill yes
			(thermal_gap 0.5)
			(thermal_bridge_width 0.5)
			(island_removal_mode 0)
		)
		(polygon
			(pts
				(arc
					(start 137.242042 -435.16042)
					(mid 137.26436 -435.214302)
					(end 137.318242 -435.23662)
				)
				(arc
					(start 138.258042 -435.23662)
					(mid 138.311924 -435.214302)
					(end 138.334242 -435.16042)
				)
				(arc
					(start 138.334242 -432.618896)
					(mid 138.311924 -432.565014)
					(end 138.258042 -432.542696)
				)
				(arc
					(start 137.318242 -432.542696)
					(mid 137.26436 -432.565014)
					(end 137.242042 -432.618896)
				)
				(arc
					(start 137.242042 -433.346352)
					(mid 137.244041 -433.363693)
					(end 137.249916 -433.380134)
				)
				(arc
					(start 137.483342 -433.856384)
					(mid 137.491125 -433.889912)
					(end 137.483342 -433.92344)
				)
				(arc
					(start 137.249916 -434.39969)
					(mid 137.244021 -434.416126)
					(end 137.242042 -434.433472)
				)
			)
		)
	)
	(zone
		(layers "In12.Cu" "In14.Cu")
		(hatch none 0.5)
		(connect_pads
			(clearance 0)
		)
		(min_thickness 0.25)
		(keepout
			(tracks not_allowed)
			(vias allowed)
			(pads allowed)
			(copperpour not_allowed)
			(footprints allowed)
		)
		(placement
			(enabled no)
			(sheetname "")
		)
		(fill yes
			(thermal_gap 0.5)
			(thermal_bridge_width 0.5)
			(island_removal_mode 0)
		)
		(polygon
			(pts
				(arc
					(start 345.142058 -439.760614)
					(mid 345.164376 -439.814496)
					(end 345.218258 -439.836814)
				)
				(arc
					(start 346.158058 -439.836814)
					(mid 346.21194 -439.814496)
					(end 346.234258 -439.760614)
				)
				(arc
					(start 346.234258 -437.21909)
					(mid 346.21194 -437.165208)
					(end 346.158058 -437.14289)
				)
				(arc
					(start 345.218258 -437.14289)
					(mid 345.164376 -437.165208)
					(end 345.142058 -437.21909)
				)
				(arc
					(start 345.142058 -437.946546)
					(mid 345.144057 -437.963887)
					(end 345.149932 -437.980328)
				)
				(arc
					(start 345.383358 -438.456578)
					(mid 345.391141 -438.490106)
					(end 345.383358 -438.523634)
				)
				(arc
					(start 345.149932 -438.999884)
					(mid 345.144037 -439.01632)
					(end 345.142058 -439.033666)
				)
			)
		)
	)
	(zone
		(layers "In12.Cu" "In14.Cu")
		(hatch none 0.5)
		(connect_pads
			(clearance 0)
		)
		(min_thickness 0.25)
		(keepout
			(tracks not_allowed)
			(vias allowed)
			(pads allowed)
			(copperpour not_allowed)
			(footprints allowed)
		)
		(placement
			(enabled no)
			(sheetname "")
		)
		(fill yes
			(thermal_gap 0.5)
			(thermal_bridge_width 0.5)
			(island_removal_mode 0)
		)
		(polygon
			(pts
				(arc
					(start 152.242012 -436.160418)
					(mid 152.26433 -436.2143)
					(end 152.318212 -436.236618)
				)
				(arc
					(start 153.258012 -436.236618)
					(mid 153.311894 -436.2143)
					(end 153.334212 -436.160418)
				)
				(arc
					(start 153.334212 -433.618894)
					(mid 153.311894 -433.565012)
					(end 153.258012 -433.542694)
				)
				(arc
					(start 152.318212 -433.542694)
					(mid 152.26433 -433.565012)
					(end 152.242012 -433.618894)
				)
				(arc
					(start 152.242012 -434.34635)
					(mid 152.244011 -434.363691)
					(end 152.249886 -434.380132)
				)
				(arc
					(start 152.483312 -434.856382)
					(mid 152.491095 -434.88991)
					(end 152.483312 -434.923438)
				)
				(arc
					(start 152.249886 -435.399688)
					(mid 152.243991 -435.416124)
					(end 152.242012 -435.43347)
				)
			)
		)
	)
	(zone
		(layers "In12.Cu" "In14.Cu")
		(hatch none 0.5)
		(connect_pads
			(clearance 0)
		)
		(min_thickness 0.25)
		(keepout
			(tracks not_allowed)
			(vias allowed)
			(pads allowed)
			(copperpour not_allowed)
			(footprints allowed)
		)
		(placement
			(enabled no)
			(sheetname "")
		)
		(fill yes
			(thermal_gap 0.5)
			(thermal_bridge_width 0.5)
			(island_removal_mode 0)
		)
		(polygon
			(pts
				(arc
					(start 68.142104 -439.760614)
					(mid 68.164422 -439.814496)
					(end 68.218304 -439.836814)
				)
				(arc
					(start 69.158104 -439.836814)
					(mid 69.211986 -439.814496)
					(end 69.234304 -439.760614)
				)
				(arc
					(start 69.234304 -437.21909)
					(mid 69.211986 -437.165208)
					(end 69.158104 -437.14289)
				)
				(arc
					(start 68.218304 -437.14289)
					(mid 68.164422 -437.165208)
					(end 68.142104 -437.21909)
				)
				(arc
					(start 68.142104 -437.946546)
					(mid 68.144103 -437.963887)
					(end 68.149978 -437.980328)
				)
				(arc
					(start 68.383404 -438.456578)
					(mid 68.391187 -438.490106)
					(end 68.383404 -438.523634)
				)
				(arc
					(start 68.149978 -438.999884)
					(mid 68.144083 -439.01632)
					(end 68.142104 -439.033666)
				)
			)
		)
	)
	(zone
		(layers "In12.Cu" "In14.Cu")
		(hatch none 0.5)
		(connect_pads
			(clearance 0)
		)
		(min_thickness 0.25)
		(keepout
			(tracks not_allowed)
			(vias allowed)
			(pads allowed)
			(copperpour not_allowed)
			(footprints allowed)
		)
		(placement
			(enabled no)
			(sheetname "")
		)
		(fill yes
			(thermal_gap 0.5)
			(thermal_bridge_width 0.5)
			(island_removal_mode 0)
		)
		(polygon
			(pts
				(arc
					(start 337.142074 -439.760614)
					(mid 337.164392 -439.814496)
					(end 337.218274 -439.836814)
				)
				(arc
					(start 338.158074 -439.836814)
					(mid 338.211956 -439.814496)
					(end 338.234274 -439.760614)
				)
				(arc
					(start 338.234274 -437.21909)
					(mid 338.211956 -437.165208)
					(end 338.158074 -437.14289)
				)
				(arc
					(start 337.218274 -437.14289)
					(mid 337.164392 -437.165208)
					(end 337.142074 -437.21909)
				)
				(arc
					(start 337.142074 -437.946546)
					(mid 337.144073 -437.963887)
					(end 337.149948 -437.980328)
				)
				(arc
					(start 337.383374 -438.456578)
					(mid 337.391157 -438.490106)
					(end 337.383374 -438.523634)
				)
				(arc
					(start 337.149948 -438.999884)
					(mid 337.144053 -439.01632)
					(end 337.142074 -439.033666)
				)
			)
		)
	)
	(zone
		(layer "In13.Cu")
		(hatch none 0.5)
		(connect_pads
			(clearance 0)
		)
		(min_thickness 0.25)
		(keepout
			(tracks allowed)
			(vias allowed)
			(pads allowed)
			(copperpour allowed)
			(footprints allowed)
		)
		(placement
			(enabled no)
			(sheetname "")
		)
		(fill
			(thermal_gap 0.5)
			(thermal_bridge_width 0.5)
			(island_removal_mode 0)
		)
		(polygon
			(pts
				(xy 372.97868 -341.516208) (xy 372.97868 -339.862668) (xy 377.84278 -339.862668) (xy 377.84278 -341.516208)
			)
		)
	)
	(zone
		(layer "In13.Cu")
		(hatch none 0.5)
		(connect_pads
			(clearance 0)
		)
		(min_thickness 0.25)
		(keepout
			(tracks allowed)
			(vias allowed)
			(pads allowed)
			(copperpour allowed)
			(footprints allowed)
		)
		(placement
			(enabled no)
			(sheetname "")
		)
		(fill
			(thermal_gap 0.5)
			(thermal_bridge_width 0.5)
			(island_removal_mode 0)
		)
		(polygon
			(pts
				(xy 430.539906 -18.182336) (xy 430.539906 -16.206216) (xy 432.503326 -16.206216) (xy 432.503326 -18.182336)
			)
		)
	)
	(zone
		(layer "In13.Cu")
		(hatch none 0.5)
		(connect_pads
			(clearance 0)
		)
		(min_thickness 0.25)
		(keepout
			(tracks allowed)
			(vias allowed)
			(pads allowed)
			(copperpour allowed)
			(footprints allowed)
		)
		(placement
			(enabled no)
			(sheetname "")
		)
		(fill
			(thermal_gap 0.5)
			(thermal_bridge_width 0.5)
			(island_removal_mode 0)
		)
		(polygon
			(pts
				(xy 333.045816 -291.07892) (xy 333.045816 -257.177286) (xy 334.160114 -256.062988) (xy 334.160114 -247.016778)
				(xy 333.045816 -245.90248) (xy 333.045816 -212.839554) (xy 387.975602 -212.839554) (xy 387.975602 -244.483636)
				(xy 384.85826 -247.600978) (xy 384.85826 -252.996954) (xy 386.631688 -254.770382) (xy 386.631688 -256.290318)
				(xy 386.809234 -256.467864) (xy 386.860796 -256.467864) (xy 387.975602 -257.58267) (xy 387.975602 -291.07892)
			)
		)
	)
	(zone
		(layer "In13.Cu")
		(hatch none 0.5)
		(connect_pads
			(clearance 0)
		)
		(min_thickness 0.25)
		(keepout
			(tracks allowed)
			(vias allowed)
			(pads allowed)
			(copperpour allowed)
			(footprints allowed)
		)
		(placement
			(enabled no)
			(sheetname "")
		)
		(fill
			(thermal_gap 0.5)
			(thermal_bridge_width 0.5)
			(island_removal_mode 0)
		)
		(polygon
			(pts
				(xy 326.62114 -347.937328) (xy 326.62114 -346.232988) (xy 329.21702 -346.232988) (xy 329.21702 -347.937328)
			)
		)
	)
	(zone
		(layer "In13.Cu")
		(hatch none 0.5)
		(connect_pads
			(clearance 0)
		)
		(min_thickness 0.25)
		(keepout
			(tracks allowed)
			(vias allowed)
			(pads allowed)
			(copperpour allowed)
			(footprints allowed)
		)
		(placement
			(enabled no)
			(sheetname "")
		)
		(fill
			(thermal_gap 0.5)
			(thermal_bridge_width 0.5)
			(island_removal_mode 0)
		)
		(polygon
			(pts
				(xy 424.58386 -367.111788) (xy 424.58386 -365.704628) (xy 426.24756 -365.704628) (xy 426.24756 -367.111788)
			)
		)
	)
	(zone
		(layer "In13.Cu")
		(hatch none 0.5)
		(connect_pads
			(clearance 0)
		)
		(min_thickness 0.25)
		(keepout
			(tracks allowed)
			(vias allowed)
			(pads allowed)
			(copperpour allowed)
			(footprints allowed)
		)
		(placement
			(enabled no)
			(sheetname "")
		)
		(fill
			(thermal_gap 0.5)
			(thermal_bridge_width 0.5)
			(island_removal_mode 0)
		)
		(polygon
			(pts
				(xy 433.333906 -18.182336) (xy 433.333906 -16.206216) (xy 435.297326 -16.206216) (xy 435.297326 -18.182336)
			)
		)
	)
	(zone
		(layer "In13.Cu")
		(hatch none 0.5)
		(connect_pads
			(clearance 0)
		)
		(min_thickness 0.25)
		(keepout
			(tracks allowed)
			(vias allowed)
			(pads allowed)
			(copperpour allowed)
			(footprints allowed)
		)
		(placement
			(enabled no)
			(sheetname "")
		)
		(fill
			(thermal_gap 0.5)
			(thermal_bridge_width 0.5)
			(island_removal_mode 0)
		)
		(polygon
			(pts
				(xy 422.12387 -18.182336) (xy 422.12387 -16.206216) (xy 424.08729 -16.206216) (xy 424.08729 -18.182336)
			)
		)
	)
	(zone
		(layer "In13.Cu")
		(hatch none 0.5)
		(connect_pads
			(clearance 0)
		)
		(min_thickness 0.25)
		(keepout
			(tracks allowed)
			(vias allowed)
			(pads allowed)
			(copperpour allowed)
			(footprints allowed)
		)
		(placement
			(enabled no)
			(sheetname "")
		)
		(fill
			(thermal_gap 0.5)
			(thermal_bridge_width 0.5)
			(island_removal_mode 0)
		)
		(polygon
			(pts
				(xy 911.530054 -83.354164) (xy 911.530054 -68.258944) (xy 929.589454 -68.258944) (xy 929.589454 -85.205824)
				(xy 929.210994 -85.205824) (xy 929.063674 -85.353144) (xy 912.833074 -85.353144) (xy 911.931374 -84.451444)
				(xy 911.931374 -83.755484)
			)
		)
	)
	(zone
		(layer "In13.Cu")
		(hatch none 0.5)
		(connect_pads
			(clearance 0)
		)
		(min_thickness 0.25)
		(keepout
			(tracks allowed)
			(vias allowed)
			(pads allowed)
			(copperpour allowed)
			(footprints allowed)
		)
		(placement
			(enabled no)
			(sheetname "")
		)
		(fill
			(thermal_gap 0.5)
			(thermal_bridge_width 0.5)
			(island_removal_mode 0)
		)
		(polygon
			(pts
				(xy 40.154606 -5.774436) (xy 40.154606 -4.021836) (xy 45.666406 -4.021836) (xy 45.666406 -5.774436)
			)
		)
	)
	(zone
		(layer "In13.Cu")
		(hatch none 0.5)
		(connect_pads
			(clearance 0)
		)
		(min_thickness 0.25)
		(keepout
			(tracks allowed)
			(vias allowed)
			(pads allowed)
			(copperpour allowed)
			(footprints allowed)
		)
		(placement
			(enabled no)
			(sheetname "")
		)
		(fill
			(thermal_gap 0.5)
			(thermal_bridge_width 0.5)
			(island_removal_mode 0)
		)
		(polygon
			(pts
				(xy 51.457606 -5.723636) (xy 51.457606 -4.021836) (xy 56.842406 -4.021836) (xy 56.842406 -5.723636)
			)
		)
	)
	(zone
		(layer "In13.Cu")
		(hatch none 0.5)
		(connect_pads
			(clearance 0)
		)
		(min_thickness 0.25)
		(keepout
			(tracks allowed)
			(vias allowed)
			(pads allowed)
			(copperpour allowed)
			(footprints allowed)
		)
		(placement
			(enabled no)
			(sheetname "")
		)
		(fill
			(thermal_gap 0.5)
			(thermal_bridge_width 0.5)
			(island_removal_mode 0)
		)
		(polygon
			(pts
				(xy 419.32987 -18.182336) (xy 419.32987 -16.206216) (xy 421.29329 -16.206216) (xy 421.29329 -18.182336)
			)
		)
	)
	(zone
		(layer "In13.Cu")
		(hatch none 0.5)
		(connect_pads
			(clearance 0)
		)
		(min_thickness 0.25)
		(keepout
			(tracks allowed)
			(vias allowed)
			(pads allowed)
			(copperpour allowed)
			(footprints allowed)
		)
		(placement
			(enabled no)
			(sheetname "")
		)
		(fill
			(thermal_gap 0.5)
			(thermal_bridge_width 0.5)
			(island_removal_mode 0)
		)
		(polygon
			(pts
				(xy 413.74187 -18.182336) (xy 413.74187 -16.206216) (xy 415.70529 -16.206216) (xy 415.70529 -18.182336)
			)
		)
	)
	(zone
		(layer "In13.Cu")
		(hatch none 0.5)
		(connect_pads
			(clearance 0)
		)
		(min_thickness 0.25)
		(keepout
			(tracks allowed)
			(vias allowed)
			(pads allowed)
			(copperpour allowed)
			(footprints allowed)
		)
		(placement
			(enabled no)
			(sheetname "")
		)
		(fill
			(thermal_gap 0.5)
			(thermal_bridge_width 0.5)
			(island_removal_mode 0)
		)
		(polygon
			(pts
				(xy 356.14356 -338.206588) (xy 356.14356 -335.293208) (xy 369.75796 -335.293208) (xy 369.75796 -338.206588)
			)
		)
	)
	(zone
		(layer "In13.Cu")
		(hatch none 0.5)
		(connect_pads
			(clearance 0)
		)
		(min_thickness 0.25)
		(keepout
			(tracks allowed)
			(vias allowed)
			(pads allowed)
			(copperpour allowed)
			(footprints allowed)
		)
		(placement
			(enabled no)
			(sheetname "")
		)
		(fill
			(thermal_gap 0.5)
			(thermal_bridge_width 0.5)
			(island_removal_mode 0)
		)
		(polygon
			(pts
				(xy 76.61656 -350.789748) (xy 76.61656 -349.235268) (xy 77.39888 -349.235268) (xy 77.39888 -350.789748)
			)
		)
	)
	(zone
		(layer "In13.Cu")
		(hatch none 0.5)
		(connect_pads
			(clearance 0)
		)
		(min_thickness 0.25)
		(keepout
			(tracks allowed)
			(vias allowed)
			(pads allowed)
			(copperpour allowed)
			(footprints allowed)
		)
		(placement
			(enabled no)
			(sheetname "")
		)
		(fill
			(thermal_gap 0.5)
			(thermal_bridge_width 0.5)
			(island_removal_mode 0)
		)
		(polygon
			(pts
				(xy 340.33206 -339.060028) (xy 340.33206 -335.651348) (xy 353.19208 -335.651348) (xy 353.19208 -339.060028)
			)
		)
	)
	(zone
		(layer "In13.Cu")
		(hatch none 0.5)
		(connect_pads
			(clearance 0)
		)
		(min_thickness 0.25)
		(keepout
			(tracks allowed)
			(vias allowed)
			(pads allowed)
			(copperpour allowed)
			(footprints allowed)
		)
		(placement
			(enabled no)
			(sheetname "")
		)
		(fill
			(thermal_gap 0.5)
			(thermal_bridge_width 0.5)
			(island_removal_mode 0)
		)
		(polygon
			(pts
				(xy 85.105748 -291.07892) (xy 85.105748 -257.177286) (xy 86.220046 -256.062988) (xy 86.220046 -247.016778)
				(xy 85.105748 -245.90248) (xy 85.105748 -224.790508) (xy 84.18322 -223.86798) (xy 84.18322 -222.535496)
				(xy 85.105748 -221.612968) (xy 85.105748 -212.839554) (xy 140.035534 -212.839554) (xy 140.035534 -244.483636)
				(xy 136.918192 -247.600978) (xy 136.918192 -252.996954) (xy 138.69162 -254.770382) (xy 138.69162 -256.290318)
				(xy 138.869166 -256.467864) (xy 138.920728 -256.467864) (xy 140.035534 -257.58267) (xy 140.035534 -291.07892)
			)
		)
	)
	(zone
		(layer "In13.Cu")
		(hatch none 0.5)
		(connect_pads
			(clearance 0)
		)
		(min_thickness 0.25)
		(keepout
			(tracks allowed)
			(vias allowed)
			(pads allowed)
			(copperpour allowed)
			(footprints allowed)
		)
		(placement
			(enabled no)
			(sheetname "")
		)
		(fill
			(thermal_gap 0.5)
			(thermal_bridge_width 0.5)
			(island_removal_mode 0)
		)
		(polygon
			(pts
				(xy 331.52334 -223.436688) (xy 331.52334 -221.955868) (xy 332.78572 -221.955868) (xy 332.78572 -223.436688)
			)
		)
	)
	(zone
		(layer "In13.Cu")
		(hatch none 0.5)
		(connect_pads
			(clearance 0)
		)
		(min_thickness 0.25)
		(keepout
			(tracks allowed)
			(vias allowed)
			(pads allowed)
			(copperpour allowed)
			(footprints allowed)
		)
		(placement
			(enabled no)
			(sheetname "")
		)
		(fill
			(thermal_gap 0.5)
			(thermal_bridge_width 0.5)
			(island_removal_mode 0)
		)
		(polygon
			(pts
				(xy 40.2971 -358.397048) (xy 40.2971 -357.088948) (xy 42.19956 -357.088948) (xy 42.19956 -358.397048)
			)
		)
	)
	(zone
		(layer "In13.Cu")
		(hatch none 0.5)
		(connect_pads
			(clearance 0)
		)
		(min_thickness 0.25)
		(keepout
			(tracks allowed)
			(vias allowed)
			(pads allowed)
			(copperpour allowed)
			(footprints allowed)
		)
		(placement
			(enabled no)
			(sheetname "")
		)
		(fill
			(thermal_gap 0.5)
			(thermal_bridge_width 0.5)
			(island_removal_mode 0)
		)
		(polygon
			(pts
				(xy 93.4974 -337.909408) (xy 93.4974 -336.382868) (xy 96.94418 -336.382868) (xy 96.94418 -337.909408)
			)
		)
	)
	(zone
		(layer "In13.Cu")
		(hatch none 0.5)
		(connect_pads
			(clearance 0)
		)
		(min_thickness 0.25)
		(keepout
			(tracks allowed)
			(vias allowed)
			(pads allowed)
			(copperpour allowed)
			(footprints allowed)
		)
		(placement
			(enabled no)
			(sheetname "")
		)
		(fill
			(thermal_gap 0.5)
			(thermal_bridge_width 0.5)
			(island_removal_mode 0)
		)
		(polygon
			(pts
				(xy 414.96742 -366.870488) (xy 414.96742 -365.722408) (xy 416.36442 -365.722408) (xy 416.36442 -366.870488)
			)
		)
	)
	(zone
		(layer "In13.Cu")
		(hatch none 0.5)
		(connect_pads
			(clearance 0)
		)
		(min_thickness 0.25)
		(keepout
			(tracks allowed)
			(vias allowed)
			(pads allowed)
			(copperpour allowed)
			(footprints allowed)
		)
		(placement
			(enabled no)
			(sheetname "")
		)
		(fill
			(thermal_gap 0.5)
			(thermal_bridge_width 0.5)
			(island_removal_mode 0)
		)
		(polygon
			(pts
				(xy 180.4162 -358.209088) (xy 180.4162 -356.873048) (xy 182.1307 -356.873048) (xy 182.1307 -358.209088)
			)
		)
	)
	(zone
		(layer "In13.Cu")
		(hatch none 0.5)
		(connect_pads
			(clearance 0)
		)
		(min_thickness 0.25)
		(keepout
			(tracks allowed)
			(vias allowed)
			(pads allowed)
			(copperpour allowed)
			(footprints allowed)
		)
		(placement
			(enabled no)
			(sheetname "")
		)
		(fill
			(thermal_gap 0.5)
			(thermal_bridge_width 0.5)
			(island_removal_mode 0)
		)
		(polygon
			(pts
				(xy 424.91787 -18.182336) (xy 424.91787 -16.206216) (xy 426.88129 -16.206216) (xy 426.88129 -18.182336)
			)
		)
	)
	(zone
		(layer "In13.Cu")
		(hatch none 0.5)
		(connect_pads
			(clearance 0)
		)
		(min_thickness 0.25)
		(keepout
			(tracks allowed)
			(vias allowed)
			(pads allowed)
			(copperpour allowed)
			(footprints allowed)
		)
		(placement
			(enabled no)
			(sheetname "")
		)
		(fill
			(thermal_gap 0.5)
			(thermal_bridge_width 0.5)
			(island_removal_mode 0)
		)
		(polygon
			(pts
				(xy 427.745906 -18.182336) (xy 427.745906 -16.206216) (xy 429.709326 -16.206216) (xy 429.709326 -18.182336)
			)
		)
	)
	(zone
		(layer "In13.Cu")
		(hatch none 0.5)
		(connect_pads
			(clearance 0)
		)
		(min_thickness 0.25)
		(keepout
			(tracks allowed)
			(vias allowed)
			(pads allowed)
			(copperpour allowed)
			(footprints allowed)
		)
		(placement
			(enabled no)
			(sheetname "")
		)
		(fill
			(thermal_gap 0.5)
			(thermal_bridge_width 0.5)
			(island_removal_mode 0)
		)
		(polygon
			(pts
				(xy 134.00024 -347.777308) (xy 134.00024 -345.618308) (xy 138.3792 -345.618308) (xy 138.3792 -347.777308)
			)
		)
	)
	(zone
		(layer "In13.Cu")
		(hatch none 0.5)
		(connect_pads
			(clearance 0)
		)
		(min_thickness 0.25)
		(keepout
			(tracks allowed)
			(vias allowed)
			(pads allowed)
			(copperpour allowed)
			(footprints allowed)
		)
		(placement
			(enabled no)
			(sheetname "")
		)
		(fill
			(thermal_gap 0.5)
			(thermal_bridge_width 0.5)
			(island_removal_mode 0)
		)
		(polygon
			(pts
				(xy 296.95648 -367.632488) (xy 296.95648 -366.245648) (xy 298.72178 -366.245648) (xy 298.72178 -367.632488)
			)
		)
	)
	(zone
		(layer "In13.Cu")
		(hatch none 0.5)
		(connect_pads
			(clearance 0)
		)
		(min_thickness 0.25)
		(keepout
			(tracks allowed)
			(vias allowed)
			(pads allowed)
			(copperpour allowed)
			(footprints allowed)
		)
		(placement
			(enabled no)
			(sheetname "")
		)
		(fill
			(thermal_gap 0.5)
			(thermal_bridge_width 0.5)
			(island_removal_mode 0)
		)
		(polygon
			(pts
				(xy 410.94787 -18.182336) (xy 410.94787 -16.206216) (xy 412.91129 -16.206216) (xy 412.91129 -18.182336)
			)
		)
	)
	(zone
		(layer "In13.Cu")
		(hatch none 0.5)
		(connect_pads
			(clearance 0)
		)
		(min_thickness 0.25)
		(keepout
			(tracks allowed)
			(vias allowed)
			(pads allowed)
			(copperpour allowed)
			(footprints allowed)
		)
		(placement
			(enabled no)
			(sheetname "")
		)
		(fill
			(thermal_gap 0.5)
			(thermal_bridge_width 0.5)
			(island_removal_mode 0)
		)
		(polygon
			(pts
				(xy 116.3828 -339.217508) (xy 116.3828 -335.135728) (xy 122.05208 -335.135728) (xy 122.05208 -339.217508)
			)
		)
	)
	(zone
		(layer "In13.Cu")
		(hatch none 0.5)
		(connect_pads
			(clearance 0)
		)
		(min_thickness 0.25)
		(keepout
			(tracks allowed)
			(vias allowed)
			(pads allowed)
			(copperpour allowed)
			(footprints allowed)
		)
		(placement
			(enabled no)
			(sheetname "")
		)
		(fill
			(thermal_gap 0.5)
			(thermal_bridge_width 0.5)
			(island_removal_mode 0)
		)
		(polygon
			(pts
				(xy 356.613206 -354.646992) (xy 359.742486 -354.646992) (xy 360.032046 -354.936552) (xy 360.032046 -355.256592)
				(xy 359.839006 -355.449632) (xy 359.056686 -355.449632) (xy 358.985566 -355.378512) (xy 356.953566 -355.378512)
				(xy 356.112826 -356.219252) (xy 356.112826 -361.662472) (xy 357.151686 -362.701332) (xy 357.151686 -363.150912)
				(xy 357.146606 -363.155992) (xy 357.146606 -365.556292) (xy 358.703626 -367.113312) (xy 365.719106 -367.113312)
				(xy 375.399046 -376.793252) (xy 425.388786 -376.793252) (xy 428.073566 -374.108472) (xy 428.073566 -370.125752)
				(xy 427.560486 -369.612672) (xy 423.669206 -369.612672) (xy 422.411906 -368.355372) (xy 422.411906 -366.869472)
				(xy 423.714926 -365.566452) (xy 423.951146 -365.566452) (xy 424.123866 -365.739172) (xy 424.123866 -366.760252)
				(xy 423.989246 -366.894872) (xy 423.458386 -366.894872) (xy 423.189146 -367.164112) (xy 423.189146 -367.997232)
				(xy 424.131486 -368.939572) (xy 427.865286 -368.939572) (xy 428.774606 -369.848892) (xy 428.774606 -374.425972)
				(xy 425.726606 -377.473972) (xy 375.033286 -377.473972) (xy 365.401606 -367.842292) (xy 358.439466 -367.842292)
				(xy 356.453186 -365.856012) (xy 356.453186 -363.059472) (xy 355.355906 -361.962192) (xy 355.355906 -355.904292)
			)
		)
	)
	(zone
		(layer "In13.Cu")
		(hatch none 0.5)
		(connect_pads
			(clearance 0)
		)
		(min_thickness 0.25)
		(keepout
			(tracks allowed)
			(vias allowed)
			(pads allowed)
			(copperpour allowed)
			(footprints allowed)
		)
		(placement
			(enabled no)
			(sheetname "")
		)
		(fill
			(thermal_gap 0.5)
			(thermal_bridge_width 0.5)
			(island_removal_mode 0)
		)
		(polygon
			(pts
				(xy 170.67784 -358.249728) (xy 170.67784 -356.931468) (xy 172.39996 -356.931468) (xy 172.39996 -358.249728)
			)
		)
	)
	(zone
		(layer "In13.Cu")
		(hatch none 0.5)
		(connect_pads
			(clearance 0)
		)
		(min_thickness 0.25)
		(keepout
			(tracks allowed)
			(vias allowed)
			(pads allowed)
			(copperpour allowed)
			(footprints allowed)
		)
		(placement
			(enabled no)
			(sheetname "")
		)
		(fill
			(thermal_gap 0.5)
			(thermal_bridge_width 0.5)
			(island_removal_mode 0)
		)
		(polygon
			(pts
				(xy 405.35987 -18.182336) (xy 405.35987 -16.206216) (xy 407.32329 -16.206216) (xy 407.32329 -18.182336)
			)
		)
	)
	(zone
		(layer "In13.Cu")
		(hatch none 0.5)
		(connect_pads
			(clearance 0)
		)
		(min_thickness 0.25)
		(keepout
			(tracks allowed)
			(vias allowed)
			(pads allowed)
			(copperpour allowed)
			(footprints allowed)
		)
		(placement
			(enabled no)
			(sheetname "")
		)
		(fill
			(thermal_gap 0.5)
			(thermal_bridge_width 0.5)
			(island_removal_mode 0)
		)
		(polygon
			(pts
				(xy 332.30566 -217.068908) (xy 332.30566 -216.245948) (xy 333.84744 -216.245948) (xy 333.84744 -217.068908)
			)
		)
	)
	(zone
		(layer "In13.Cu")
		(hatch none 0.5)
		(connect_pads
			(clearance 0)
		)
		(min_thickness 0.25)
		(keepout
			(tracks allowed)
			(vias allowed)
			(pads allowed)
			(copperpour allowed)
			(footprints allowed)
		)
		(placement
			(enabled no)
			(sheetname "")
		)
		(fill
			(thermal_gap 0.5)
			(thermal_bridge_width 0.5)
			(island_removal_mode 0)
		)
		(polygon
			(pts
				(xy 86.90864 -341.567008) (xy 86.90864 -340.297008) (xy 89.15908 -340.297008) (xy 89.15908 -341.567008)
			)
		)
	)
	(zone
		(layer "In13.Cu")
		(hatch none 0.5)
		(connect_pads
			(clearance 0)
		)
		(min_thickness 0.25)
		(keepout
			(tracks allowed)
			(vias allowed)
			(pads allowed)
			(copperpour allowed)
			(footprints allowed)
		)
		(placement
			(enabled no)
			(sheetname "")
		)
		(fill
			(thermal_gap 0.5)
			(thermal_bridge_width 0.5)
			(island_removal_mode 0)
		)
		(polygon
			(pts
				(xy 287.28924 -367.574068) (xy 287.28924 -366.306608) (xy 289.0139 -366.306608) (xy 289.0139 -367.574068)
			)
		)
	)
	(zone
		(layer "In13.Cu")
		(hatch none 0.5)
		(connect_pads
			(clearance 0)
		)
		(min_thickness 0.25)
		(keepout
			(tracks allowed)
			(vias allowed)
			(pads allowed)
			(copperpour allowed)
			(footprints allowed)
		)
		(placement
			(enabled no)
			(sheetname "")
		)
		(fill
			(thermal_gap 0.5)
			(thermal_bridge_width 0.5)
			(island_removal_mode 0)
		)
		(polygon
			(pts
				(xy 399.77187 -18.182336) (xy 399.77187 -16.206216) (xy 401.73529 -16.206216) (xy 401.73529 -18.182336)
			)
		)
	)
	(zone
		(layer "In13.Cu")
		(hatch none 0.5)
		(connect_pads
			(clearance 0)
		)
		(min_thickness 0.25)
		(keepout
			(tracks allowed)
			(vias allowed)
			(pads allowed)
			(copperpour allowed)
			(footprints allowed)
		)
		(placement
			(enabled no)
			(sheetname "")
		)
		(fill
			(thermal_gap 0.5)
			(thermal_bridge_width 0.5)
			(island_removal_mode 0)
		)
		(polygon
			(pts
				(xy 110.96498 -365.275368) (xy 110.96498 -363.588808) (xy 112.9157 -363.588808) (xy 112.9157 -365.275368)
			)
		)
	)
	(zone
		(layer "In13.Cu")
		(hatch none 0.5)
		(connect_pads
			(clearance 0)
		)
		(min_thickness 0.25)
		(keepout
			(tracks allowed)
			(vias allowed)
			(pads allowed)
			(copperpour allowed)
			(footprints allowed)
		)
		(placement
			(enabled no)
			(sheetname "")
		)
		(fill
			(thermal_gap 0.5)
			(thermal_bridge_width 0.5)
			(island_removal_mode 0)
		)
		(polygon
			(pts
				(xy 360.334306 -355.698552) (xy 366.161066 -355.698552) (xy 367.687606 -354.172012) (xy 371.667786 -354.172012)
				(xy 372.097046 -354.601272) (xy 378.071126 -354.601272) (xy 392.455146 -368.985292) (xy 410.575506 -368.985292)
				(xy 413.981646 -365.579152) (xy 414.337246 -365.579152) (xy 414.428686 -365.670592) (xy 414.428686 -366.709452)
				(xy 414.334706 -366.803432) (xy 413.770826 -366.803432) (xy 410.915866 -369.658392) (xy 392.142726 -369.658392)
				(xy 377.791726 -355.307392) (xy 371.815106 -355.307392) (xy 371.398546 -354.890832) (xy 367.939066 -354.890832)
				(xy 366.382046 -356.447852) (xy 360.626406 -356.447852) (xy 360.275886 -356.097332) (xy 360.275886 -355.756972)
			)
		)
	)
	(zone
		(layer "In13.Cu")
		(hatch none 0.5)
		(connect_pads
			(clearance 0)
		)
		(min_thickness 0.25)
		(keepout
			(tracks allowed)
			(vias allowed)
			(pads allowed)
			(copperpour allowed)
			(footprints allowed)
		)
		(placement
			(enabled no)
			(sheetname "")
		)
		(fill
			(thermal_gap 0.5)
			(thermal_bridge_width 0.5)
			(island_removal_mode 0)
		)
		(polygon
			(pts
				(xy 116.23802 -355.097588) (xy 116.23802 -353.494848) (xy 117.1702 -353.494848) (xy 117.1702 -355.097588)
			)
		)
	)
	(zone
		(layer "In13.Cu")
		(hatch none 0.5)
		(connect_pads
			(clearance 0)
		)
		(min_thickness 0.25)
		(keepout
			(tracks allowed)
			(vias allowed)
			(pads allowed)
			(copperpour allowed)
			(footprints allowed)
		)
		(placement
			(enabled no)
			(sheetname "")
		)
		(fill
			(thermal_gap 0.5)
			(thermal_bridge_width 0.5)
			(island_removal_mode 0)
		)
		(polygon
			(pts
				(xy 396.97787 -18.182336) (xy 396.97787 -16.206216) (xy 398.94129 -16.206216) (xy 398.94129 -18.182336)
			)
		)
	)
	(zone
		(layer "In13.Cu")
		(hatch none 0.5)
		(connect_pads
			(clearance 0)
		)
		(min_thickness 0.25)
		(keepout
			(tracks allowed)
			(vias allowed)
			(pads allowed)
			(copperpour allowed)
			(footprints allowed)
		)
		(placement
			(enabled no)
			(sheetname "")
		)
		(fill
			(thermal_gap 0.5)
			(thermal_bridge_width 0.5)
			(island_removal_mode 0)
		)
		(polygon
			(pts
				(xy 328.57948 -57.368948) (xy 328.57948 -39.436548) (xy 345.29268 -39.436548) (xy 345.29268 -57.368948)
			)
		)
	)
	(zone
		(layer "In13.Cu")
		(hatch none 0.5)
		(connect_pads
			(clearance 0)
		)
		(min_thickness 0.25)
		(keepout
			(tracks allowed)
			(vias allowed)
			(pads allowed)
			(copperpour allowed)
			(footprints allowed)
		)
		(placement
			(enabled no)
			(sheetname "")
		)
		(fill
			(thermal_gap 0.5)
			(thermal_bridge_width 0.5)
			(island_removal_mode 0)
		)
		(polygon
			(pts
				(xy 352.171 -351.729548) (xy 352.171 -351.008188) (xy 353.42068 -351.008188) (xy 353.42068 -351.729548)
			)
		)
	)
	(zone
		(layer "In13.Cu")
		(hatch none 0.5)
		(connect_pads
			(clearance 0)
		)
		(min_thickness 0.25)
		(keepout
			(tracks allowed)
			(vias allowed)
			(pads allowed)
			(copperpour allowed)
			(footprints allowed)
		)
		(placement
			(enabled no)
			(sheetname "")
		)
		(fill
			(thermal_gap 0.5)
			(thermal_bridge_width 0.5)
			(island_removal_mode 0)
		)
		(polygon
			(pts
				(xy 416.53587 -18.182336) (xy 416.53587 -16.206216) (xy 418.49929 -16.206216) (xy 418.49929 -18.182336)
			)
		)
	)
	(zone
		(layer "In13.Cu")
		(hatch none 0.5)
		(connect_pads
			(clearance 0)
		)
		(min_thickness 0.25)
		(keepout
			(tracks allowed)
			(vias allowed)
			(pads allowed)
			(copperpour allowed)
			(footprints allowed)
		)
		(placement
			(enabled no)
			(sheetname "")
		)
		(fill
			(thermal_gap 0.5)
			(thermal_bridge_width 0.5)
			(island_removal_mode 0)
		)
		(polygon
			(pts
				(xy 394.18387 -18.182336) (xy 394.18387 -16.206216) (xy 396.14729 -16.206216) (xy 396.14729 -18.182336)
			)
		)
	)
	(zone
		(layer "In13.Cu")
		(hatch none 0.5)
		(connect_pads
			(clearance 0)
		)
		(min_thickness 0.25)
		(keepout
			(tracks allowed)
			(vias allowed)
			(pads allowed)
			(copperpour allowed)
			(footprints allowed)
		)
		(placement
			(enabled no)
			(sheetname "")
		)
		(fill
			(thermal_gap 0.5)
			(thermal_bridge_width 0.5)
			(island_removal_mode 0)
		)
		(polygon
			(pts
				(xy 408.15387 -18.182336) (xy 408.15387 -16.206216) (xy 410.11729 -16.206216) (xy 410.11729 -18.182336)
			)
		)
	)
	(zone
		(layer "In13.Cu")
		(hatch none 0.5)
		(connect_pads
			(clearance 0)
		)
		(min_thickness 0.25)
		(keepout
			(tracks allowed)
			(vias allowed)
			(pads allowed)
			(copperpour allowed)
			(footprints allowed)
		)
		(placement
			(enabled no)
			(sheetname "")
		)
		(fill
			(thermal_gap 0.5)
			(thermal_bridge_width 0.5)
			(island_removal_mode 0)
		)
		(polygon
			(pts
				(xy 335.3181 -341.673688) (xy 335.3181 -340.723728) (xy 337.16214 -340.723728) (xy 337.16214 -341.673688)
			)
		)
	)
	(zone
		(layer "In13.Cu")
		(hatch none 0.5)
		(connect_pads
			(clearance 0)
		)
		(min_thickness 0.25)
		(keepout
			(tracks allowed)
			(vias allowed)
			(pads allowed)
			(copperpour allowed)
			(footprints allowed)
		)
		(placement
			(enabled no)
			(sheetname "")
		)
		(fill
			(thermal_gap 0.5)
			(thermal_bridge_width 0.5)
			(island_removal_mode 0)
		)
		(polygon
			(pts
				(xy 79.3115 -347.856048) (xy 79.3115 -346.499688) (xy 80.71612 -346.499688) (xy 80.71612 -347.856048)
			)
		)
	)
	(zone
		(layer "In13.Cu")
		(hatch none 0.5)
		(connect_pads
			(clearance 0)
		)
		(min_thickness 0.25)
		(keepout
			(tracks allowed)
			(vias allowed)
			(pads allowed)
			(copperpour allowed)
			(footprints allowed)
		)
		(placement
			(enabled no)
			(sheetname "")
		)
		(fill
			(thermal_gap 0.5)
			(thermal_bridge_width 0.5)
			(island_removal_mode 0)
		)
		(polygon
			(pts
				(xy 50.04308 -358.341168) (xy 50.04308 -357.571548) (xy 51.36134 -357.571548) (xy 51.36134 -358.341168)
			)
		)
	)
	(zone
		(layer "In13.Cu")
		(hatch none 0.5)
		(connect_pads
			(clearance 0)
		)
		(min_thickness 0.25)
		(keepout
			(tracks allowed)
			(vias allowed)
			(pads allowed)
			(copperpour allowed)
			(footprints allowed)
		)
		(placement
			(enabled no)
			(sheetname "")
		)
		(fill
			(thermal_gap 0.5)
			(thermal_bridge_width 0.5)
			(island_removal_mode 0)
		)
		(polygon
			(pts
				(xy 436.127906 -18.182336) (xy 436.127906 -16.206216) (xy 438.091326 -16.206216) (xy 438.091326 -18.182336)
			)
		)
	)
	(zone
		(layer "In13.Cu")
		(hatch none 0.5)
		(connect_pads
			(clearance 0)
		)
		(min_thickness 0.25)
		(keepout
			(tracks allowed)
			(vias allowed)
			(pads allowed)
			(copperpour allowed)
			(footprints allowed)
		)
		(placement
			(enabled no)
			(sheetname "")
		)
		(fill
			(thermal_gap 0.5)
			(thermal_bridge_width 0.5)
			(island_removal_mode 0)
		)
		(polygon
			(pts
				(xy 402.56587 -18.182336) (xy 402.56587 -16.206216) (xy 404.52929 -16.206216) (xy 404.52929 -18.182336)
			)
		)
	)
	(zone
		(layer "In13.Cu")
		(hatch none 0.5)
		(connect_pads
			(clearance 0)
		)
		(min_thickness 0.25)
		(keepout
			(tracks allowed)
			(vias allowed)
			(pads allowed)
			(copperpour allowed)
			(footprints allowed)
		)
		(placement
			(enabled no)
			(sheetname "")
		)
		(fill
			(thermal_gap 0.5)
			(thermal_bridge_width 0.5)
			(island_removal_mode 0)
		)
		(polygon
			(pts
				(xy 104.11968 -351.790508) (xy 104.11968 -351.145348) (xy 105.45572 -351.145348) (xy 105.45572 -351.790508)
			)
		)
	)
	(zone
		(layer "In13.Cu")
		(hatch none 0.5)
		(connect_pads
			(clearance 0)
		)
		(min_thickness 0.25)
		(keepout
			(tracks allowed)
			(vias allowed)
			(pads allowed)
			(copperpour allowed)
			(footprints allowed)
		)
		(placement
			(enabled no)
			(sheetname "")
		)
		(fill
			(thermal_gap 0.5)
			(thermal_bridge_width 0.5)
			(island_removal_mode 0)
		)
		(polygon
			(pts
				(xy 20.012406 -5.672836) (xy 20.012406 -4.047236) (xy 33.042606 -4.047236) (xy 33.042606 -5.672836)
			)
		)
	)
	(zone
		(layer "In13.Cu")
		(hatch none 0.5)
		(connect_pads
			(clearance 0)
		)
		(min_thickness 0.25)
		(keepout
			(tracks allowed)
			(vias allowed)
			(pads allowed)
			(copperpour allowed)
			(footprints allowed)
		)
		(placement
			(enabled no)
			(sheetname "")
		)
		(fill
			(thermal_gap 0.5)
			(thermal_bridge_width 0.5)
			(island_removal_mode 0)
		)
		(polygon
			(pts
				(xy 321.9069 -348.889828) (xy 321.9069 -347.185488) (xy 322.79844 -347.185488) (xy 322.79844 -348.889828)
			)
		)
	)
	(zone
		(layer "In13.Cu")
		(hatch none 0.5)
		(connect_pads
			(clearance 0)
		)
		(min_thickness 0.25)
		(keepout
			(tracks allowed)
			(vias allowed)
			(pads allowed)
			(copperpour allowed)
			(footprints allowed)
		)
		(placement
			(enabled no)
			(sheetname "")
		)
		(fill
			(thermal_gap 0.5)
			(thermal_bridge_width 0.5)
			(island_removal_mode 0)
		)
		(polygon
			(pts
				(xy 126.29134 -342.189308) (xy 126.29134 -339.672168) (xy 130.23342 -339.672168) (xy 130.23342 -342.189308)
			)
		)
	)
	(zone
		(layer "In13.Cu")
		(hatch none 0.5)
		(connect_pads
			(clearance 0)
		)
		(min_thickness 0.25)
		(keepout
			(tracks allowed)
			(vias allowed)
			(pads allowed)
			(copperpour allowed)
			(footprints allowed)
		)
		(placement
			(enabled no)
			(sheetname "")
		)
		(fill
			(thermal_gap 0.5)
			(thermal_bridge_width 0.5)
			(island_removal_mode 0)
		)
		(polygon
			(pts
				(xy 100.26396 -338.879688) (xy 100.26396 -334.343248) (xy 114.30254 -334.343248) (xy 114.30254 -338.879688)
			)
		)
	)
	(zone
		(layer "In13.Cu")
		(hatch none 0.5)
		(connect_pads
			(clearance 0)
		)
		(min_thickness 0.25)
		(keepout
			(tracks allowed)
			(vias allowed)
			(pads allowed)
			(copperpour allowed)
			(footprints allowed)
		)
		(placement
			(enabled no)
			(sheetname "")
		)
		(fill
			(thermal_gap 0.5)
			(thermal_bridge_width 0.5)
			(island_removal_mode 0)
		)
		(polygon
			(pts
				(xy 381.51816 -347.668088) (xy 381.51816 -343.784428) (xy 386.78866 -343.784428) (xy 386.78866 -347.668088)
			)
		)
	)
	(zone
		(layer "In15.Cu")
		(hatch none 0.5)
		(connect_pads
			(clearance 0)
		)
		(min_thickness 0.25)
		(keepout
			(tracks allowed)
			(vias allowed)
			(pads allowed)
			(copperpour allowed)
			(footprints allowed)
		)
		(placement
			(enabled no)
			(sheetname "")
		)
		(fill
			(thermal_gap 0.5)
			(thermal_bridge_width 0.5)
			(island_removal_mode 0)
		)
		(polygon
			(pts
				(xy 85.26526 -217.404188) (xy 85.26526 -215.773508) (xy 86.86038 -215.773508) (xy 86.86038 -217.404188)
			)
		)
	)
	(zone
		(layer "In15.Cu")
		(hatch none 0.5)
		(connect_pads
			(clearance 0)
		)
		(min_thickness 0.25)
		(keepout
			(tracks allowed)
			(vias allowed)
			(pads allowed)
			(copperpour allowed)
			(footprints allowed)
		)
		(placement
			(enabled no)
			(sheetname "")
		)
		(fill
			(thermal_gap 0.5)
			(thermal_bridge_width 0.5)
			(island_removal_mode 0)
		)
		(polygon
			(pts
				(xy 395.447266 -21.121116) (xy 395.447266 -19.297396) (xy 397.316706 -19.297396) (xy 397.316706 -21.121116)
			)
		)
	)
	(zone
		(layer "In15.Cu")
		(hatch none 0.5)
		(connect_pads
			(clearance 0)
		)
		(min_thickness 0.25)
		(keepout
			(tracks allowed)
			(vias allowed)
			(pads allowed)
			(copperpour allowed)
			(footprints allowed)
		)
		(placement
			(enabled no)
			(sheetname "")
		)
		(fill
			(thermal_gap 0.5)
			(thermal_bridge_width 0.5)
			(island_removal_mode 0)
		)
		(polygon
			(pts
				(xy 352.13544 -351.798128) (xy 352.13544 -351.023428) (xy 353.4537 -351.023428) (xy 353.4537 -351.798128)
			)
		)
	)
	(zone
		(layer "In15.Cu")
		(hatch none 0.5)
		(connect_pads
			(clearance 0)
		)
		(min_thickness 0.25)
		(keepout
			(tracks allowed)
			(vias allowed)
			(pads allowed)
			(copperpour allowed)
			(footprints allowed)
		)
		(placement
			(enabled no)
			(sheetname "")
		)
		(fill
			(thermal_gap 0.5)
			(thermal_bridge_width 0.5)
			(island_removal_mode 0)
		)
		(polygon
			(pts
				(xy 138.56462 -223.726248) (xy 138.56462 -222.603568) (xy 139.99464 -222.603568) (xy 139.99464 -223.726248)
			)
		)
	)
	(zone
		(layer "In15.Cu")
		(hatch none 0.5)
		(connect_pads
			(clearance 0)
		)
		(min_thickness 0.25)
		(keepout
			(tracks allowed)
			(vias allowed)
			(pads allowed)
			(copperpour allowed)
			(footprints allowed)
		)
		(placement
			(enabled no)
			(sheetname "")
		)
		(fill
			(thermal_gap 0.5)
			(thermal_bridge_width 0.5)
			(island_removal_mode 0)
		)
		(polygon
			(pts
				(xy 424.62958 -366.969548) (xy 424.62958 -365.763048) (xy 426.20946 -365.763048) (xy 426.20946 -366.969548)
			)
		)
	)
	(zone
		(layer "In15.Cu")
		(hatch none 0.5)
		(connect_pads
			(clearance 0)
		)
		(min_thickness 0.25)
		(keepout
			(tracks allowed)
			(vias allowed)
			(pads allowed)
			(copperpour allowed)
			(footprints allowed)
		)
		(placement
			(enabled no)
			(sheetname "")
		)
		(fill
			(thermal_gap 0.5)
			(thermal_bridge_width 0.5)
			(island_removal_mode 0)
		)
		(polygon
			(pts
				(xy 110.9853 -365.293148) (xy 110.9853 -363.581188) (xy 112.94618 -363.581188) (xy 112.94618 -365.293148)
			)
		)
	)
	(zone
		(layer "In15.Cu")
		(hatch none 0.5)
		(connect_pads
			(clearance 0)
		)
		(min_thickness 0.25)
		(keepout
			(tracks allowed)
			(vias allowed)
			(pads allowed)
			(copperpour allowed)
			(footprints allowed)
		)
		(placement
			(enabled no)
			(sheetname "")
		)
		(fill
			(thermal_gap 0.5)
			(thermal_bridge_width 0.5)
			(island_removal_mode 0)
		)
		(polygon
			(pts
				(xy 138.897106 -401.820634) (xy 138.897106 -399.859754) (xy 140.802106 -399.859754) (xy 140.802106 -401.820634)
			)
		)
	)
	(zone
		(layer "In15.Cu")
		(hatch none 0.5)
		(connect_pads
			(clearance 0)
		)
		(min_thickness 0.25)
		(keepout
			(tracks allowed)
			(vias allowed)
			(pads allowed)
			(copperpour allowed)
			(footprints allowed)
		)
		(placement
			(enabled no)
			(sheetname "")
		)
		(fill
			(thermal_gap 0.5)
			(thermal_bridge_width 0.5)
			(island_removal_mode 0)
		)
		(polygon
			(pts
				(xy 403.911054 -21.136356) (xy 403.911054 -19.312636) (xy 405.780494 -19.312636) (xy 405.780494 -21.136356)
			)
		)
	)
	(zone
		(layer "In15.Cu")
		(hatch none 0.5)
		(connect_pads
			(clearance 0)
		)
		(min_thickness 0.25)
		(keepout
			(tracks allowed)
			(vias allowed)
			(pads allowed)
			(copperpour allowed)
			(footprints allowed)
		)
		(placement
			(enabled no)
			(sheetname "")
		)
		(fill
			(thermal_gap 0.5)
			(thermal_bridge_width 0.5)
			(island_removal_mode 0)
		)
		(polygon
			(pts
				(xy 367.339626 -337.187032) (xy 367.532666 -337.187032) (xy 368.269266 -337.923632) (xy 368.269266 -339.864192)
				(xy 365.937546 -342.195912) (xy 365.937546 -345.444572) (xy 361.787186 -349.594932) (xy 358.535986 -349.594932)
				(xy 357.748586 -350.382332) (xy 357.748586 -351.116392) (xy 357.900986 -351.268792) (xy 357.900986 -351.563432)
				(xy 357.786686 -351.677732) (xy 357.535226 -351.677732) (xy 356.991666 -351.134172) (xy 356.991666 -350.031812)
				(xy 358.236266 -348.787212) (xy 361.573826 -348.787212) (xy 365.155226 -345.205812) (xy 365.155226 -341.906352)
				(xy 367.443766 -339.617812) (xy 367.443766 -338.695792) (xy 367.154206 -338.406232) (xy 367.154206 -337.372452)
			)
		)
	)
	(zone
		(layer "In15.Cu")
		(hatch none 0.5)
		(connect_pads
			(clearance 0)
		)
		(min_thickness 0.25)
		(keepout
			(tracks allowed)
			(vias allowed)
			(pads allowed)
			(copperpour allowed)
			(footprints allowed)
		)
		(placement
			(enabled no)
			(sheetname "")
		)
		(fill
			(thermal_gap 0.5)
			(thermal_bridge_width 0.5)
			(island_removal_mode 0)
		)
		(polygon
			(pts
				(xy 157.870652 -401.820634) (xy 157.870652 -399.859754) (xy 159.775652 -399.859754) (xy 159.775652 -401.820634)
			)
		)
	)
	(zone
		(layer "In15.Cu")
		(hatch none 0.5)
		(connect_pads
			(clearance 0)
		)
		(min_thickness 0.25)
		(keepout
			(tracks allowed)
			(vias allowed)
			(pads allowed)
			(copperpour allowed)
			(footprints allowed)
		)
		(placement
			(enabled no)
			(sheetname "")
		)
		(fill
			(thermal_gap 0.5)
			(thermal_bridge_width 0.5)
			(island_removal_mode 0)
		)
		(polygon
			(pts
				(xy 411.977586 -21.136356) (xy 411.977586 -19.312636) (xy 413.847026 -19.312636) (xy 413.847026 -21.136356)
			)
		)
	)
	(zone
		(layer "In15.Cu")
		(hatch none 0.5)
		(connect_pads
			(clearance 0)
		)
		(min_thickness 0.25)
		(keepout
			(tracks allowed)
			(vias allowed)
			(pads allowed)
			(copperpour allowed)
			(footprints allowed)
		)
		(placement
			(enabled no)
			(sheetname "")
		)
		(fill
			(thermal_gap 0.5)
			(thermal_bridge_width 0.5)
			(island_removal_mode 0)
		)
		(polygon
			(pts
				(xy 116.28374 -339.237828) (xy 116.28374 -335.077308) (xy 122.06986 -335.077308) (xy 122.06986 -339.237828)
			)
		)
	)
	(zone
		(layer "In15.Cu")
		(hatch none 0.5)
		(connect_pads
			(clearance 0)
		)
		(min_thickness 0.25)
		(keepout
			(tracks allowed)
			(vias allowed)
			(pads allowed)
			(copperpour allowed)
			(footprints allowed)
		)
		(placement
			(enabled no)
			(sheetname "")
		)
		(fill
			(thermal_gap 0.5)
			(thermal_bridge_width 0.5)
			(island_removal_mode 0)
		)
		(polygon
			(pts
				(xy 356.12324 -338.226908) (xy 356.12324 -335.214468) (xy 369.89258 -335.214468) (xy 369.89258 -338.226908)
			)
		)
	)
	(zone
		(layer "In15.Cu")
		(hatch none 0.5)
		(connect_pads
			(clearance 0)
		)
		(min_thickness 0.25)
		(keepout
			(tracks allowed)
			(vias allowed)
			(pads allowed)
			(copperpour allowed)
			(footprints allowed)
		)
		(placement
			(enabled no)
			(sheetname "")
		)
		(fill
			(thermal_gap 0.5)
			(thermal_bridge_width 0.5)
			(island_removal_mode 0)
		)
		(polygon
			(pts
				(xy 321.93484 -348.935548) (xy 321.93484 -347.182948) (xy 322.7959 -347.182948) (xy 322.7959 -348.935548)
			)
		)
	)
	(zone
		(layer "In15.Cu")
		(hatch none 0.5)
		(connect_pads
			(clearance 0)
		)
		(min_thickness 0.25)
		(keepout
			(tracks allowed)
			(vias allowed)
			(pads allowed)
			(copperpour allowed)
			(footprints allowed)
		)
		(placement
			(enabled no)
			(sheetname "")
		)
		(fill
			(thermal_gap 0.5)
			(thermal_bridge_width 0.5)
			(island_removal_mode 0)
		)
		(polygon
			(pts
				(xy 180.4162 -358.191308) (xy 180.4162 -356.903528) (xy 182.17896 -356.903528) (xy 182.17896 -358.191308)
			)
		)
	)
	(zone
		(layer "In15.Cu")
		(hatch none 0.5)
		(connect_pads
			(clearance 0)
		)
		(min_thickness 0.25)
		(keepout
			(tracks allowed)
			(vias allowed)
			(pads allowed)
			(copperpour allowed)
			(footprints allowed)
		)
		(placement
			(enabled no)
			(sheetname "")
		)
		(fill
			(thermal_gap 0.5)
			(thermal_bridge_width 0.5)
			(island_removal_mode 0)
		)
		(polygon
			(pts
				(xy 76.62672 -350.784668) (xy 76.62672 -349.283528) (xy 77.38364 -349.283528) (xy 77.38364 -350.784668)
			)
		)
	)
	(zone
		(layer "In15.Cu")
		(hatch none 0.5)
		(connect_pads
			(clearance 0)
		)
		(min_thickness 0.25)
		(keepout
			(tracks allowed)
			(vias allowed)
			(pads allowed)
			(copperpour allowed)
			(footprints allowed)
		)
		(placement
			(enabled no)
			(sheetname "")
		)
		(fill
			(thermal_gap 0.5)
			(thermal_bridge_width 0.5)
			(island_removal_mode 0)
		)
		(polygon
			(pts
				(xy 130.819906 -401.820634) (xy 130.819906 -399.859754) (xy 132.724906 -399.859754) (xy 132.724906 -401.820634)
			)
		)
	)
	(zone
		(layer "In15.Cu")
		(hatch none 0.5)
		(connect_pads
			(clearance 0)
		)
		(min_thickness 0.25)
		(keepout
			(tracks allowed)
			(vias allowed)
			(pads allowed)
			(copperpour allowed)
			(footprints allowed)
		)
		(placement
			(enabled no)
			(sheetname "")
		)
		(fill
			(thermal_gap 0.5)
			(thermal_bridge_width 0.5)
			(island_removal_mode 0)
		)
		(polygon
			(pts
				(xy 330.25334 -42.532808) (xy 330.25334 -39.642288) (xy 335.6356 -39.642288) (xy 335.6356 -42.532808)
			)
		)
	)
	(zone
		(layer "In15.Cu")
		(hatch none 0.5)
		(connect_pads
			(clearance 0)
		)
		(min_thickness 0.25)
		(keepout
			(tracks allowed)
			(vias allowed)
			(pads allowed)
			(copperpour allowed)
			(footprints allowed)
		)
		(placement
			(enabled no)
			(sheetname "")
		)
		(fill
			(thermal_gap 0.5)
			(thermal_bridge_width 0.5)
			(island_removal_mode 0)
		)
		(polygon
			(pts
				(xy 351.106486 -337.187032) (xy 351.258886 -337.187032) (xy 351.906586 -337.834732) (xy 351.906586 -340.458552)
				(xy 351.002346 -341.362792) (xy 351.002346 -345.170252) (xy 351.771966 -345.939872) (xy 354.728526 -345.939872)
				(xy 355.594666 -346.806012) (xy 355.594666 -351.672652) (xy 355.434646 -351.832672) (xy 355.305106 -351.832672)
				(xy 355.178106 -351.705672) (xy 355.178106 -351.121472) (xy 354.863146 -350.806512) (xy 354.863146 -347.151452)
				(xy 354.350066 -346.638372) (xy 351.380806 -346.638372) (xy 350.316546 -345.574112) (xy 350.316546 -340.997032)
				(xy 351.144586 -340.168992) (xy 351.144586 -338.568792) (xy 350.893126 -338.317332) (xy 350.893126 -337.400392)
			)
		)
	)
	(zone
		(layer "In15.Cu")
		(hatch none 0.5)
		(connect_pads
			(clearance 0)
		)
		(min_thickness 0.25)
		(keepout
			(tracks allowed)
			(vias allowed)
			(pads allowed)
			(copperpour allowed)
			(footprints allowed)
		)
		(placement
			(enabled no)
			(sheetname "")
		)
		(fill
			(thermal_gap 0.5)
			(thermal_bridge_width 0.5)
			(island_removal_mode 0)
		)
		(polygon
			(pts
				(xy 332.97114 -217.632788) (xy 332.97114 -216.248488) (xy 335.10982 -216.248488) (xy 335.10982 -217.632788)
			)
		)
	)
	(zone
		(layer "In15.Cu")
		(hatch none 0.5)
		(connect_pads
			(clearance 0)
		)
		(min_thickness 0.25)
		(keepout
			(tracks allowed)
			(vias allowed)
			(pads allowed)
			(copperpour allowed)
			(footprints allowed)
		)
		(placement
			(enabled no)
			(sheetname "")
		)
		(fill
			(thermal_gap 0.5)
			(thermal_bridge_width 0.5)
			(island_removal_mode 0)
		)
		(polygon
			(pts
				(xy 335.29016 -341.714328) (xy 335.29016 -340.396068) (xy 337.0834 -340.396068) (xy 337.0834 -341.714328)
			)
		)
	)
	(zone
		(layer "In15.Cu")
		(hatch none 0.5)
		(connect_pads
			(clearance 0)
		)
		(min_thickness 0.25)
		(keepout
			(tracks allowed)
			(vias allowed)
			(pads allowed)
			(copperpour allowed)
			(footprints allowed)
		)
		(placement
			(enabled no)
			(sheetname "")
		)
		(fill
			(thermal_gap 0.5)
			(thermal_bridge_width 0.5)
			(island_removal_mode 0)
		)
		(polygon
			(pts
				(xy 334.690466 -340.577932) (xy 335.053686 -340.577932) (xy 335.477866 -341.002112) (xy 335.477866 -343.013792)
				(xy 336.006186 -343.542112) (xy 342.396826 -343.542112) (xy 344.550746 -345.696032) (xy 345.637866 -345.696032)
				(xy 352.409506 -352.467672) (xy 358.345486 -352.467672) (xy 358.408986 -352.531172) (xy 358.408986 -352.894392)
				(xy 358.040686 -353.262692) (xy 352.145346 -353.262692) (xy 345.302586 -346.419932) (xy 344.238326 -346.419932)
				(xy 342.104726 -344.286332) (xy 335.729326 -344.286332) (xy 334.690466 -343.247472) (xy 334.690466 -341.977472)
				(xy 334.517746 -341.804752) (xy 334.517746 -340.750652)
			)
		)
	)
	(zone
		(layer "In15.Cu")
		(hatch none 0.5)
		(connect_pads
			(clearance 0)
		)
		(min_thickness 0.25)
		(keepout
			(tracks allowed)
			(vias allowed)
			(pads allowed)
			(copperpour allowed)
			(footprints allowed)
		)
		(placement
			(enabled no)
			(sheetname "")
		)
		(fill
			(thermal_gap 0.5)
			(thermal_bridge_width 0.5)
			(island_removal_mode 0)
		)
		(polygon
			(pts
				(xy 331.60462 -225.628708) (xy 331.60462 -221.211648) (xy 337.58378 -221.211648) (xy 337.58378 -225.628708)
			)
		)
	)
	(zone
		(layer "In15.Cu")
		(hatch none 0.5)
		(connect_pads
			(clearance 0)
		)
		(min_thickness 0.25)
		(keepout
			(tracks allowed)
			(vias allowed)
			(pads allowed)
			(copperpour allowed)
			(footprints allowed)
		)
		(placement
			(enabled no)
			(sheetname "")
		)
		(fill
			(thermal_gap 0.5)
			(thermal_bridge_width 0.5)
			(island_removal_mode 0)
		)
		(polygon
			(pts
				(xy 86.86038 -341.556848) (xy 86.86038 -340.406228) (xy 89.19718 -340.406228) (xy 89.19718 -341.556848)
			)
		)
	)
	(zone
		(layer "In15.Cu")
		(hatch none 0.5)
		(connect_pads
			(clearance 0)
		)
		(min_thickness 0.25)
		(keepout
			(tracks allowed)
			(vias allowed)
			(pads allowed)
			(copperpour allowed)
			(footprints allowed)
		)
		(placement
			(enabled no)
			(sheetname "")
		)
		(fill
			(thermal_gap 0.5)
			(thermal_bridge_width 0.5)
			(island_removal_mode 0)
		)
		(polygon
			(pts
				(xy 312.081926 -364.746032) (xy 312.356246 -364.746032) (xy 312.516266 -364.906052) (xy 312.516266 -366.262412)
				(xy 314.032646 -367.778792) (xy 327.316846 -367.778792) (xy 328.457306 -368.919252) (xy 348.830646 -368.919252)
				(xy 351.965006 -365.784892) (xy 354.365306 -365.784892) (xy 355.046026 -366.465612) (xy 356.712266 -366.465612)
				(xy 356.864666 -366.618012) (xy 356.864666 -367.476532) (xy 356.145846 -368.195352) (xy 354.952046 -368.195352)
				(xy 354.223066 -367.466372) (xy 354.223066 -366.849152) (xy 353.903026 -366.529112) (xy 352.285046 -366.529112)
				(xy 349.066866 -369.747292) (xy 328.238866 -369.747292) (xy 327.001886 -368.510312) (xy 313.506866 -368.510312)
				(xy 311.416446 -366.419892) (xy 311.416446 -365.411512)
			)
		)
	)
	(zone
		(layer "In15.Cu")
		(hatch none 0.5)
		(connect_pads
			(clearance 0)
		)
		(min_thickness 0.25)
		(keepout
			(tracks allowed)
			(vias allowed)
			(pads allowed)
			(copperpour allowed)
			(footprints allowed)
		)
		(placement
			(enabled no)
			(sheetname "")
		)
		(fill
			(thermal_gap 0.5)
			(thermal_bridge_width 0.5)
			(island_removal_mode 0)
		)
		(polygon
			(pts
				(xy 342.808306 -337.194652) (xy 343.168986 -337.194652) (xy 343.763346 -337.789012) (xy 343.763346 -340.001352)
				(xy 344.258646 -340.496652) (xy 348.086426 -340.496652) (xy 349.496126 -341.906352) (xy 349.496126 -346.567252)
				(xy 350.707706 -347.778832) (xy 353.920806 -347.778832) (xy 354.665026 -348.523052) (xy 354.665026 -351.865692)
				(xy 354.558346 -351.972372) (xy 354.329746 -351.972372) (xy 353.908106 -351.550732) (xy 353.908106 -348.812612)
				(xy 353.549966 -348.454472) (xy 350.291146 -348.454472) (xy 348.739206 -346.902532) (xy 348.739206 -342.310212)
				(xy 347.720666 -341.291672) (xy 343.849706 -341.291672) (xy 342.694006 -340.135972) (xy 342.694006 -337.308952)
			)
		)
	)
	(zone
		(layer "In15.Cu")
		(hatch none 0.5)
		(connect_pads
			(clearance 0)
		)
		(min_thickness 0.25)
		(keepout
			(tracks allowed)
			(vias allowed)
			(pads allowed)
			(copperpour allowed)
			(footprints allowed)
		)
		(placement
			(enabled no)
			(sheetname "")
		)
		(fill
			(thermal_gap 0.5)
			(thermal_bridge_width 0.5)
			(island_removal_mode 0)
		)
		(polygon
			(pts
				(xy 79.30642 -347.856048) (xy 79.30642 -346.553028) (xy 81.04378 -346.553028) (xy 81.04378 -347.856048)
			)
		)
	)
	(zone
		(layer "In15.Cu")
		(hatch none 0.5)
		(connect_pads
			(clearance 0)
		)
		(min_thickness 0.25)
		(keepout
			(tracks allowed)
			(vias allowed)
			(pads allowed)
			(copperpour allowed)
			(footprints allowed)
		)
		(placement
			(enabled no)
			(sheetname "")
		)
		(fill
			(thermal_gap 0.5)
			(thermal_bridge_width 0.5)
			(island_removal_mode 0)
		)
		(polygon
			(pts
				(xy 421.9575 -365.509048) (xy 421.9575 -362.400088) (xy 423.82948 -362.400088) (xy 423.82948 -365.509048)
			)
		)
	)
	(zone
		(layer "In15.Cu")
		(hatch none 0.5)
		(connect_pads
			(clearance 0)
		)
		(min_thickness 0.25)
		(keepout
			(tracks allowed)
			(vias allowed)
			(pads allowed)
			(copperpour allowed)
			(footprints allowed)
		)
		(placement
			(enabled no)
			(sheetname "")
		)
		(fill
			(thermal_gap 0.5)
			(thermal_bridge_width 0.5)
			(island_removal_mode 0)
		)
		(polygon
			(pts
				(xy 144.408652 -401.820634) (xy 144.408652 -399.859754) (xy 146.313652 -399.859754) (xy 146.313652 -401.820634)
			)
		)
	)
	(zone
		(layer "In15.Cu")
		(hatch none 0.5)
		(connect_pads
			(clearance 0)
		)
		(min_thickness 0.25)
		(keepout
			(tracks allowed)
			(vias allowed)
			(pads allowed)
			(copperpour allowed)
			(footprints allowed)
		)
		(placement
			(enabled no)
			(sheetname "")
		)
		(fill
			(thermal_gap 0.5)
			(thermal_bridge_width 0.5)
			(island_removal_mode 0)
		)
		(polygon
			(pts
				(xy 326.65924 -347.985588) (xy 326.65924 -346.332048) (xy 329.16622 -346.332048) (xy 329.16622 -347.985588)
			)
		)
	)
	(zone
		(layer "In15.Cu")
		(hatch none 0.5)
		(connect_pads
			(clearance 0)
		)
		(min_thickness 0.25)
		(keepout
			(tracks allowed)
			(vias allowed)
			(pads allowed)
			(copperpour allowed)
			(footprints allowed)
		)
		(placement
			(enabled no)
			(sheetname "")
		)
		(fill
			(thermal_gap 0.5)
			(thermal_bridge_width 0.5)
			(island_removal_mode 0)
		)
		(polygon
			(pts
				(xy 133.512306 -401.820634) (xy 133.512306 -399.859754) (xy 135.417306 -399.859754) (xy 135.417306 -401.820634)
			)
		)
	)
	(zone
		(layer "In15.Cu")
		(hatch none 0.5)
		(connect_pads
			(clearance 0)
		)
		(min_thickness 0.25)
		(keepout
			(tracks allowed)
			(vias allowed)
			(pads allowed)
			(copperpour allowed)
			(footprints allowed)
		)
		(placement
			(enabled no)
			(sheetname "")
		)
		(fill
			(thermal_gap 0.5)
			(thermal_bridge_width 0.5)
			(island_removal_mode 0)
		)
		(polygon
			(pts
				(xy 16.0274 -407.5811) (xy 16.0274 -405.72944) (xy 17.5895 -405.72944) (xy 17.5895 -407.5811)
			)
		)
	)
	(zone
		(layer "In15.Cu")
		(hatch none 0.5)
		(connect_pads
			(clearance 0)
		)
		(min_thickness 0.25)
		(keepout
			(tracks allowed)
			(vias allowed)
			(pads allowed)
			(copperpour allowed)
			(footprints allowed)
		)
		(placement
			(enabled no)
			(sheetname "")
		)
		(fill
			(thermal_gap 0.5)
			(thermal_bridge_width 0.5)
			(island_removal_mode 0)
		)
		(polygon
			(pts
				(xy 364.20044 -354.904548) (xy 364.20044 -353.538028) (xy 365.1123 -353.538028) (xy 365.1123 -354.904548)
			)
		)
	)
	(zone
		(layer "In15.Cu")
		(hatch none 0.5)
		(connect_pads
			(clearance 0)
		)
		(min_thickness 0.25)
		(keepout
			(tracks allowed)
			(vias allowed)
			(pads allowed)
			(copperpour allowed)
			(footprints allowed)
		)
		(placement
			(enabled no)
			(sheetname "")
		)
		(fill
			(thermal_gap 0.5)
			(thermal_bridge_width 0.5)
			(island_removal_mode 0)
		)
		(polygon
			(pts
				(xy 326.496426 -346.381832) (xy 326.745346 -346.381832) (xy 327.337166 -346.973652) (xy 327.337166 -348.114112)
				(xy 328.343006 -349.119952) (xy 332.175866 -349.119952) (xy 334.715866 -346.579952) (xy 343.212166 -346.579952)
				(xy 343.930986 -347.298772) (xy 344.924126 -347.298772) (xy 352.836226 -355.210872) (xy 356.768146 -355.210872)
				(xy 358.523286 -353.455732) (xy 358.523286 -353.313492) (xy 358.599486 -353.237292) (xy 358.927146 -353.237292)
				(xy 359.061766 -353.371912) (xy 359.061766 -354.083112) (xy 357.131366 -356.013512) (xy 357.009446 -356.135432)
				(xy 352.412046 -356.135432) (xy 344.352626 -348.076012) (xy 343.572846 -348.076012) (xy 342.854026 -347.357192)
				(xy 335.068926 -347.357192) (xy 332.541626 -349.884492) (xy 327.870566 -349.884492) (xy 326.382126 -348.396052)
				(xy 326.382126 -346.496132)
			)
		)
	)
	(zone
		(layer "In15.Cu")
		(hatch none 0.5)
		(connect_pads
			(clearance 0)
		)
		(min_thickness 0.25)
		(keepout
			(tracks allowed)
			(vias allowed)
			(pads allowed)
			(copperpour allowed)
			(footprints allowed)
		)
		(placement
			(enabled no)
			(sheetname "")
		)
		(fill
			(thermal_gap 0.5)
			(thermal_bridge_width 0.5)
			(island_removal_mode 0)
		)
		(polygon
			(pts
				(xy 415.127694 -21.197316) (xy 415.127694 -19.373596) (xy 416.997134 -19.373596) (xy 416.997134 -21.197316)
			)
		)
	)
	(zone
		(layer "In15.Cu")
		(hatch none 0.5)
		(connect_pads
			(clearance 0)
		)
		(min_thickness 0.25)
		(keepout
			(tracks allowed)
			(vias allowed)
			(pads allowed)
			(copperpour allowed)
			(footprints allowed)
		)
		(placement
			(enabled no)
			(sheetname "")
		)
		(fill
			(thermal_gap 0.5)
			(thermal_bridge_width 0.5)
			(island_removal_mode 0)
		)
		(polygon
			(pts
				(xy 359.107486 -350.036892) (xy 362.942886 -350.036892) (xy 366.295686 -346.684092) (xy 374.733566 -346.684092)
				(xy 375.574306 -345.843352) (xy 375.574306 -342.048592) (xy 375.335546 -341.809832) (xy 375.335546 -340.748112)
				(xy 375.439686 -340.643972) (xy 375.726706 -340.643972) (xy 376.310906 -341.228172) (xy 376.310906 -346.259912)
				(xy 375.167906 -347.402912) (xy 366.666526 -347.402912) (xy 363.275626 -350.793812) (xy 359.473246 -350.793812)
				(xy 359.224326 -351.042732) (xy 359.224326 -351.619312) (xy 358.998266 -351.845372) (xy 358.838246 -351.845372)
				(xy 358.581706 -351.588832) (xy 358.581706 -350.562672)
			)
		)
	)
	(zone
		(layer "In15.Cu")
		(hatch none 0.5)
		(connect_pads
			(clearance 0)
		)
		(min_thickness 0.25)
		(keepout
			(tracks allowed)
			(vias allowed)
			(pads allowed)
			(copperpour allowed)
			(footprints allowed)
		)
		(placement
			(enabled no)
			(sheetname "")
		)
		(fill
			(thermal_gap 0.5)
			(thermal_bridge_width 0.5)
			(island_removal_mode 0)
		)
		(polygon
			(pts
				(xy 302.003206 -364.873032) (xy 302.640746 -364.873032) (xy 302.795686 -365.027972) (xy 302.795686 -365.759492)
				(xy 300.141386 -368.413792) (xy 300.141386 -372.185692) (xy 303.654206 -375.698512) (xy 321.660266 -375.698512)
				(xy 325.559166 -371.799612) (xy 349.529146 -371.799612) (xy 352.516186 -368.812572) (xy 352.516186 -367.362232)
				(xy 352.683826 -367.194592) (xy 353.786186 -367.194592) (xy 354.042726 -367.451132) (xy 354.042726 -368.937032)
				(xy 350.192086 -372.787672) (xy 326.211946 -372.787672) (xy 322.302886 -376.696732) (xy 303.359566 -376.696732)
				(xy 299.270166 -372.607332) (xy 299.270166 -367.606072)
			)
		)
	)
	(zone
		(layer "In15.Cu")
		(hatch none 0.5)
		(connect_pads
			(clearance 0)
		)
		(min_thickness 0.25)
		(keepout
			(tracks allowed)
			(vias allowed)
			(pads allowed)
			(copperpour allowed)
			(footprints allowed)
		)
		(placement
			(enabled no)
			(sheetname "")
		)
		(fill
			(thermal_gap 0.5)
			(thermal_bridge_width 0.5)
			(island_removal_mode 0)
		)
		(polygon
			(pts
				(xy 141.690852 -401.820634) (xy 141.690852 -399.859754) (xy 143.595852 -399.859754) (xy 143.595852 -401.820634)
			)
		)
	)
	(zone
		(layer "In15.Cu")
		(hatch none 0.5)
		(connect_pads
			(clearance 0)
		)
		(min_thickness 0.25)
		(keepout
			(tracks allowed)
			(vias allowed)
			(pads allowed)
			(copperpour allowed)
			(footprints allowed)
		)
		(placement
			(enabled no)
			(sheetname "")
		)
		(fill
			(thermal_gap 0.5)
			(thermal_bridge_width 0.5)
			(island_removal_mode 0)
		)
		(polygon
			(pts
				(xy 359.140506 -337.194652) (xy 359.343706 -337.194652) (xy 359.922826 -337.773772) (xy 359.922826 -340.565232)
				(xy 358.401366 -342.086692) (xy 358.401366 -347.509592) (xy 356.664006 -349.246952) (xy 356.664006 -351.774252)
				(xy 356.542086 -351.896172) (xy 356.356666 -351.896172) (xy 356.229666 -351.769172) (xy 356.229666 -351.151952)
				(xy 355.927406 -350.849692) (xy 355.927406 -348.926912) (xy 357.697786 -347.156532) (xy 357.697786 -341.675212)
				(xy 359.074466 -340.298532) (xy 359.074466 -338.474812) (xy 359.018586 -338.418932) (xy 359.018586 -337.316572)
			)
		)
	)
	(zone
		(layer "In15.Cu")
		(hatch none 0.5)
		(connect_pads
			(clearance 0)
		)
		(min_thickness 0.25)
		(keepout
			(tracks allowed)
			(vias allowed)
			(pads allowed)
			(copperpour allowed)
			(footprints allowed)
		)
		(placement
			(enabled no)
			(sheetname "")
		)
		(fill
			(thermal_gap 0.5)
			(thermal_bridge_width 0.5)
			(island_removal_mode 0)
		)
		(polygon
			(pts
				(xy 409.54325 -21.136356) (xy 409.54325 -19.312636) (xy 411.41269 -19.312636) (xy 411.41269 -21.136356)
			)
		)
	)
	(zone
		(layer "In15.Cu")
		(hatch none 0.5)
		(connect_pads
			(clearance 0)
		)
		(min_thickness 0.25)
		(keepout
			(tracks allowed)
			(vias allowed)
			(pads allowed)
			(copperpour allowed)
			(footprints allowed)
		)
		(placement
			(enabled no)
			(sheetname "")
		)
		(fill
			(thermal_gap 0.5)
			(thermal_bridge_width 0.5)
			(island_removal_mode 0)
		)
		(polygon
			(pts
				(xy 333.486252 -291.12972) (xy 333.486252 -213.322916) (xy 387.951218 -213.322916) (xy 387.951218 -291.12972)
			)
		)
	)
	(zone
		(layer "In15.Cu")
		(hatch none 0.5)
		(connect_pads
			(clearance 0)
		)
		(min_thickness 0.25)
		(keepout
			(tracks allowed)
			(vias allowed)
			(pads allowed)
			(copperpour allowed)
			(footprints allowed)
		)
		(placement
			(enabled no)
			(sheetname "")
		)
		(fill
			(thermal_gap 0.5)
			(thermal_bridge_width 0.5)
			(island_removal_mode 0)
		)
		(polygon
			(pts
				(xy 40.25392 -358.516428) (xy 40.25392 -357.170228) (xy 42.23512 -357.170228) (xy 42.23512 -358.516428)
			)
		)
	)
	(zone
		(layer "In15.Cu")
		(hatch none 0.5)
		(connect_pads
			(clearance 0)
		)
		(min_thickness 0.25)
		(keepout
			(tracks allowed)
			(vias allowed)
			(pads allowed)
			(copperpour allowed)
			(footprints allowed)
		)
		(placement
			(enabled no)
			(sheetname "")
		)
		(fill
			(thermal_gap 0.5)
			(thermal_bridge_width 0.5)
			(island_removal_mode 0)
		)
		(polygon
			(pts
				(xy 423.447972 -21.197316) (xy 423.447972 -19.373596) (xy 425.317412 -19.373596) (xy 425.317412 -21.197316)
			)
		)
	)
	(zone
		(layer "In15.Cu")
		(hatch none 0.5)
		(connect_pads
			(clearance 0)
		)
		(min_thickness 0.25)
		(keepout
			(tracks allowed)
			(vias allowed)
			(pads allowed)
			(copperpour allowed)
			(footprints allowed)
		)
		(placement
			(enabled no)
			(sheetname "")
		)
		(fill
			(thermal_gap 0.5)
			(thermal_bridge_width 0.5)
			(island_removal_mode 0)
		)
		(polygon
			(pts
				(xy 398.098772 -21.105876) (xy 398.098772 -19.282156) (xy 399.968212 -19.282156) (xy 399.968212 -21.105876)
			)
		)
	)
	(zone
		(layer "In15.Cu")
		(hatch none 0.5)
		(connect_pads
			(clearance 0)
		)
		(min_thickness 0.25)
		(keepout
			(tracks allowed)
			(vias allowed)
			(pads allowed)
			(copperpour allowed)
			(footprints allowed)
		)
		(placement
			(enabled no)
			(sheetname "")
		)
		(fill
			(thermal_gap 0.5)
			(thermal_bridge_width 0.5)
			(island_removal_mode 0)
		)
		(polygon
			(pts
				(xy 125.435106 -401.820634) (xy 125.435106 -399.859754) (xy 127.340106 -399.859754) (xy 127.340106 -401.820634)
			)
		)
	)
	(zone
		(layer "In15.Cu")
		(hatch none 0.5)
		(connect_pads
			(clearance 0)
		)
		(min_thickness 0.25)
		(keepout
			(tracks allowed)
			(vias allowed)
			(pads allowed)
			(copperpour allowed)
			(footprints allowed)
		)
		(placement
			(enabled no)
			(sheetname "")
		)
		(fill
			(thermal_gap 0.5)
			(thermal_bridge_width 0.5)
			(island_removal_mode 0)
		)
		(polygon
			(pts
				(xy 50.62728 -172.837348) (xy 50.62728 -171.816268) (xy 51.96078 -171.816268) (xy 51.96078 -172.837348)
			)
		)
	)
	(zone
		(layer "In15.Cu")
		(hatch none 0.5)
		(connect_pads
			(clearance 0)
		)
		(min_thickness 0.25)
		(keepout
			(tracks allowed)
			(vias allowed)
			(pads allowed)
			(copperpour allowed)
			(footprints allowed)
		)
		(placement
			(enabled no)
			(sheetname "")
		)
		(fill
			(thermal_gap 0.5)
			(thermal_bridge_width 0.5)
			(island_removal_mode 0)
		)
		(polygon
			(pts
				(xy 406.72639 -21.136356) (xy 406.72639 -19.312636) (xy 408.59583 -19.312636) (xy 408.59583 -21.136356)
			)
		)
	)
	(zone
		(layer "In15.Cu")
		(hatch none 0.5)
		(connect_pads
			(clearance 0)
		)
		(min_thickness 0.25)
		(keepout
			(tracks allowed)
			(vias allowed)
			(pads allowed)
			(copperpour allowed)
			(footprints allowed)
		)
		(placement
			(enabled no)
			(sheetname "")
		)
		(fill
			(thermal_gap 0.5)
			(thermal_bridge_width 0.5)
			(island_removal_mode 0)
		)
		(polygon
			(pts
				(xy 155.178252 -401.820634) (xy 155.178252 -399.859754) (xy 157.083252 -399.859754) (xy 157.083252 -401.820634)
			)
		)
	)
	(zone
		(layer "In15.Cu")
		(hatch none 0.5)
		(connect_pads
			(clearance 0)
		)
		(min_thickness 0.25)
		(keepout
			(tracks allowed)
			(vias allowed)
			(pads allowed)
			(copperpour allowed)
			(footprints allowed)
		)
		(placement
			(enabled no)
			(sheetname "")
		)
		(fill
			(thermal_gap 0.5)
			(thermal_bridge_width 0.5)
			(island_removal_mode 0)
		)
		(polygon
			(pts
				(xy 170.71594 -358.229408) (xy 170.71594 -356.977188) (xy 172.39234 -356.977188) (xy 172.39234 -358.229408)
			)
		)
	)
	(zone
		(layer "In15.Cu")
		(hatch none 0.5)
		(connect_pads
			(clearance 0)
		)
		(min_thickness 0.25)
		(keepout
			(tracks allowed)
			(vias allowed)
			(pads allowed)
			(copperpour allowed)
			(footprints allowed)
		)
		(placement
			(enabled no)
			(sheetname "")
		)
		(fill
			(thermal_gap 0.5)
			(thermal_bridge_width 0.5)
			(island_removal_mode 0)
		)
		(polygon
			(pts
				(xy 431.969672 -21.197316) (xy 431.969672 -19.373596) (xy 433.839112 -19.373596) (xy 433.839112 -21.197316)
			)
		)
	)
	(zone
		(layer "In15.Cu")
		(hatch none 0.5)
		(connect_pads
			(clearance 0)
		)
		(min_thickness 0.25)
		(keepout
			(tracks allowed)
			(vias allowed)
			(pads allowed)
			(copperpour allowed)
			(footprints allowed)
		)
		(placement
			(enabled no)
			(sheetname "")
		)
		(fill
			(thermal_gap 0.5)
			(thermal_bridge_width 0.5)
			(island_removal_mode 0)
		)
		(polygon
			(pts
				(xy 134.01802 -347.739208) (xy 134.01802 -345.638628) (xy 138.39952 -345.638628) (xy 138.39952 -347.739208)
			)
		)
	)
	(zone
		(layer "In15.Cu")
		(hatch none 0.5)
		(connect_pads
			(clearance 0)
		)
		(min_thickness 0.25)
		(keepout
			(tracks allowed)
			(vias allowed)
			(pads allowed)
			(copperpour allowed)
			(footprints allowed)
		)
		(placement
			(enabled no)
			(sheetname "")
		)
		(fill
			(thermal_gap 0.5)
			(thermal_bridge_width 0.5)
			(island_removal_mode 0)
		)
		(polygon
			(pts
				(xy 429.153066 -21.197316) (xy 429.153066 -19.373596) (xy 431.022506 -19.373596) (xy 431.022506 -21.197316)
			)
		)
	)
	(zone
		(layer "In15.Cu")
		(hatch none 0.5)
		(connect_pads
			(clearance 0)
		)
		(min_thickness 0.25)
		(keepout
			(tracks allowed)
			(vias allowed)
			(pads allowed)
			(copperpour allowed)
			(footprints allowed)
		)
		(placement
			(enabled no)
			(sheetname "")
		)
		(fill
			(thermal_gap 0.5)
			(thermal_bridge_width 0.5)
			(island_removal_mode 0)
		)
		(polygon
			(pts
				(xy 104.04856 -351.864168) (xy 104.04856 -351.041208) (xy 105.51414 -351.041208) (xy 105.51414 -351.864168)
			)
		)
	)
	(zone
		(layer "In15.Cu")
		(hatch none 0.5)
		(connect_pads
			(clearance 0)
		)
		(min_thickness 0.25)
		(keepout
			(tracks allowed)
			(vias allowed)
			(pads allowed)
			(copperpour allowed)
			(footprints allowed)
		)
		(placement
			(enabled no)
			(sheetname "")
		)
		(fill
			(thermal_gap 0.5)
			(thermal_bridge_width 0.5)
			(island_removal_mode 0)
		)
		(polygon
			(pts
				(xy 420.759636 -21.197316) (xy 420.759636 -19.373596) (xy 422.629076 -19.373596) (xy 422.629076 -21.197316)
			)
		)
	)
	(zone
		(layer "In15.Cu")
		(hatch none 0.5)
		(connect_pads
			(clearance 0)
		)
		(min_thickness 0.25)
		(keepout
			(tracks allowed)
			(vias allowed)
			(pads allowed)
			(copperpour allowed)
			(footprints allowed)
		)
		(placement
			(enabled no)
			(sheetname "")
		)
		(fill
			(thermal_gap 0.5)
			(thermal_bridge_width 0.5)
			(island_removal_mode 0)
		)
		(polygon
			(pts
				(xy 136.204706 -401.820634) (xy 136.204706 -399.859754) (xy 138.109706 -399.859754) (xy 138.109706 -401.820634)
			)
		)
	)
	(zone
		(layer "In15.Cu")
		(hatch none 0.5)
		(connect_pads
			(clearance 0)
		)
		(min_thickness 0.25)
		(keepout
			(tracks allowed)
			(vias allowed)
			(pads allowed)
			(copperpour allowed)
			(footprints allowed)
		)
		(placement
			(enabled no)
			(sheetname "")
		)
		(fill
			(thermal_gap 0.5)
			(thermal_bridge_width 0.5)
			(island_removal_mode 0)
		)
		(polygon
			(pts
				(xy 116.2177 -355.036628) (xy 116.2177 -353.421188) (xy 117.1194 -353.421188) (xy 117.1194 -355.036628)
			)
		)
	)
	(zone
		(layer "In15.Cu")
		(hatch none 0.5)
		(connect_pads
			(clearance 0)
		)
		(min_thickness 0.25)
		(keepout
			(tracks allowed)
			(vias allowed)
			(pads allowed)
			(copperpour allowed)
			(footprints allowed)
		)
		(placement
			(enabled no)
			(sheetname "")
		)
		(fill
			(thermal_gap 0.5)
			(thermal_bridge_width 0.5)
			(island_removal_mode 0)
		)
		(polygon
			(pts
				(xy 287.32988 -367.609628) (xy 287.32988 -366.357408) (xy 289.05962 -366.357408) (xy 289.05962 -367.609628)
			)
		)
	)
	(zone
		(layer "In15.Cu")
		(hatch none 0.5)
		(connect_pads
			(clearance 0)
		)
		(min_thickness 0.25)
		(keepout
			(tracks allowed)
			(vias allowed)
			(pads allowed)
			(copperpour allowed)
			(footprints allowed)
		)
		(placement
			(enabled no)
			(sheetname "")
		)
		(fill
			(thermal_gap 0.5)
			(thermal_bridge_width 0.5)
			(island_removal_mode 0)
		)
		(polygon
			(pts
				(xy 93.29928 -338.285328) (xy 93.29928 -335.829148) (xy 97.32264 -335.829148) (xy 97.32264 -338.285328)
			)
		)
	)
	(zone
		(layer "In15.Cu")
		(hatch none 0.5)
		(connect_pads
			(clearance 0)
		)
		(min_thickness 0.25)
		(keepout
			(tracks allowed)
			(vias allowed)
			(pads allowed)
			(copperpour allowed)
			(footprints allowed)
		)
		(placement
			(enabled no)
			(sheetname "")
		)
		(fill
			(thermal_gap 0.5)
			(thermal_bridge_width 0.5)
			(island_removal_mode 0)
		)
		(polygon
			(pts
				(xy 426.33773 -21.197316) (xy 426.33773 -19.373596) (xy 428.20717 -19.373596) (xy 428.20717 -21.197316)
			)
		)
	)
	(zone
		(layer "In15.Cu")
		(hatch none 0.5)
		(connect_pads
			(clearance 0)
		)
		(min_thickness 0.25)
		(keepout
			(tracks allowed)
			(vias allowed)
			(pads allowed)
			(copperpour allowed)
			(footprints allowed)
		)
		(placement
			(enabled no)
			(sheetname "")
		)
		(fill
			(thermal_gap 0.5)
			(thermal_bridge_width 0.5)
			(island_removal_mode 0)
		)
		(polygon
			(pts
				(xy 120.024906 -401.820634) (xy 120.024906 -399.859754) (xy 121.929906 -399.859754) (xy 121.929906 -401.820634)
			)
		)
	)
	(zone
		(layer "In15.Cu")
		(hatch none 0.5)
		(connect_pads
			(clearance 0)
		)
		(min_thickness 0.25)
		(keepout
			(tracks allowed)
			(vias allowed)
			(pads allowed)
			(copperpour allowed)
			(footprints allowed)
		)
		(placement
			(enabled no)
			(sheetname "")
		)
		(fill
			(thermal_gap 0.5)
			(thermal_bridge_width 0.5)
			(island_removal_mode 0)
		)
		(polygon
			(pts
				(xy 122.742706 -401.820634) (xy 122.742706 -399.859754) (xy 124.647706 -399.859754) (xy 124.647706 -401.820634)
			)
		)
	)
	(zone
		(layer "In15.Cu")
		(hatch none 0.5)
		(connect_pads
			(clearance 0)
		)
		(min_thickness 0.25)
		(keepout
			(tracks allowed)
			(vias allowed)
			(pads allowed)
			(copperpour allowed)
			(footprints allowed)
		)
		(placement
			(enabled no)
			(sheetname "")
		)
		(fill
			(thermal_gap 0.5)
			(thermal_bridge_width 0.5)
			(island_removal_mode 0)
		)
		(polygon
			(pts
				(xy 13.47216 -115.99672) (xy 13.47216 -113.75898) (xy 10.72896 -113.75898) (xy 10.72896 -115.99672)
			)
		)
	)
	(zone
		(layer "In15.Cu")
		(hatch none 0.5)
		(connect_pads
			(clearance 0)
		)
		(min_thickness 0.25)
		(keepout
			(tracks allowed)
			(vias allowed)
			(pads allowed)
			(copperpour allowed)
			(footprints allowed)
		)
		(placement
			(enabled no)
			(sheetname "")
		)
		(fill
			(thermal_gap 0.5)
			(thermal_bridge_width 0.5)
			(island_removal_mode 0)
		)
		(polygon
			(pts
				(xy 340.25078 -339.060028) (xy 340.25078 -335.610708) (xy 353.18954 -335.610708) (xy 353.18954 -339.060028)
			)
		)
	)
	(zone
		(layer "In15.Cu")
		(hatch none 0.5)
		(connect_pads
			(clearance 0)
		)
		(min_thickness 0.25)
		(keepout
			(tracks allowed)
			(vias allowed)
			(pads allowed)
			(copperpour allowed)
			(footprints allowed)
		)
		(placement
			(enabled no)
			(sheetname "")
		)
		(fill
			(thermal_gap 0.5)
			(thermal_bridge_width 0.5)
			(island_removal_mode 0)
		)
		(polygon
			(pts
				(xy 160.563052 -401.820634) (xy 160.563052 -399.859754) (xy 162.468052 -399.859754) (xy 162.468052 -401.820634)
			)
		)
	)
	(zone
		(layer "In15.Cu")
		(hatch none 0.5)
		(connect_pads
			(clearance 0)
		)
		(min_thickness 0.25)
		(keepout
			(tracks allowed)
			(vias allowed)
			(pads allowed)
			(copperpour allowed)
			(footprints allowed)
		)
		(placement
			(enabled no)
			(sheetname "")
		)
		(fill
			(thermal_gap 0.5)
			(thermal_bridge_width 0.5)
			(island_removal_mode 0)
		)
		(polygon
			(pts
				(xy 296.47896 -367.660428) (xy 296.47896 -366.263428) (xy 298.74718 -366.263428) (xy 298.74718 -367.660428)
			)
		)
	)
	(zone
		(layer "In15.Cu")
		(hatch none 0.5)
		(connect_pads
			(clearance 0)
		)
		(min_thickness 0.25)
		(keepout
			(tracks allowed)
			(vias allowed)
			(pads allowed)
			(copperpour allowed)
			(footprints allowed)
		)
		(placement
			(enabled no)
			(sheetname "")
		)
		(fill
			(thermal_gap 0.5)
			(thermal_bridge_width 0.5)
			(island_removal_mode 0)
		)
		(polygon
			(pts
				(xy 50.00498 -358.379268) (xy 50.00498 -357.508048) (xy 51.50866 -357.508048) (xy 51.50866 -358.379268)
			)
		)
	)
	(zone
		(layer "In15.Cu")
		(hatch none 0.5)
		(connect_pads
			(clearance 0)
		)
		(min_thickness 0.25)
		(keepout
			(tracks allowed)
			(vias allowed)
			(pads allowed)
			(copperpour allowed)
			(footprints allowed)
		)
		(placement
			(enabled no)
			(sheetname "")
		)
		(fill
			(thermal_gap 0.5)
			(thermal_bridge_width 0.5)
			(island_removal_mode 0)
		)
		(polygon
			(pts
				(xy 126.2507 -342.151208) (xy 126.2507 -339.672168) (xy 130.27406 -339.672168) (xy 130.27406 -342.151208)
			)
		)
	)
	(zone
		(layer "In15.Cu")
		(hatch none 0.5)
		(connect_pads
			(clearance 0)
		)
		(min_thickness 0.25)
		(keepout
			(tracks allowed)
			(vias allowed)
			(pads allowed)
			(copperpour allowed)
			(footprints allowed)
		)
		(placement
			(enabled no)
			(sheetname "")
		)
		(fill
			(thermal_gap 0.5)
			(thermal_bridge_width 0.5)
			(island_removal_mode 0)
		)
		(polygon
			(pts
				(xy 401.094448 -21.136356) (xy 401.094448 -19.312636) (xy 402.963888 -19.312636) (xy 402.963888 -21.136356)
			)
		)
	)
	(zone
		(layer "In15.Cu")
		(hatch none 0.5)
		(connect_pads
			(clearance 0)
		)
		(min_thickness 0.25)
		(keepout
			(tracks allowed)
			(vias allowed)
			(pads allowed)
			(copperpour allowed)
			(footprints allowed)
		)
		(placement
			(enabled no)
			(sheetname "")
		)
		(fill
			(thermal_gap 0.5)
			(thermal_bridge_width 0.5)
			(island_removal_mode 0)
		)
		(polygon
			(pts
				(xy 381.56388 -347.698568) (xy 381.56388 -343.855548) (xy 386.81406 -343.855548) (xy 386.81406 -347.698568)
			)
		)
	)
	(zone
		(layer "In15.Cu")
		(hatch none 0.5)
		(connect_pads
			(clearance 0)
		)
		(min_thickness 0.25)
		(keepout
			(tracks allowed)
			(vias allowed)
			(pads allowed)
			(copperpour allowed)
			(footprints allowed)
		)
		(placement
			(enabled no)
			(sheetname "")
		)
		(fill
			(thermal_gap 0.5)
			(thermal_bridge_width 0.5)
			(island_removal_mode 0)
		)
		(polygon
			(pts
				(xy 152.485852 -401.820634) (xy 152.485852 -399.859754) (xy 154.390852 -399.859754) (xy 154.390852 -401.820634)
			)
		)
	)
	(zone
		(layer "In15.Cu")
		(hatch none 0.5)
		(connect_pads
			(clearance 0)
		)
		(min_thickness 0.25)
		(keepout
			(tracks allowed)
			(vias allowed)
			(pads allowed)
			(copperpour allowed)
			(footprints allowed)
		)
		(placement
			(enabled no)
			(sheetname "")
		)
		(fill
			(thermal_gap 0.5)
			(thermal_bridge_width 0.5)
			(island_removal_mode 0)
		)
		(polygon
			(pts
				(xy 372.94566 -341.516208) (xy 372.94566 -339.773768) (xy 377.81992 -339.773768) (xy 377.81992 -341.516208)
			)
		)
	)
	(zone
		(layer "In15.Cu")
		(hatch none 0.5)
		(connect_pads
			(clearance 0)
		)
		(min_thickness 0.25)
		(keepout
			(tracks allowed)
			(vias allowed)
			(pads allowed)
			(copperpour allowed)
			(footprints allowed)
		)
		(placement
			(enabled no)
			(sheetname "")
		)
		(fill
			(thermal_gap 0.5)
			(thermal_bridge_width 0.5)
			(island_removal_mode 0)
		)
		(polygon
			(pts
				(xy 99.42322 -338.841588) (xy 99.42322 -334.244188) (xy 114.28476 -334.244188) (xy 114.28476 -338.841588)
			)
		)
	)
	(zone
		(layer "In15.Cu")
		(hatch none 0.5)
		(connect_pads
			(clearance 0)
		)
		(min_thickness 0.25)
		(keepout
			(tracks allowed)
			(vias allowed)
			(pads allowed)
			(copperpour allowed)
			(footprints allowed)
		)
		(placement
			(enabled no)
			(sheetname "")
		)
		(fill
			(thermal_gap 0.5)
			(thermal_bridge_width 0.5)
			(island_removal_mode 0)
		)
		(polygon
			(pts
				(xy 392.495786 -21.121116) (xy 392.495786 -19.297396) (xy 394.365226 -19.297396) (xy 394.365226 -21.121116)
			)
		)
	)
	(zone
		(layer "In15.Cu")
		(hatch none 0.5)
		(connect_pads
			(clearance 0)
		)
		(min_thickness 0.25)
		(keepout
			(tracks allowed)
			(vias allowed)
			(pads allowed)
			(copperpour allowed)
			(footprints allowed)
		)
		(placement
			(enabled no)
			(sheetname "")
		)
		(fill
			(thermal_gap 0.5)
			(thermal_bridge_width 0.5)
			(island_removal_mode 0)
		)
		(polygon
			(pts
				(xy 83.79206 -225.433128) (xy 83.79206 -221.821248) (xy 88.38438 -221.821248) (xy 88.38438 -225.433128)
			)
		)
	)
	(zone
		(layer "In15.Cu")
		(hatch none 0.5)
		(connect_pads
			(clearance 0)
		)
		(min_thickness 0.25)
		(keepout
			(tracks allowed)
			(vias allowed)
			(pads allowed)
			(copperpour allowed)
			(footprints allowed)
		)
		(placement
			(enabled no)
			(sheetname "")
		)
		(fill
			(thermal_gap 0.5)
			(thermal_bridge_width 0.5)
			(island_removal_mode 0)
		)
		(polygon
			(pts
				(xy 434.919628 -21.182076) (xy 434.919628 -19.358356) (xy 436.789068 -19.358356) (xy 436.789068 -21.182076)
			)
		)
	)
	(zone
		(layer "In15.Cu")
		(hatch none 0.5)
		(connect_pads
			(clearance 0)
		)
		(min_thickness 0.25)
		(keepout
			(tracks allowed)
			(vias allowed)
			(pads allowed)
			(copperpour allowed)
			(footprints allowed)
		)
		(placement
			(enabled no)
			(sheetname "")
		)
		(fill
			(thermal_gap 0.5)
			(thermal_bridge_width 0.5)
			(island_removal_mode 0)
		)
		(polygon
			(pts
				(xy 147.101052 -401.820634) (xy 147.101052 -399.859754) (xy 149.006052 -399.859754) (xy 149.006052 -401.820634)
			)
		)
	)
	(zone
		(layer "In15.Cu")
		(hatch none 0.5)
		(connect_pads
			(clearance 0)
		)
		(min_thickness 0.25)
		(keepout
			(tracks allowed)
			(vias allowed)
			(pads allowed)
			(copperpour allowed)
			(footprints allowed)
		)
		(placement
			(enabled no)
			(sheetname "")
		)
		(fill
			(thermal_gap 0.5)
			(thermal_bridge_width 0.5)
			(island_removal_mode 0)
		)
		(polygon
			(pts
				(xy 149.793452 -401.820634) (xy 149.793452 -399.859754) (xy 151.698452 -399.859754) (xy 151.698452 -401.820634)
			)
		)
	)
	(zone
		(layer "In15.Cu")
		(hatch none 0.5)
		(connect_pads
			(clearance 0)
		)
		(min_thickness 0.25)
		(keepout
			(tracks allowed)
			(vias allowed)
			(pads allowed)
			(copperpour allowed)
			(footprints allowed)
		)
		(placement
			(enabled no)
			(sheetname "")
		)
		(fill
			(thermal_gap 0.5)
			(thermal_bridge_width 0.5)
			(island_removal_mode 0)
		)
		(polygon
			(pts
				(xy 417.81603 -21.197316) (xy 417.81603 -19.373596) (xy 419.68547 -19.373596) (xy 419.68547 -21.197316)
			)
		)
	)
	(zone
		(layer "In15.Cu")
		(hatch none 0.5)
		(connect_pads
			(clearance 0)
		)
		(min_thickness 0.25)
		(keepout
			(tracks allowed)
			(vias allowed)
			(pads allowed)
			(copperpour allowed)
			(footprints allowed)
		)
		(placement
			(enabled no)
			(sheetname "")
		)
		(fill
			(thermal_gap 0.5)
			(thermal_bridge_width 0.5)
			(island_removal_mode 0)
		)
		(polygon
			(pts
				(xy 355.4222 -45.286168) (xy 355.4222 -44.163488) (xy 357.01224 -44.163488) (xy 357.01224 -45.286168)
			)
		)
	)
	(zone
		(layer "In15.Cu")
		(hatch none 0.5)
		(connect_pads
			(clearance 0)
		)
		(min_thickness 0.25)
		(keepout
			(tracks allowed)
			(vias allowed)
			(pads allowed)
			(copperpour allowed)
			(footprints allowed)
		)
		(placement
			(enabled no)
			(sheetname "")
		)
		(fill
			(thermal_gap 0.5)
			(thermal_bridge_width 0.5)
			(island_removal_mode 0)
		)
		(polygon
			(pts
				(xy 414.94202 -366.875568) (xy 414.94202 -365.712248) (xy 416.33394 -365.712248) (xy 416.33394 -366.875568)
			)
		)
	)
	(zone
		(layer "In15.Cu")
		(hatch none 0.5)
		(connect_pads
			(clearance 0)
		)
		(min_thickness 0.25)
		(keepout
			(tracks allowed)
			(vias allowed)
			(pads allowed)
			(copperpour allowed)
			(footprints allowed)
		)
		(placement
			(enabled no)
			(sheetname "")
		)
		(fill
			(thermal_gap 0.5)
			(thermal_bridge_width 0.5)
			(island_removal_mode 0)
		)
		(polygon
			(pts
				(xy 360.524806 -352.127312) (xy 363.026706 -352.127312) (xy 366.778286 -348.375732) (xy 383.006346 -348.375732)
				(xy 383.499106 -347.882972) (xy 383.499106 -346.546932) (xy 383.613406 -346.432632) (xy 383.824226 -346.432632)
				(xy 384.517646 -347.126052) (xy 384.517646 -347.976952) (xy 383.354326 -349.140272) (xy 367.136426 -349.140272)
				(xy 363.417866 -352.858832) (xy 361.192826 -352.858832) (xy 360.570526 -353.481132) (xy 360.301286 -353.481132)
				(xy 360.230166 -353.410012) (xy 360.230166 -352.421952)
			)
		)
	)
	(zone
		(layer "In15.Cu")
		(hatch none 0.5)
		(connect_pads
			(clearance 0)
		)
		(min_thickness 0.25)
		(keepout
			(tracks allowed)
			(vias allowed)
			(pads allowed)
			(copperpour allowed)
			(footprints allowed)
		)
		(placement
			(enabled no)
			(sheetname "")
		)
		(fill
			(thermal_gap 0.5)
			(thermal_bridge_width 0.5)
			(island_removal_mode 0)
		)
		(polygon
			(pts
				(xy 128.127506 -401.820634) (xy 128.127506 -399.859754) (xy 130.032506 -399.859754) (xy 130.032506 -401.820634)
			)
		)
	)
	(zone
		(layer "In15.Cu")
		(hatch none 0.5)
		(connect_pads
			(clearance 0)
		)
		(min_thickness 0.25)
		(keepout
			(tracks allowed)
			(vias allowed)
			(pads allowed)
			(copperpour allowed)
			(footprints allowed)
		)
		(placement
			(enabled no)
			(sheetname "")
		)
		(fill
			(thermal_gap 0.5)
			(thermal_bridge_width 0.5)
			(island_removal_mode 0)
		)
		(polygon
			(pts
				(xy 85.904832 -291.080698) (xy 85.904832 -212.495892) (xy 138.968988 -212.495892) (xy 138.968988 -291.080698)
			)
		)
	)
	(zone
		(layer "In16.Cu")
		(hatch none 0.5)
		(connect_pads
			(clearance 0)
		)
		(min_thickness 0.25)
		(keepout
			(tracks not_allowed)
			(vias allowed)
			(pads allowed)
			(copperpour not_allowed)
			(footprints allowed)
		)
		(placement
			(enabled no)
			(sheetname "")
		)
		(fill
			(thermal_gap 0.5)
			(thermal_bridge_width 0.5)
			(island_removal_mode 0)
		)
		(polygon
			(pts
				(arc
					(start 342.493092 -64.227964)
					(mid 342.470774 -64.174082)
					(end 342.416892 -64.151764)
				)
				(arc
					(start 342.086692 -64.151764)
					(mid 342.03281 -64.174082)
					(end 342.010492 -64.227964)
				)
				(arc
					(start 342.010492 -64.481964)
					(mid 342.03281 -64.535846)
					(end 342.086692 -64.558164)
				)
				(arc
					(start 342.416892 -64.558164)
					(mid 342.470774 -64.535846)
					(end 342.493092 -64.481964)
				)
			)
		)
	)
	(zone
		(layer "In16.Cu")
		(hatch none 0.5)
		(connect_pads
			(clearance 0)
		)
		(min_thickness 0.25)
		(keepout
			(tracks not_allowed)
			(vias allowed)
			(pads allowed)
			(copperpour not_allowed)
			(footprints allowed)
		)
		(placement
			(enabled no)
			(sheetname "")
		)
		(fill
			(thermal_gap 0.5)
			(thermal_bridge_width 0.5)
			(island_removal_mode 0)
		)
		(polygon
			(pts
				(xy 126.361698 -25.163272) (xy 126.869698 -25.163272) (xy 126.869698 -25.640284) (xy 126.361698 -25.640284)
			)
		)
	)
	(zone
		(layer "In16.Cu")
		(hatch none 0.5)
		(connect_pads
			(clearance 0)
		)
		(min_thickness 0.25)
		(keepout
			(tracks not_allowed)
			(vias allowed)
			(pads allowed)
			(copperpour not_allowed)
			(footprints allowed)
		)
		(placement
			(enabled no)
			(sheetname "")
		)
		(fill
			(thermal_gap 0.5)
			(thermal_bridge_width 0.5)
			(island_removal_mode 0)
		)
		(polygon
			(pts
				(arc
					(start 261.845044 -2.702306)
					(mid 261.822726 -2.756188)
					(end 261.768844 -2.778506)
				)
				(arc
					(start 261.156704 -2.778506)
					(mid 261.102822 -2.756188)
					(end 261.080504 -2.702306)
				)
				(arc
					(start 261.080504 -1.605026)
					(mid 261.102822 -1.551144)
					(end 261.156704 -1.528826)
				)
				(arc
					(start 261.768844 -1.528826)
					(mid 261.822726 -1.551144)
					(end 261.845044 -1.605026)
				)
			)
		)
	)
	(zone
		(layer "In16.Cu")
		(hatch none 0.5)
		(connect_pads
			(clearance 0)
		)
		(min_thickness 0.25)
		(keepout
			(tracks not_allowed)
			(vias allowed)
			(pads allowed)
			(copperpour not_allowed)
			(footprints allowed)
		)
		(placement
			(enabled no)
			(sheetname "")
		)
		(fill
			(thermal_gap 0.5)
			(thermal_bridge_width 0.5)
			(island_removal_mode 0)
		)
		(polygon
			(pts
				(arc
					(start 344.081608 -61.662564)
					(mid 344.05929 -61.608682)
					(end 344.005408 -61.586364)
				)
				(arc
					(start 343.675208 -61.586364)
					(mid 343.621326 -61.608682)
					(end 343.599008 -61.662564)
				)
				(arc
					(start 343.599008 -61.916564)
					(mid 343.621326 -61.970446)
					(end 343.675208 -61.992764)
				)
				(arc
					(start 344.005408 -61.992764)
					(mid 344.05929 -61.970446)
					(end 344.081608 -61.916564)
				)
			)
		)
	)
	(zone
		(layer "In16.Cu")
		(hatch none 0.5)
		(connect_pads
			(clearance 0)
		)
		(min_thickness 0.25)
		(keepout
			(tracks not_allowed)
			(vias allowed)
			(pads allowed)
			(copperpour not_allowed)
			(footprints allowed)
		)
		(placement
			(enabled no)
			(sheetname "")
		)
		(fill
			(thermal_gap 0.5)
			(thermal_bridge_width 0.5)
			(island_removal_mode 0)
		)
		(polygon
			(pts
				(xy 12.18946 -112.03051) (xy 12.18946 -111.21009) (xy 12.35964 -111.21009) (xy 12.35964 -112.03051)
			)
		)
	)
	(zone
		(layer "In16.Cu")
		(hatch none 0.5)
		(connect_pads
			(clearance 0)
		)
		(min_thickness 0.25)
		(keepout
			(tracks not_allowed)
			(vias allowed)
			(pads allowed)
			(copperpour not_allowed)
			(footprints allowed)
		)
		(placement
			(enabled no)
			(sheetname "")
		)
		(fill
			(thermal_gap 0.5)
			(thermal_bridge_width 0.5)
			(island_removal_mode 0)
		)
		(polygon
			(pts
				(arc
					(start 344.081608 -62.195964)
					(mid 344.05929 -62.142082)
					(end 344.005408 -62.119764)
				)
				(arc
					(start 343.675208 -62.119764)
					(mid 343.621326 -62.142082)
					(end 343.599008 -62.195964)
				)
				(arc
					(start 343.599008 -62.449964)
					(mid 343.621326 -62.503846)
					(end 343.675208 -62.526164)
				)
				(arc
					(start 344.005408 -62.526164)
					(mid 344.05929 -62.503846)
					(end 344.081608 -62.449964)
				)
			)
		)
	)
	(zone
		(layer "In16.Cu")
		(hatch none 0.5)
		(connect_pads
			(clearance 0)
		)
		(min_thickness 0.25)
		(keepout
			(tracks not_allowed)
			(vias allowed)
			(pads allowed)
			(copperpour not_allowed)
			(footprints allowed)
		)
		(placement
			(enabled no)
			(sheetname "")
		)
		(fill
			(thermal_gap 0.5)
			(thermal_bridge_width 0.5)
			(island_removal_mode 0)
		)
		(polygon
			(pts
				(arc
					(start 339.68436 -66.031364)
					(mid 339.662042 -65.977482)
					(end 339.60816 -65.955164)
				)
				(arc
					(start 339.27796 -65.955164)
					(mid 339.224078 -65.977482)
					(end 339.20176 -66.031364)
				)
				(arc
					(start 339.20176 -66.285364)
					(mid 339.224078 -66.339246)
					(end 339.27796 -66.361564)
				)
				(arc
					(start 339.60816 -66.361564)
					(mid 339.662042 -66.339246)
					(end 339.68436 -66.285364)
				)
			)
		)
	)
	(zone
		(layer "In16.Cu")
		(hatch none 0.5)
		(connect_pads
			(clearance 0)
		)
		(min_thickness 0.25)
		(keepout
			(tracks not_allowed)
			(vias allowed)
			(pads allowed)
			(copperpour not_allowed)
			(footprints allowed)
		)
		(placement
			(enabled no)
			(sheetname "")
		)
		(fill
			(thermal_gap 0.5)
			(thermal_bridge_width 0.5)
			(island_removal_mode 0)
		)
		(polygon
			(pts
				(arc
					(start 345.7956 -63.694564)
					(mid 345.773282 -63.640682)
					(end 345.7194 -63.618364)
				)
				(arc
					(start 345.3892 -63.618364)
					(mid 345.335318 -63.640682)
					(end 345.313 -63.694564)
				)
				(arc
					(start 345.313 -63.948564)
					(mid 345.335318 -64.002446)
					(end 345.3892 -64.024764)
				)
				(arc
					(start 345.7194 -64.024764)
					(mid 345.773282 -64.002446)
					(end 345.7956 -63.948564)
				)
			)
		)
	)
	(zone
		(layer "In16.Cu")
		(hatch none 0.5)
		(connect_pads
			(clearance 0)
		)
		(min_thickness 0.25)
		(keepout
			(tracks not_allowed)
			(vias allowed)
			(pads allowed)
			(copperpour not_allowed)
			(footprints allowed)
		)
		(placement
			(enabled no)
			(sheetname "")
		)
		(fill
			(thermal_gap 0.5)
			(thermal_bridge_width 0.5)
			(island_removal_mode 0)
		)
		(polygon
			(pts
				(arc
					(start 167.937688 -48.862488)
					(mid 167.277288 -48.862488)
					(end 167.937688 -48.862488)
				)
			)
		)
	)
	(zone
		(layer "In16.Cu")
		(hatch none 0.5)
		(connect_pads
			(clearance 0)
		)
		(min_thickness 0.25)
		(keepout
			(tracks not_allowed)
			(vias allowed)
			(pads allowed)
			(copperpour not_allowed)
			(footprints allowed)
		)
		(placement
			(enabled no)
			(sheetname "")
		)
		(fill
			(thermal_gap 0.5)
			(thermal_bridge_width 0.5)
			(island_removal_mode 0)
		)
		(polygon
			(pts
				(arc
					(start 340.647528 -62.195964)
					(mid 340.62521 -62.142082)
					(end 340.571328 -62.119764)
				)
				(arc
					(start 340.241128 -62.119764)
					(mid 340.187246 -62.142082)
					(end 340.164928 -62.195964)
				)
				(arc
					(start 340.164928 -62.449964)
					(mid 340.187246 -62.503846)
					(end 340.241128 -62.526164)
				)
				(arc
					(start 340.571328 -62.526164)
					(mid 340.62521 -62.503846)
					(end 340.647528 -62.449964)
				)
			)
		)
	)
	(zone
		(layer "In16.Cu")
		(hatch none 0.5)
		(connect_pads
			(clearance 0)
		)
		(min_thickness 0.25)
		(keepout
			(tracks not_allowed)
			(vias allowed)
			(pads allowed)
			(copperpour not_allowed)
			(footprints allowed)
		)
		(placement
			(enabled no)
			(sheetname "")
		)
		(fill
			(thermal_gap 0.5)
			(thermal_bridge_width 0.5)
			(island_removal_mode 0)
		)
		(polygon
			(pts
				(arc
					(start 340.41207 -2.702306)
					(mid 340.389752 -2.756188)
					(end 340.33587 -2.778506)
				)
				(arc
					(start 339.72373 -2.778506)
					(mid 339.669848 -2.756188)
					(end 339.64753 -2.702306)
				)
				(arc
					(start 339.64753 -1.605026)
					(mid 339.669848 -1.551144)
					(end 339.72373 -1.528826)
				)
				(arc
					(start 340.33587 -1.528826)
					(mid 340.389752 -1.551144)
					(end 340.41207 -1.605026)
				)
			)
		)
	)
	(zone
		(layer "In16.Cu")
		(hatch none 0.5)
		(connect_pads
			(clearance 0)
		)
		(min_thickness 0.25)
		(keepout
			(tracks not_allowed)
			(vias allowed)
			(pads allowed)
			(copperpour not_allowed)
			(footprints allowed)
		)
		(placement
			(enabled no)
			(sheetname "")
		)
		(fill
			(thermal_gap 0.5)
			(thermal_bridge_width 0.5)
			(island_removal_mode 0)
		)
		(polygon
			(pts
				(arc
					(start 346.063824 -58.957972)
					(mid 346.009886 -58.935667)
					(end 345.955874 -58.957972)
				)
				(arc
					(start 345.722448 -59.191398)
					(mid 345.699964 -59.24541)
					(end 345.722448 -59.299348)
				)
				(arc
					(start 345.902026 -59.478926)
					(mid 345.955874 -59.501231)
					(end 346.009722 -59.478926)
				)
				(arc
					(start 346.243402 -59.2455)
					(mid 346.265707 -59.191562)
					(end 346.243402 -59.13755)
				)
			)
		)
	)
	(zone
		(layer "In16.Cu")
		(hatch none 0.5)
		(connect_pads
			(clearance 0)
		)
		(min_thickness 0.25)
		(keepout
			(tracks not_allowed)
			(vias allowed)
			(pads allowed)
			(copperpour not_allowed)
			(footprints allowed)
		)
		(placement
			(enabled no)
			(sheetname "")
		)
		(fill
			(thermal_gap 0.5)
			(thermal_bridge_width 0.5)
			(island_removal_mode 0)
		)
		(polygon
			(pts
				(arc
					(start 328.126852 8.549894)
					(mid 328.14917 8.603776)
					(end 328.203052 8.626094)
				)
				(arc
					(start 328.815192 8.626094)
					(mid 328.869074 8.603776)
					(end 328.891392 8.549894)
				)
				(arc
					(start 328.891392 7.452614)
					(mid 328.869074 7.398732)
					(end 328.815192 7.376414)
				)
				(arc
					(start 328.203052 7.376414)
					(mid 328.14917 7.398732)
					(end 328.126852 7.452614)
				)
			)
		)
	)
	(zone
		(layer "In16.Cu")
		(hatch none 0.5)
		(connect_pads
			(clearance 0)
		)
		(min_thickness 0.25)
		(keepout
			(tracks not_allowed)
			(vias allowed)
			(pads allowed)
			(copperpour not_allowed)
			(footprints allowed)
		)
		(placement
			(enabled no)
			(sheetname "")
		)
		(fill
			(thermal_gap 0.5)
			(thermal_bridge_width 0.5)
			(island_removal_mode 0)
		)
		(polygon
			(pts
				(arc
					(start 249.541284 6.0071)
					(mid 249.563602 6.060982)
					(end 249.617484 6.0833)
				)
				(arc
					(start 250.229624 6.0833)
					(mid 250.283506 6.060982)
					(end 250.305824 6.0071)
				)
				(arc
					(start 250.305824 4.90982)
					(mid 250.283506 4.855938)
					(end 250.229624 4.83362)
				)
				(arc
					(start 249.617484 4.83362)
					(mid 249.563602 4.855938)
					(end 249.541284 4.90982)
				)
			)
		)
	)
	(zone
		(layer "In16.Cu")
		(hatch none 0.5)
		(connect_pads
			(clearance 0)
		)
		(min_thickness 0.25)
		(keepout
			(tracks not_allowed)
			(vias allowed)
			(pads allowed)
			(copperpour not_allowed)
			(footprints allowed)
		)
		(placement
			(enabled no)
			(sheetname "")
		)
		(fill
			(thermal_gap 0.5)
			(thermal_bridge_width 0.5)
			(island_removal_mode 0)
		)
		(polygon
			(pts
				(arc
					(start 343.407492 -64.227964)
					(mid 343.385174 -64.174082)
					(end 343.331292 -64.151764)
				)
				(arc
					(start 343.001092 -64.151764)
					(mid 342.94721 -64.174082)
					(end 342.924892 -64.227964)
				)
				(arc
					(start 342.924892 -64.481964)
					(mid 342.94721 -64.535846)
					(end 343.001092 -64.558164)
				)
				(arc
					(start 343.331292 -64.558164)
					(mid 343.385174 -64.535846)
					(end 343.407492 -64.481964)
				)
			)
		)
	)
	(zone
		(layer "In16.Cu")
		(hatch none 0.5)
		(connect_pads
			(clearance 0)
		)
		(min_thickness 0.25)
		(keepout
			(tracks not_allowed)
			(vias allowed)
			(pads allowed)
			(copperpour not_allowed)
			(footprints allowed)
		)
		(placement
			(enabled no)
			(sheetname "")
		)
		(fill
			(thermal_gap 0.5)
			(thermal_bridge_width 0.5)
			(island_removal_mode 0)
		)
		(polygon
			(pts
				(arc
					(start 133.428232 -27.996896)
					(mid 133.389191 -28.004653)
					(end 133.35635 -28.027122)
				)
				(arc
					(start 133.35635 -28.027122)
					(mid 133.336308 -28.05781)
					(end 133.328664 -28.09367)
				)
				(xy 133.328664 -28.23591) (xy 133.328918 -28.23591)
				(arc
					(start 133.328918 -29.163264)
					(mid 133.358108 -29.22677)
					(end 133.422136 -29.254704)
				)
				(arc
					(start 133.728968 -29.254704)
					(mid 133.768009 -29.246947)
					(end 133.80085 -29.224478)
				)
				(arc
					(start 133.80085 -29.224478)
					(mid 133.820892 -29.19379)
					(end 133.828536 -29.15793)
				)
				(xy 133.828536 -28.12669) (xy 133.828282 -28.12669)
				(arc
					(start 133.828282 -28.088336)
					(mid 133.799092 -28.02483)
					(end 133.735064 -27.996896)
				)
			)
		)
	)
	(zone
		(layer "In16.Cu")
		(hatch none 0.5)
		(connect_pads
			(clearance 0)
		)
		(min_thickness 0.25)
		(keepout
			(tracks not_allowed)
			(vias allowed)
			(pads allowed)
			(copperpour not_allowed)
			(footprints allowed)
		)
		(placement
			(enabled no)
			(sheetname "")
		)
		(fill
			(thermal_gap 0.5)
			(thermal_bridge_width 0.5)
			(island_removal_mode 0)
		)
		(polygon
			(pts
				(xy 140.39088 -29.540708) (xy 140.39088 -28.720288) (xy 140.56106 -28.720288) (xy 140.56106 -29.540708)
			)
		)
	)
	(zone
		(layer "In16.Cu")
		(hatch none 0.5)
		(connect_pads
			(clearance 0)
		)
		(min_thickness 0.25)
		(keepout
			(tracks not_allowed)
			(vias allowed)
			(pads allowed)
			(copperpour not_allowed)
			(footprints allowed)
		)
		(placement
			(enabled no)
			(sheetname "")
		)
		(fill
			(thermal_gap 0.5)
			(thermal_bridge_width 0.5)
			(island_removal_mode 0)
		)
		(polygon
			(pts
				(arc
					(start 340.41207 2.377694)
					(mid 340.389752 2.323812)
					(end 340.33587 2.301494)
				)
				(arc
					(start 339.72373 2.301494)
					(mid 339.669848 2.323812)
					(end 339.64753 2.377694)
				)
				(arc
					(start 339.64753 3.474974)
					(mid 339.669848 3.528856)
					(end 339.72373 3.551174)
				)
				(arc
					(start 340.33587 3.551174)
					(mid 340.389752 3.528856)
					(end 340.41207 3.474974)
				)
			)
		)
	)
	(zone
		(layer "In16.Cu")
		(hatch none 0.5)
		(connect_pads
			(clearance 0)
		)
		(min_thickness 0.25)
		(keepout
			(tracks not_allowed)
			(vias allowed)
			(pads allowed)
			(copperpour not_allowed)
			(footprints allowed)
		)
		(placement
			(enabled no)
			(sheetname "")
		)
		(fill
			(thermal_gap 0.5)
			(thermal_bridge_width 0.5)
			(island_removal_mode 0)
		)
		(polygon
			(pts
				(arc
					(start 345.686634 -58.580782)
					(mid 345.632696 -58.558477)
					(end 345.578684 -58.580782)
				)
				(arc
					(start 345.345258 -58.814462)
					(mid 345.322953 -58.86831)
					(end 345.345258 -58.922158)
				)
				(arc
					(start 345.524836 -59.101736)
					(mid 345.578684 -59.124041)
					(end 345.632532 -59.101736)
				)
				(arc
					(start 345.866212 -58.86831)
					(mid 345.888517 -58.814372)
					(end 345.866212 -58.76036)
				)
			)
		)
	)
	(zone
		(layer "In16.Cu")
		(hatch none 0.5)
		(connect_pads
			(clearance 0)
		)
		(min_thickness 0.25)
		(keepout
			(tracks not_allowed)
			(vias allowed)
			(pads allowed)
			(copperpour not_allowed)
			(footprints allowed)
		)
		(placement
			(enabled no)
			(sheetname "")
		)
		(fill
			(thermal_gap 0.5)
			(thermal_bridge_width 0.5)
			(island_removal_mode 0)
		)
		(polygon
			(pts
				(arc
					(start 183.259476 4.9149)
					(mid 183.237158 4.861018)
					(end 183.183276 4.8387)
				)
				(arc
					(start 182.571136 4.8387)
					(mid 182.517254 4.861018)
					(end 182.494936 4.9149)
				)
				(arc
					(start 182.494936 6.01218)
					(mid 182.517254 6.066062)
					(end 182.571136 6.08838)
				)
				(arc
					(start 183.183276 6.08838)
					(mid 183.237158 6.066062)
					(end 183.259476 6.01218)
				)
			)
		)
	)
	(zone
		(layer "In16.Cu")
		(hatch none 0.5)
		(connect_pads
			(clearance 0)
		)
		(min_thickness 0.25)
		(keepout
			(tracks not_allowed)
			(vias allowed)
			(pads allowed)
			(copperpour not_allowed)
			(footprints allowed)
		)
		(placement
			(enabled no)
			(sheetname "")
		)
		(fill
			(thermal_gap 0.5)
			(thermal_bridge_width 0.5)
			(island_removal_mode 0)
		)
		(polygon
			(pts
				(arc
					(start 261.845044 2.377694)
					(mid 261.822726 2.323812)
					(end 261.768844 2.301494)
				)
				(arc
					(start 261.156704 2.301494)
					(mid 261.102822 2.323812)
					(end 261.080504 2.377694)
				)
				(arc
					(start 261.080504 3.474974)
					(mid 261.102822 3.528856)
					(end 261.156704 3.551174)
				)
				(arc
					(start 261.768844 3.551174)
					(mid 261.822726 3.528856)
					(end 261.845044 3.474974)
				)
			)
		)
	)
	(zone
		(layer "In16.Cu")
		(hatch none 0.5)
		(connect_pads
			(clearance 0)
		)
		(min_thickness 0.25)
		(keepout
			(tracks not_allowed)
			(vias allowed)
			(pads allowed)
			(copperpour not_allowed)
			(footprints allowed)
		)
		(placement
			(enabled no)
			(sheetname "")
		)
		(fill
			(thermal_gap 0.5)
			(thermal_bridge_width 0.5)
			(island_removal_mode 0)
		)
		(polygon
			(pts
				(arc
					(start 328.126852 -1.610106)
					(mid 328.14917 -1.556224)
					(end 328.203052 -1.533906)
				)
				(arc
					(start 328.815192 -1.533906)
					(mid 328.869074 -1.556224)
					(end 328.891392 -1.610106)
				)
				(arc
					(start 328.891392 -2.707386)
					(mid 328.869074 -2.761268)
					(end 328.815192 -2.783586)
				)
				(arc
					(start 328.203052 -2.783586)
					(mid 328.14917 -2.761268)
					(end 328.126852 -2.707386)
				)
			)
		)
	)
	(zone
		(layer "In16.Cu")
		(hatch none 0.5)
		(connect_pads
			(clearance 0)
		)
		(min_thickness 0.25)
		(keepout
			(tracks not_allowed)
			(vias allowed)
			(pads allowed)
			(copperpour not_allowed)
			(footprints allowed)
		)
		(placement
			(enabled no)
			(sheetname "")
		)
		(fill
			(thermal_gap 0.5)
			(thermal_bridge_width 0.5)
			(island_removal_mode 0)
		)
		(polygon
			(pts
				(xy 12.18946 -113.430558) (xy 12.18946 -112.610138) (xy 12.35964 -112.610138) (xy 12.35964 -113.430558)
			)
		)
	)
	(zone
		(layer "In16.Cu")
		(hatch none 0.5)
		(connect_pads
			(clearance 0)
		)
		(min_thickness 0.25)
		(keepout
			(tracks not_allowed)
			(vias allowed)
			(pads allowed)
			(copperpour not_allowed)
			(footprints allowed)
		)
		(placement
			(enabled no)
			(sheetname "")
		)
		(fill
			(thermal_gap 0.5)
			(thermal_bridge_width 0.5)
			(island_removal_mode 0)
		)
		(polygon
			(pts
				(arc
					(start 349.536004 -65.33642)
					(mid 349.589886 -65.314102)
					(end 349.612204 -65.26022)
				)
				(arc
					(start 349.612204 -64.93002)
					(mid 349.589886 -64.876138)
					(end 349.536004 -64.85382)
				)
				(arc
					(start 349.282004 -64.85382)
					(mid 349.228122 -64.876138)
					(end 349.205804 -64.93002)
				)
				(arc
					(start 349.205804 -65.26022)
					(mid 349.228122 -65.314102)
					(end 349.282004 -65.33642)
				)
			)
		)
	)
	(zone
		(layer "In16.Cu")
		(hatch none 0.5)
		(connect_pads
			(clearance 0)
		)
		(min_thickness 0.25)
		(keepout
			(tracks not_allowed)
			(vias allowed)
			(pads allowed)
			(copperpour not_allowed)
			(footprints allowed)
		)
		(placement
			(enabled no)
			(sheetname "")
		)
		(fill
			(thermal_gap 0.5)
			(thermal_bridge_width 0.5)
			(island_removal_mode 0)
		)
		(polygon
			(pts
				(arc
					(start 339.68436 -66.564764)
					(mid 339.662042 -66.510882)
					(end 339.60816 -66.488564)
				)
				(arc
					(start 339.27796 -66.488564)
					(mid 339.224078 -66.510882)
					(end 339.20176 -66.564764)
				)
				(arc
					(start 339.20176 -66.818764)
					(mid 339.224078 -66.872646)
					(end 339.27796 -66.894964)
				)
				(arc
					(start 339.60816 -66.894964)
					(mid 339.662042 -66.872646)
					(end 339.68436 -66.818764)
				)
			)
		)
	)
	(zone
		(layer "In16.Cu")
		(hatch none 0.5)
		(connect_pads
			(clearance 0)
		)
		(min_thickness 0.25)
		(keepout
			(tracks not_allowed)
			(vias allowed)
			(pads allowed)
			(copperpour not_allowed)
			(footprints allowed)
		)
		(placement
			(enabled no)
			(sheetname "")
		)
		(fill
			(thermal_gap 0.5)
			(thermal_bridge_width 0.5)
			(island_removal_mode 0)
		)
		(polygon
			(pts
				(xy 125.522736 -25.532842) (xy 125.522736 -26.015442) (xy 125.116336 -26.015442) (xy 125.116336 -25.532842)
			)
		)
	)
	(zone
		(layer "In16.Cu")
		(hatch none 0.5)
		(connect_pads
			(clearance 0)
		)
		(min_thickness 0.25)
		(keepout
			(tracks not_allowed)
			(vias allowed)
			(pads allowed)
			(copperpour not_allowed)
			(footprints allowed)
		)
		(placement
			(enabled no)
			(sheetname "")
		)
		(fill
			(thermal_gap 0.5)
			(thermal_bridge_width 0.5)
			(island_removal_mode 0)
		)
		(polygon
			(pts
				(arc
					(start 340.59876 -66.564764)
					(mid 340.576442 -66.510882)
					(end 340.52256 -66.488564)
				)
				(arc
					(start 340.19236 -66.488564)
					(mid 340.138478 -66.510882)
					(end 340.11616 -66.564764)
				)
				(arc
					(start 340.11616 -66.818764)
					(mid 340.138478 -66.872646)
					(end 340.19236 -66.894964)
				)
				(arc
					(start 340.52256 -66.894964)
					(mid 340.576442 -66.872646)
					(end 340.59876 -66.818764)
				)
			)
		)
	)
	(zone
		(layer "In16.Cu")
		(hatch none 0.5)
		(connect_pads
			(clearance 0)
		)
		(min_thickness 0.25)
		(keepout
			(tracks not_allowed)
			(vias allowed)
			(pads allowed)
			(copperpour not_allowed)
			(footprints allowed)
		)
		(placement
			(enabled no)
			(sheetname "")
		)
		(fill
			(thermal_gap 0.5)
			(thermal_bridge_width 0.5)
			(island_removal_mode 0)
		)
		(polygon
			(pts
				(arc
					(start 139.041886 -25.564338)
					(mid 138.381994 -25.564338)
					(end 139.041886 -25.564338)
				)
			)
		)
	)
	(zone
		(layer "In16.Cu")
		(hatch none 0.5)
		(connect_pads
			(clearance 0)
		)
		(min_thickness 0.25)
		(keepout
			(tracks not_allowed)
			(vias allowed)
			(pads allowed)
			(copperpour not_allowed)
			(footprints allowed)
		)
		(placement
			(enabled no)
			(sheetname "")
		)
		(fill
			(thermal_gap 0.5)
			(thermal_bridge_width 0.5)
			(island_removal_mode 0)
		)
		(polygon
			(pts
				(arc
					(start 337.460082 -63.922148)
					(mid 337.437764 -63.868266)
					(end 337.383882 -63.845948)
				)
				(arc
					(start 337.053682 -63.845948)
					(mid 336.9998 -63.868266)
					(end 336.977482 -63.922148)
				)
				(arc
					(start 336.977482 -64.176148)
					(mid 336.9998 -64.23003)
					(end 337.053682 -64.252348)
				)
				(arc
					(start 337.383882 -64.252348)
					(mid 337.437764 -64.23003)
					(end 337.460082 -64.176148)
				)
			)
		)
	)
	(zone
		(layer "In16.Cu")
		(hatch none 0.5)
		(connect_pads
			(clearance 0)
		)
		(min_thickness 0.25)
		(keepout
			(tracks not_allowed)
			(vias allowed)
			(pads allowed)
			(copperpour not_allowed)
			(footprints allowed)
		)
		(placement
			(enabled no)
			(sheetname "")
		)
		(fill
			(thermal_gap 0.5)
			(thermal_bridge_width 0.5)
			(island_removal_mode 0)
		)
		(polygon
			(pts
				(arc
					(start 37.117528 -406.926796)
					(mid 37.109771 -406.887755)
					(end 37.087302 -406.854914)
				)
				(arc
					(start 37.087302 -406.854914)
					(mid 37.056614 -406.834872)
					(end 37.020754 -406.827228)
				)
				(xy 36.878514 -406.827228) (xy 36.878514 -406.827482)
				(arc
					(start 35.95116 -406.827482)
					(mid 35.887654 -406.856672)
					(end 35.85972 -406.9207)
				)
				(arc
					(start 35.85972 -407.227532)
					(mid 35.867477 -407.266573)
					(end 35.889946 -407.299414)
				)
				(arc
					(start 35.889946 -407.299414)
					(mid 35.920634 -407.319456)
					(end 35.956494 -407.3271)
				)
				(xy 36.987734 -407.3271) (xy 36.987734 -407.326846)
				(arc
					(start 37.026088 -407.326846)
					(mid 37.089594 -407.297656)
					(end 37.117528 -407.233628)
				)
			)
		)
	)
	(zone
		(layer "In16.Cu")
		(hatch none 0.5)
		(connect_pads
			(clearance 0)
		)
		(min_thickness 0.25)
		(keepout
			(tracks not_allowed)
			(vias allowed)
			(pads allowed)
			(copperpour not_allowed)
			(footprints allowed)
		)
		(placement
			(enabled no)
			(sheetname "")
		)
		(fill
			(thermal_gap 0.5)
			(thermal_bridge_width 0.5)
			(island_removal_mode 0)
		)
		(polygon
			(pts
				(xy 124.989336 -24.745442) (xy 124.989336 -25.228042) (xy 124.582936 -25.228042) (xy 124.582936 -24.745442)
			)
		)
	)
	(zone
		(layer "In16.Cu")
		(hatch none 0.5)
		(connect_pads
			(clearance 0)
		)
		(min_thickness 0.25)
		(keepout
			(tracks not_allowed)
			(vias allowed)
			(pads allowed)
			(copperpour not_allowed)
			(footprints allowed)
		)
		(placement
			(enabled no)
			(sheetname "")
		)
		(fill
			(thermal_gap 0.5)
			(thermal_bridge_width 0.5)
			(island_removal_mode 0)
		)
		(polygon
			(pts
				(arc
					(start 340.59876 -66.031364)
					(mid 340.576442 -65.977482)
					(end 340.52256 -65.955164)
				)
				(arc
					(start 340.19236 -65.955164)
					(mid 340.138478 -65.977482)
					(end 340.11616 -66.031364)
				)
				(arc
					(start 340.11616 -66.285364)
					(mid 340.138478 -66.339246)
					(end 340.19236 -66.361564)
				)
				(arc
					(start 340.52256 -66.361564)
					(mid 340.576442 -66.339246)
					(end 340.59876 -66.285364)
				)
			)
		)
	)
	(zone
		(layer "In16.Cu")
		(hatch none 0.5)
		(connect_pads
			(clearance 0)
		)
		(min_thickness 0.25)
		(keepout
			(tracks not_allowed)
			(vias allowed)
			(pads allowed)
			(copperpour not_allowed)
			(footprints allowed)
		)
		(placement
			(enabled no)
			(sheetname "")
		)
		(fill
			(thermal_gap 0.5)
			(thermal_bridge_width 0.5)
			(island_removal_mode 0)
		)
		(polygon
			(pts
				(xy 11.789664 -112.03051) (xy 11.789664 -111.21009) (xy 11.959844 -111.21009) (xy 11.959844 -112.03051)
			)
		)
	)
	(zone
		(layer "In16.Cu")
		(hatch none 0.5)
		(connect_pads
			(clearance 0)
		)
		(min_thickness 0.25)
		(keepout
			(tracks not_allowed)
			(vias allowed)
			(pads allowed)
			(copperpour not_allowed)
			(footprints allowed)
		)
		(placement
			(enabled no)
			(sheetname "")
		)
		(fill
			(thermal_gap 0.5)
			(thermal_bridge_width 0.5)
			(island_removal_mode 0)
		)
		(polygon
			(pts
				(arc
					(start 376.986038 8.549894)
					(mid 377.008356 8.603776)
					(end 377.062238 8.626094)
				)
				(arc
					(start 377.674378 8.626094)
					(mid 377.72826 8.603776)
					(end 377.750578 8.549894)
				)
				(arc
					(start 377.750578 7.452614)
					(mid 377.72826 7.398732)
					(end 377.674378 7.376414)
				)
				(arc
					(start 377.062238 7.376414)
					(mid 377.008356 7.398732)
					(end 376.986038 7.452614)
				)
			)
		)
	)
	(zone
		(layer "In16.Cu")
		(hatch none 0.5)
		(connect_pads
			(clearance 0)
		)
		(min_thickness 0.25)
		(keepout
			(tracks not_allowed)
			(vias allowed)
			(pads allowed)
			(copperpour not_allowed)
			(footprints allowed)
		)
		(placement
			(enabled no)
			(sheetname "")
		)
		(fill
			(thermal_gap 0.5)
			(thermal_bridge_width 0.5)
			(island_removal_mode 0)
		)
		(polygon
			(pts
				(arc
					(start 133.428232 -26.244296)
					(mid 133.389191 -26.252053)
					(end 133.35635 -26.274522)
				)
				(arc
					(start 133.35635 -26.274522)
					(mid 133.336308 -26.30521)
					(end 133.328664 -26.34107)
				)
				(xy 133.328664 -26.48331) (xy 133.328918 -26.48331)
				(arc
					(start 133.328918 -27.410664)
					(mid 133.358108 -27.47417)
					(end 133.422136 -27.502104)
				)
				(arc
					(start 133.728968 -27.502104)
					(mid 133.768009 -27.494347)
					(end 133.80085 -27.471878)
				)
				(arc
					(start 133.80085 -27.471878)
					(mid 133.820892 -27.44119)
					(end 133.828536 -27.40533)
				)
				(xy 133.828536 -26.37409) (xy 133.828282 -26.37409)
				(arc
					(start 133.828282 -26.335736)
					(mid 133.799092 -26.27223)
					(end 133.735064 -26.244296)
				)
			)
		)
	)
	(zone
		(layer "In16.Cu")
		(hatch none 0.5)
		(connect_pads
			(clearance 0)
		)
		(min_thickness 0.25)
		(keepout
			(tracks not_allowed)
			(vias allowed)
			(pads allowed)
			(copperpour not_allowed)
			(footprints allowed)
		)
		(placement
			(enabled no)
			(sheetname "")
		)
		(fill
			(thermal_gap 0.5)
			(thermal_bridge_width 0.5)
			(island_removal_mode 0)
		)
		(polygon
			(pts
				(arc
					(start 337.460082 -64.455548)
					(mid 337.437764 -64.401666)
					(end 337.383882 -64.379348)
				)
				(arc
					(start 337.053682 -64.379348)
					(mid 336.9998 -64.401666)
					(end 336.977482 -64.455548)
				)
				(arc
					(start 336.977482 -64.709548)
					(mid 336.9998 -64.76343)
					(end 337.053682 -64.785748)
				)
				(arc
					(start 337.383882 -64.785748)
					(mid 337.437764 -64.76343)
					(end 337.460082 -64.709548)
				)
			)
		)
	)
	(zone
		(layer "In16.Cu")
		(hatch none 0.5)
		(connect_pads
			(clearance 0)
		)
		(min_thickness 0.25)
		(keepout
			(tracks not_allowed)
			(vias allowed)
			(pads allowed)
			(copperpour not_allowed)
			(footprints allowed)
		)
		(placement
			(enabled no)
			(sheetname "")
		)
		(fill
			(thermal_gap 0.5)
			(thermal_bridge_width 0.5)
			(island_removal_mode 0)
		)
		(polygon
			(pts
				(arc
					(start 212.967316 -2.7051)
					(mid 212.944998 -2.758982)
					(end 212.891116 -2.7813)
				)
				(arc
					(start 212.278976 -2.7813)
					(mid 212.225094 -2.758982)
					(end 212.202776 -2.7051)
				)
				(arc
					(start 212.202776 -1.60782)
					(mid 212.225094 -1.553938)
					(end 212.278976 -1.53162)
				)
				(arc
					(start 212.891116 -1.53162)
					(mid 212.944998 -1.553938)
					(end 212.967316 -1.60782)
				)
			)
		)
	)
	(zone
		(layer "In16.Cu")
		(hatch none 0.5)
		(connect_pads
			(clearance 0)
		)
		(min_thickness 0.25)
		(keepout
			(tracks not_allowed)
			(vias allowed)
			(pads allowed)
			(copperpour not_allowed)
			(footprints allowed)
		)
		(placement
			(enabled no)
			(sheetname "")
		)
		(fill
			(thermal_gap 0.5)
			(thermal_bridge_width 0.5)
			(island_removal_mode 0)
		)
		(polygon
			(pts
				(xy 140.790676 -28.14066) (xy 140.790676 -27.32024) (xy 140.960856 -27.32024) (xy 140.960856 -28.14066)
			)
		)
	)
	(zone
		(layer "In16.Cu")
		(hatch none 0.5)
		(connect_pads
			(clearance 0)
		)
		(min_thickness 0.25)
		(keepout
			(tracks not_allowed)
			(vias allowed)
			(pads allowed)
			(copperpour not_allowed)
			(footprints allowed)
		)
		(placement
			(enabled no)
			(sheetname "")
		)
		(fill
			(thermal_gap 0.5)
			(thermal_bridge_width 0.5)
			(island_removal_mode 0)
		)
		(polygon
			(pts
				(arc
					(start 328.126852 3.469894)
					(mid 328.14917 3.523776)
					(end 328.203052 3.546094)
				)
				(arc
					(start 328.815192 3.546094)
					(mid 328.869074 3.523776)
					(end 328.891392 3.469894)
				)
				(arc
					(start 328.891392 2.372614)
					(mid 328.869074 2.318732)
					(end 328.815192 2.296414)
				)
				(arc
					(start 328.203052 2.296414)
					(mid 328.14917 2.318732)
					(end 328.126852 2.372614)
				)
			)
		)
	)
	(zone
		(layer "In16.Cu")
		(hatch none 0.5)
		(connect_pads
			(clearance 0)
		)
		(min_thickness 0.25)
		(keepout
			(tracks not_allowed)
			(vias allowed)
			(pads allowed)
			(copperpour not_allowed)
			(footprints allowed)
		)
		(placement
			(enabled no)
			(sheetname "")
		)
		(fill
			(thermal_gap 0.5)
			(thermal_bridge_width 0.5)
			(island_removal_mode 0)
		)
		(polygon
			(pts
				(arc
					(start 35.005772 -407.01214)
					(mid 34.345372 -407.01214)
					(end 35.005772 -407.01214)
				)
			)
		)
	)
	(zone
		(layer "In16.Cu")
		(hatch none 0.5)
		(connect_pads
			(clearance 0)
		)
		(min_thickness 0.25)
		(keepout
			(tracks not_allowed)
			(vias allowed)
			(pads allowed)
			(copperpour not_allowed)
			(footprints allowed)
		)
		(placement
			(enabled no)
			(sheetname "")
		)
		(fill
			(thermal_gap 0.5)
			(thermal_bridge_width 0.5)
			(island_removal_mode 0)
		)
		(polygon
			(pts
				(arc
					(start 343.407492 -63.694564)
					(mid 343.385174 -63.640682)
					(end 343.331292 -63.618364)
				)
				(arc
					(start 343.001092 -63.618364)
					(mid 342.94721 -63.640682)
					(end 342.924892 -63.694564)
				)
				(arc
					(start 342.924892 -63.948564)
					(mid 342.94721 -64.002446)
					(end 343.001092 -64.024764)
				)
				(arc
					(start 343.331292 -64.024764)
					(mid 343.385174 -64.002446)
					(end 343.407492 -63.948564)
				)
			)
		)
	)
	(zone
		(layer "In16.Cu")
		(hatch none 0.5)
		(connect_pads
			(clearance 0)
		)
		(min_thickness 0.25)
		(keepout
			(tracks not_allowed)
			(vias allowed)
			(pads allowed)
			(copperpour not_allowed)
			(footprints allowed)
		)
		(placement
			(enabled no)
			(sheetname "")
		)
		(fill
			(thermal_gap 0.5)
			(thermal_bridge_width 0.5)
			(island_removal_mode 0)
		)
		(polygon
			(pts
				(arc
					(start 340.647528 -61.662564)
					(mid 340.62521 -61.608682)
					(end 340.571328 -61.586364)
				)
				(arc
					(start 340.241128 -61.586364)
					(mid 340.187246 -61.608682)
					(end 340.164928 -61.662564)
				)
				(arc
					(start 340.164928 -61.916564)
					(mid 340.187246 -61.970446)
					(end 340.241128 -61.992764)
				)
				(arc
					(start 340.571328 -61.992764)
					(mid 340.62521 -61.970446)
					(end 340.647528 -61.916564)
				)
			)
		)
	)
	(zone
		(layer "In16.Cu")
		(hatch none 0.5)
		(connect_pads
			(clearance 0)
		)
		(min_thickness 0.25)
		(keepout
			(tracks not_allowed)
			(vias allowed)
			(pads allowed)
			(copperpour not_allowed)
			(footprints allowed)
		)
		(placement
			(enabled no)
			(sheetname "")
		)
		(fill
			(thermal_gap 0.5)
			(thermal_bridge_width 0.5)
			(island_removal_mode 0)
		)
		(polygon
			(pts
				(arc
					(start 341.561928 -61.662564)
					(mid 341.53961 -61.608682)
					(end 341.485728 -61.586364)
				)
				(arc
					(start 341.155528 -61.586364)
					(mid 341.101646 -61.608682)
					(end 341.079328 -61.662564)
				)
				(arc
					(start 341.079328 -61.916564)
					(mid 341.101646 -61.970446)
					(end 341.155528 -61.992764)
				)
				(arc
					(start 341.485728 -61.992764)
					(mid 341.53961 -61.970446)
					(end 341.561928 -61.916564)
				)
			)
		)
	)
	(zone
		(layer "In16.Cu")
		(hatch none 0.5)
		(connect_pads
			(clearance 0)
		)
		(min_thickness 0.25)
		(keepout
			(tracks not_allowed)
			(vias allowed)
			(pads allowed)
			(copperpour not_allowed)
			(footprints allowed)
		)
		(placement
			(enabled no)
			(sheetname "")
		)
		(fill
			(thermal_gap 0.5)
			(thermal_bridge_width 0.5)
			(island_removal_mode 0)
		)
		(polygon
			(pts
				(xy 124.989336 -25.532842) (xy 124.989336 -26.015442) (xy 124.582936 -26.015442) (xy 124.582936 -25.532842)
			)
		)
	)
	(zone
		(layer "In16.Cu")
		(hatch none 0.5)
		(connect_pads
			(clearance 0)
		)
		(min_thickness 0.25)
		(keepout
			(tracks not_allowed)
			(vias allowed)
			(pads allowed)
			(copperpour not_allowed)
			(footprints allowed)
		)
		(placement
			(enabled no)
			(sheetname "")
		)
		(fill
			(thermal_gap 0.5)
			(thermal_bridge_width 0.5)
			(island_removal_mode 0)
		)
		(polygon
			(pts
				(arc
					(start 349.536004 -64.42202)
					(mid 349.589886 -64.399702)
					(end 349.612204 -64.34582)
				)
				(arc
					(start 349.612204 -64.01562)
					(mid 349.589886 -63.961738)
					(end 349.536004 -63.93942)
				)
				(arc
					(start 349.282004 -63.93942)
					(mid 349.228122 -63.961738)
					(end 349.205804 -64.01562)
				)
				(arc
					(start 349.205804 -64.34582)
					(mid 349.228122 -64.399702)
					(end 349.282004 -64.42202)
				)
			)
		)
	)
	(zone
		(layer "In16.Cu")
		(hatch none 0.5)
		(connect_pads
			(clearance 0)
		)
		(min_thickness 0.25)
		(keepout
			(tracks not_allowed)
			(vias allowed)
			(pads allowed)
			(copperpour not_allowed)
			(footprints allowed)
		)
		(placement
			(enabled no)
			(sheetname "")
		)
		(fill
			(thermal_gap 0.5)
			(thermal_bridge_width 0.5)
			(island_removal_mode 0)
		)
		(polygon
			(pts
				(arc
					(start 376.986038 3.469894)
					(mid 377.008356 3.523776)
					(end 377.062238 3.546094)
				)
				(arc
					(start 377.674378 3.546094)
					(mid 377.72826 3.523776)
					(end 377.750578 3.469894)
				)
				(arc
					(start 377.750578 2.372614)
					(mid 377.72826 2.318732)
					(end 377.674378 2.296414)
				)
				(arc
					(start 377.062238 2.296414)
					(mid 377.008356 2.318732)
					(end 376.986038 2.372614)
				)
			)
		)
	)
	(zone
		(layer "In16.Cu")
		(hatch none 0.5)
		(connect_pads
			(clearance 0)
		)
		(min_thickness 0.25)
		(keepout
			(tracks not_allowed)
			(vias allowed)
			(pads allowed)
			(copperpour not_allowed)
			(footprints allowed)
		)
		(placement
			(enabled no)
			(sheetname "")
		)
		(fill
			(thermal_gap 0.5)
			(thermal_bridge_width 0.5)
			(island_removal_mode 0)
		)
		(polygon
			(pts
				(arc
					(start 35.006534 -405.99614)
					(mid 34.346642 -405.99614)
					(end 35.006534 -405.99614)
				)
			)
		)
	)
	(zone
		(layer "In16.Cu")
		(hatch none 0.5)
		(connect_pads
			(clearance 0)
		)
		(min_thickness 0.25)
		(keepout
			(tracks not_allowed)
			(vias allowed)
			(pads allowed)
			(copperpour not_allowed)
			(footprints allowed)
		)
		(placement
			(enabled no)
			(sheetname "")
		)
		(fill
			(thermal_gap 0.5)
			(thermal_bridge_width 0.5)
			(island_removal_mode 0)
		)
		(polygon
			(pts
				(arc
					(start 139.761468 -24.846534)
					(mid 139.101068 -24.846534)
					(end 139.761468 -24.846534)
				)
			)
		)
	)
	(zone
		(layer "In16.Cu")
		(hatch none 0.5)
		(connect_pads
			(clearance 0)
		)
		(min_thickness 0.25)
		(keepout
			(tracks not_allowed)
			(vias allowed)
			(pads allowed)
			(copperpour not_allowed)
			(footprints allowed)
		)
		(placement
			(enabled no)
			(sheetname "")
		)
		(fill
			(thermal_gap 0.5)
			(thermal_bridge_width 0.5)
			(island_removal_mode 0)
		)
		(polygon
			(pts
				(arc
					(start 338.374482 -63.922148)
					(mid 338.352164 -63.868266)
					(end 338.298282 -63.845948)
				)
				(arc
					(start 337.968082 -63.845948)
					(mid 337.9142 -63.868266)
					(end 337.891882 -63.922148)
				)
				(arc
					(start 337.891882 -64.176148)
					(mid 337.9142 -64.23003)
					(end 337.968082 -64.252348)
				)
				(arc
					(start 338.298282 -64.252348)
					(mid 338.352164 -64.23003)
					(end 338.374482 -64.176148)
				)
			)
		)
	)
	(zone
		(layer "In16.Cu")
		(hatch none 0.5)
		(connect_pads
			(clearance 0)
		)
		(min_thickness 0.25)
		(keepout
			(tracks not_allowed)
			(vias allowed)
			(pads allowed)
			(copperpour not_allowed)
			(footprints allowed)
		)
		(placement
			(enabled no)
			(sheetname "")
		)
		(fill
			(thermal_gap 0.5)
			(thermal_bridge_width 0.5)
			(island_removal_mode 0)
		)
		(polygon
			(pts
				(xy 126.361698 -26.913332) (xy 126.869698 -26.913332) (xy 126.869698 -27.390344) (xy 126.361698 -27.390344)
			)
		)
	)
	(zone
		(layer "In16.Cu")
		(hatch none 0.5)
		(connect_pads
			(clearance 0)
		)
		(min_thickness 0.25)
		(keepout
			(tracks not_allowed)
			(vias allowed)
			(pads allowed)
			(copperpour not_allowed)
			(footprints allowed)
		)
		(placement
			(enabled no)
			(sheetname "")
		)
		(fill
			(thermal_gap 0.5)
			(thermal_bridge_width 0.5)
			(island_removal_mode 0)
		)
		(polygon
			(pts
				(arc
					(start 346.71 -64.227964)
					(mid 346.687682 -64.174082)
					(end 346.6338 -64.151764)
				)
				(arc
					(start 346.3036 -64.151764)
					(mid 346.249718 -64.174082)
					(end 346.2274 -64.227964)
				)
				(arc
					(start 346.2274 -64.481964)
					(mid 346.249718 -64.535846)
					(end 346.3036 -64.558164)
				)
				(arc
					(start 346.6338 -64.558164)
					(mid 346.687682 -64.535846)
					(end 346.71 -64.481964)
				)
			)
		)
	)
	(zone
		(layer "In16.Cu")
		(hatch none 0.5)
		(connect_pads
			(clearance 0)
		)
		(min_thickness 0.25)
		(keepout
			(tracks not_allowed)
			(vias allowed)
			(pads allowed)
			(copperpour not_allowed)
			(footprints allowed)
		)
		(placement
			(enabled no)
			(sheetname "")
		)
		(fill
			(thermal_gap 0.5)
			(thermal_bridge_width 0.5)
			(island_removal_mode 0)
		)
		(polygon
			(pts
				(xy 140.790676 -29.540708) (xy 140.790676 -28.720288) (xy 140.960856 -28.720288) (xy 140.960856 -29.540708)
			)
		)
	)
	(zone
		(layer "In16.Cu")
		(hatch none 0.5)
		(connect_pads
			(clearance 0)
		)
		(min_thickness 0.25)
		(keepout
			(tracks not_allowed)
			(vias allowed)
			(pads allowed)
			(copperpour not_allowed)
			(footprints allowed)
		)
		(placement
			(enabled no)
			(sheetname "")
		)
		(fill
			(thermal_gap 0.5)
			(thermal_bridge_width 0.5)
			(island_removal_mode 0)
		)
		(polygon
			(pts
				(arc
					(start 37.117528 -405.781002)
					(mid 37.109771 -405.741961)
					(end 37.087302 -405.70912)
				)
				(arc
					(start 37.087302 -405.70912)
					(mid 37.056614 -405.689078)
					(end 37.020754 -405.681434)
				)
				(xy 36.878514 -405.681434) (xy 36.878514 -405.681688)
				(arc
					(start 35.95116 -405.681688)
					(mid 35.887654 -405.710878)
					(end 35.85972 -405.774906)
				)
				(arc
					(start 35.85972 -406.081738)
					(mid 35.867477 -406.120779)
					(end 35.889946 -406.15362)
				)
				(arc
					(start 35.889946 -406.15362)
					(mid 35.920634 -406.173662)
					(end 35.956494 -406.181306)
				)
				(xy 36.987734 -406.181306) (xy 36.987734 -406.181052)
				(arc
					(start 37.026088 -406.181052)
					(mid 37.089594 -406.151862)
					(end 37.117528 -406.087834)
				)
			)
		)
	)
	(zone
		(layer "In16.Cu")
		(hatch none 0.5)
		(connect_pads
			(clearance 0)
		)
		(min_thickness 0.25)
		(keepout
			(tracks not_allowed)
			(vias allowed)
			(pads allowed)
			(copperpour not_allowed)
			(footprints allowed)
		)
		(placement
			(enabled no)
			(sheetname "")
		)
		(fill
			(thermal_gap 0.5)
			(thermal_bridge_width 0.5)
			(island_removal_mode 0)
		)
		(polygon
			(pts
				(xy 128.811782 -26.913332) (xy 129.319782 -26.913332) (xy 129.319782 -27.390344) (xy 128.811782 -27.390344)
			)
		)
	)
	(zone
		(layer "In16.Cu")
		(hatch none 0.5)
		(connect_pads
			(clearance 0)
		)
		(min_thickness 0.25)
		(keepout
			(tracks not_allowed)
			(vias allowed)
			(pads allowed)
			(copperpour not_allowed)
			(footprints allowed)
		)
		(placement
			(enabled no)
			(sheetname "")
		)
		(fill
			(thermal_gap 0.5)
			(thermal_bridge_width 0.5)
			(island_removal_mode 0)
		)
		(polygon
			(pts
				(arc
					(start 342.493092 -63.694564)
					(mid 342.470774 -63.640682)
					(end 342.416892 -63.618364)
				)
				(arc
					(start 342.086692 -63.618364)
					(mid 342.03281 -63.640682)
					(end 342.010492 -63.694564)
				)
				(arc
					(start 342.010492 -63.948564)
					(mid 342.03281 -64.002446)
					(end 342.086692 -64.024764)
				)
				(arc
					(start 342.416892 -64.024764)
					(mid 342.470774 -64.002446)
					(end 342.493092 -63.948564)
				)
			)
		)
	)
	(zone
		(layer "In16.Cu")
		(hatch none 0.5)
		(connect_pads
			(clearance 0)
		)
		(min_thickness 0.25)
		(keepout
			(tracks not_allowed)
			(vias allowed)
			(pads allowed)
			(copperpour not_allowed)
			(footprints allowed)
		)
		(placement
			(enabled no)
			(sheetname "")
		)
		(fill
			(thermal_gap 0.5)
			(thermal_bridge_width 0.5)
			(island_removal_mode 0)
		)
		(polygon
			(pts
				(arc
					(start 346.333064 -57.934352)
					(mid 346.279216 -57.912047)
					(end 346.225368 -57.934352)
				)
				(arc
					(start 345.991942 -58.167778)
					(mid 345.969637 -58.221626)
					(end 345.991942 -58.275474)
				)
				(arc
					(start 346.17152 -58.455052)
					(mid 346.225368 -58.477357)
					(end 346.279216 -58.455052)
				)
				(arc
					(start 346.512642 -58.221626)
					(mid 346.534947 -58.167778)
					(end 346.512642 -58.11393)
				)
			)
		)
	)
	(zone
		(layer "In16.Cu")
		(hatch none 0.5)
		(connect_pads
			(clearance 0)
		)
		(min_thickness 0.25)
		(keepout
			(tracks not_allowed)
			(vias allowed)
			(pads allowed)
			(copperpour not_allowed)
			(footprints allowed)
		)
		(placement
			(enabled no)
			(sheetname "")
		)
		(fill
			(thermal_gap 0.5)
			(thermal_bridge_width 0.5)
			(island_removal_mode 0)
		)
		(polygon
			(pts
				(arc
					(start 344.996008 -61.662564)
					(mid 344.97369 -61.608682)
					(end 344.919808 -61.586364)
				)
				(arc
					(start 344.589608 -61.586364)
					(mid 344.535726 -61.608682)
					(end 344.513408 -61.662564)
				)
				(arc
					(start 344.513408 -61.916564)
					(mid 344.535726 -61.970446)
					(end 344.589608 -61.992764)
				)
				(arc
					(start 344.919808 -61.992764)
					(mid 344.97369 -61.970446)
					(end 344.996008 -61.916564)
				)
			)
		)
	)
	(zone
		(layer "In16.Cu")
		(hatch none 0.5)
		(connect_pads
			(clearance 0)
		)
		(min_thickness 0.25)
		(keepout
			(tracks not_allowed)
			(vias allowed)
			(pads allowed)
			(copperpour not_allowed)
			(footprints allowed)
		)
		(placement
			(enabled no)
			(sheetname "")
		)
		(fill
			(thermal_gap 0.5)
			(thermal_bridge_width 0.5)
			(island_removal_mode 0)
		)
		(polygon
			(pts
				(arc
					(start 346.71 -63.694564)
					(mid 346.687682 -63.640682)
					(end 346.6338 -63.618364)
				)
				(arc
					(start 346.3036 -63.618364)
					(mid 346.249718 -63.640682)
					(end 346.2274 -63.694564)
				)
				(arc
					(start 346.2274 -63.948564)
					(mid 346.249718 -64.002446)
					(end 346.3036 -64.024764)
				)
				(arc
					(start 346.6338 -64.024764)
					(mid 346.687682 -64.002446)
					(end 346.71 -63.948564)
				)
			)
		)
	)
	(zone
		(layer "In16.Cu")
		(hatch none 0.5)
		(connect_pads
			(clearance 0)
		)
		(min_thickness 0.25)
		(keepout
			(tracks not_allowed)
			(vias allowed)
			(pads allowed)
			(copperpour not_allowed)
			(footprints allowed)
		)
		(placement
			(enabled no)
			(sheetname "")
		)
		(fill
			(thermal_gap 0.5)
			(thermal_bridge_width 0.5)
			(island_removal_mode 0)
		)
		(polygon
			(pts
				(xy 140.39088 -28.14066) (xy 140.39088 -27.32024) (xy 140.56106 -27.32024) (xy 140.56106 -28.14066)
			)
		)
	)
	(zone
		(layer "In16.Cu")
		(hatch none 0.5)
		(connect_pads
			(clearance 0)
		)
		(min_thickness 0.25)
		(keepout
			(tracks not_allowed)
			(vias allowed)
			(pads allowed)
			(copperpour not_allowed)
			(footprints allowed)
		)
		(placement
			(enabled no)
			(sheetname "")
		)
		(fill
			(thermal_gap 0.5)
			(thermal_bridge_width 0.5)
			(island_removal_mode 0)
		)
		(polygon
			(pts
				(arc
					(start 350.069404 -65.33642)
					(mid 350.123286 -65.314102)
					(end 350.145604 -65.26022)
				)
				(arc
					(start 350.145604 -64.93002)
					(mid 350.123286 -64.876138)
					(end 350.069404 -64.85382)
				)
				(arc
					(start 349.815404 -64.85382)
					(mid 349.761522 -64.876138)
					(end 349.739204 -64.93002)
				)
				(arc
					(start 349.739204 -65.26022)
					(mid 349.761522 -65.314102)
					(end 349.815404 -65.33642)
				)
			)
		)
	)
	(zone
		(layer "In16.Cu")
		(hatch none 0.5)
		(connect_pads
			(clearance 0)
		)
		(min_thickness 0.25)
		(keepout
			(tracks not_allowed)
			(vias allowed)
			(pads allowed)
			(copperpour not_allowed)
			(footprints allowed)
		)
		(placement
			(enabled no)
			(sheetname "")
		)
		(fill
			(thermal_gap 0.5)
			(thermal_bridge_width 0.5)
			(island_removal_mode 0)
		)
		(polygon
			(pts
				(arc
					(start 350.069404 -64.42202)
					(mid 350.123286 -64.399702)
					(end 350.145604 -64.34582)
				)
				(arc
					(start 350.145604 -64.01562)
					(mid 350.123286 -63.961738)
					(end 350.069404 -63.93942)
				)
				(arc
					(start 349.815404 -63.93942)
					(mid 349.761522 -63.961738)
					(end 349.739204 -64.01562)
				)
				(arc
					(start 349.739204 -64.34582)
					(mid 349.761522 -64.399702)
					(end 349.815404 -64.42202)
				)
			)
		)
	)
	(zone
		(layer "In16.Cu")
		(hatch none 0.5)
		(connect_pads
			(clearance 0)
		)
		(min_thickness 0.25)
		(keepout
			(tracks not_allowed)
			(vias allowed)
			(pads allowed)
			(copperpour not_allowed)
			(footprints allowed)
		)
		(placement
			(enabled no)
			(sheetname "")
		)
		(fill
			(thermal_gap 0.5)
			(thermal_bridge_width 0.5)
			(island_removal_mode 0)
		)
		(polygon
			(pts
				(xy 128.811782 -25.163272) (xy 129.319782 -25.163272) (xy 129.319782 -25.640284) (xy 128.811782 -25.640284)
			)
		)
	)
	(zone
		(layer "In16.Cu")
		(hatch none 0.5)
		(connect_pads
			(clearance 0)
		)
		(min_thickness 0.25)
		(keepout
			(tracks not_allowed)
			(vias allowed)
			(pads allowed)
			(copperpour not_allowed)
			(footprints allowed)
		)
		(placement
			(enabled no)
			(sheetname "")
		)
		(fill
			(thermal_gap 0.5)
			(thermal_bridge_width 0.5)
			(island_removal_mode 0)
		)
		(polygon
			(pts
				(arc
					(start 340.41207 7.457694)
					(mid 340.389752 7.403812)
					(end 340.33587 7.381494)
				)
				(arc
					(start 339.72373 7.381494)
					(mid 339.669848 7.403812)
					(end 339.64753 7.457694)
				)
				(arc
					(start 339.64753 8.554974)
					(mid 339.669848 8.608856)
					(end 339.72373 8.631174)
				)
				(arc
					(start 340.33587 8.631174)
					(mid 340.389752 8.608856)
					(end 340.41207 8.554974)
				)
			)
		)
	)
	(zone
		(layer "In16.Cu")
		(hatch none 0.5)
		(connect_pads
			(clearance 0)
		)
		(min_thickness 0.25)
		(keepout
			(tracks not_allowed)
			(vias allowed)
			(pads allowed)
			(copperpour not_allowed)
			(footprints allowed)
		)
		(placement
			(enabled no)
			(sheetname "")
		)
		(fill
			(thermal_gap 0.5)
			(thermal_bridge_width 0.5)
			(island_removal_mode 0)
		)
		(polygon
			(pts
				(arc
					(start 138.694668 -23.571962)
					(mid 138.733709 -23.564205)
					(end 138.76655 -23.541736)
				)
				(arc
					(start 138.76655 -23.541736)
					(mid 138.786592 -23.511048)
					(end 138.794236 -23.475188)
				)
				(xy 138.794236 -23.332948) (xy 138.793982 -23.332948)
				(arc
					(start 138.793982 -22.405594)
					(mid 138.764792 -22.342088)
					(end 138.700764 -22.314154)
				)
				(arc
					(start 138.393932 -22.314154)
					(mid 138.354891 -22.321911)
					(end 138.32205 -22.34438)
				)
				(arc
					(start 138.32205 -22.34438)
					(mid 138.302008 -22.375068)
					(end 138.294364 -22.410928)
				)
				(xy 138.294364 -23.442168) (xy 138.294618 -23.442168)
				(arc
					(start 138.294618 -23.480522)
					(mid 138.323808 -23.544028)
					(end 138.387836 -23.571962)
				)
			)
		)
	)
	(zone
		(layer "In16.Cu")
		(hatch none 0.5)
		(connect_pads
			(clearance 0)
		)
		(min_thickness 0.25)
		(keepout
			(tracks not_allowed)
			(vias allowed)
			(pads allowed)
			(copperpour not_allowed)
			(footprints allowed)
		)
		(placement
			(enabled no)
			(sheetname "")
		)
		(fill
			(thermal_gap 0.5)
			(thermal_bridge_width 0.5)
			(island_removal_mode 0)
		)
		(polygon
			(pts
				(arc
					(start 345.7956 -64.227964)
					(mid 345.773282 -64.174082)
					(end 345.7194 -64.151764)
				)
				(arc
					(start 345.3892 -64.151764)
					(mid 345.335318 -64.174082)
					(end 345.313 -64.227964)
				)
				(arc
					(start 345.313 -64.481964)
					(mid 345.335318 -64.535846)
					(end 345.3892 -64.558164)
				)
				(arc
					(start 345.7194 -64.558164)
					(mid 345.773282 -64.535846)
					(end 345.7956 -64.481964)
				)
			)
		)
	)
	(zone
		(layer "In16.Cu")
		(hatch none 0.5)
		(connect_pads
			(clearance 0)
		)
		(min_thickness 0.25)
		(keepout
			(tracks not_allowed)
			(vias allowed)
			(pads allowed)
			(copperpour not_allowed)
			(footprints allowed)
		)
		(placement
			(enabled no)
			(sheetname "")
		)
		(fill
			(thermal_gap 0.5)
			(thermal_bridge_width 0.5)
			(island_removal_mode 0)
		)
		(polygon
			(pts
				(arc
					(start 187.247022 -20.046696)
					(mid 187.286063 -20.038939)
					(end 187.318904 -20.01647)
				)
				(arc
					(start 187.318904 -20.01647)
					(mid 187.338946 -19.985782)
					(end 187.34659 -19.949922)
				)
				(xy 187.34659 -19.807682) (xy 187.346336 -19.807682)
				(arc
					(start 187.346336 -18.880328)
					(mid 187.317146 -18.816822)
					(end 187.253118 -18.788888)
				)
				(arc
					(start 186.946286 -18.788888)
					(mid 186.907245 -18.796645)
					(end 186.874404 -18.819114)
				)
				(arc
					(start 186.874404 -18.819114)
					(mid 186.854362 -18.849802)
					(end 186.846718 -18.885662)
				)
				(xy 186.846718 -19.916902) (xy 186.846972 -19.916902)
				(arc
					(start 186.846972 -19.955256)
					(mid 186.876162 -20.018762)
					(end 186.94019 -20.046696)
				)
			)
		)
	)
	(zone
		(layer "In16.Cu")
		(hatch none 0.5)
		(connect_pads
			(clearance 0)
		)
		(min_thickness 0.25)
		(keepout
			(tracks not_allowed)
			(vias allowed)
			(pads allowed)
			(copperpour not_allowed)
			(footprints allowed)
		)
		(placement
			(enabled no)
			(sheetname "")
		)
		(fill
			(thermal_gap 0.5)
			(thermal_bridge_width 0.5)
			(island_removal_mode 0)
		)
		(polygon
			(pts
				(arc
					(start 344.996008 -62.195964)
					(mid 344.97369 -62.142082)
					(end 344.919808 -62.119764)
				)
				(arc
					(start 344.589608 -62.119764)
					(mid 344.535726 -62.142082)
					(end 344.513408 -62.195964)
				)
				(arc
					(start 344.513408 -62.449964)
					(mid 344.535726 -62.503846)
					(end 344.589608 -62.526164)
				)
				(arc
					(start 344.919808 -62.526164)
					(mid 344.97369 -62.503846)
					(end 344.996008 -62.449964)
				)
			)
		)
	)
	(zone
		(layer "In16.Cu")
		(hatch none 0.5)
		(connect_pads
			(clearance 0)
		)
		(min_thickness 0.25)
		(keepout
			(tracks not_allowed)
			(vias allowed)
			(pads allowed)
			(copperpour not_allowed)
			(footprints allowed)
		)
		(placement
			(enabled no)
			(sheetname "")
		)
		(fill
			(thermal_gap 0.5)
			(thermal_bridge_width 0.5)
			(island_removal_mode 0)
		)
		(polygon
			(pts
				(arc
					(start 346.710254 -58.311542)
					(mid 346.656406 -58.289237)
					(end 346.602558 -58.311542)
				)
				(arc
					(start 346.369132 -58.544968)
					(mid 346.346827 -58.598816)
					(end 346.369132 -58.652664)
				)
				(arc
					(start 346.54871 -58.832242)
					(mid 346.602558 -58.854547)
					(end 346.656406 -58.832242)
				)
				(arc
					(start 346.889832 -58.598816)
					(mid 346.912137 -58.544968)
					(end 346.889832 -58.49112)
				)
			)
		)
	)
	(zone
		(layer "In16.Cu")
		(hatch none 0.5)
		(connect_pads
			(clearance 0)
		)
		(min_thickness 0.25)
		(keepout
			(tracks not_allowed)
			(vias allowed)
			(pads allowed)
			(copperpour not_allowed)
			(footprints allowed)
		)
		(placement
			(enabled no)
			(sheetname "")
		)
		(fill
			(thermal_gap 0.5)
			(thermal_bridge_width 0.5)
			(island_removal_mode 0)
		)
		(polygon
			(pts
				(arc
					(start 167.93845 -47.846742)
					(mid 167.279066 -47.846742)
					(end 167.93845 -47.846742)
				)
			)
		)
	)
	(zone
		(layer "In16.Cu")
		(hatch none 0.5)
		(connect_pads
			(clearance 0)
		)
		(min_thickness 0.25)
		(keepout
			(tracks not_allowed)
			(vias allowed)
			(pads allowed)
			(copperpour not_allowed)
			(footprints allowed)
		)
		(placement
			(enabled no)
			(sheetname "")
		)
		(fill
			(thermal_gap 0.5)
			(thermal_bridge_width 0.5)
			(island_removal_mode 0)
		)
		(polygon
			(pts
				(arc
					(start 341.561928 -62.195964)
					(mid 341.53961 -62.142082)
					(end 341.485728 -62.119764)
				)
				(arc
					(start 341.155528 -62.119764)
					(mid 341.101646 -62.142082)
					(end 341.079328 -62.195964)
				)
				(arc
					(start 341.079328 -62.449964)
					(mid 341.101646 -62.503846)
					(end 341.155528 -62.526164)
				)
				(arc
					(start 341.485728 -62.526164)
					(mid 341.53961 -62.503846)
					(end 341.561928 -62.449964)
				)
			)
		)
	)
	(zone
		(layer "In16.Cu")
		(hatch none 0.5)
		(connect_pads
			(clearance 0)
		)
		(min_thickness 0.25)
		(keepout
			(tracks not_allowed)
			(vias allowed)
			(pads allowed)
			(copperpour not_allowed)
			(footprints allowed)
		)
		(placement
			(enabled no)
			(sheetname "")
		)
		(fill
			(thermal_gap 0.5)
			(thermal_bridge_width 0.5)
			(island_removal_mode 0)
		)
		(polygon
			(pts
				(arc
					(start 249.541284 -1.6129)
					(mid 249.563602 -1.559018)
					(end 249.617484 -1.5367)
				)
				(arc
					(start 250.229624 -1.5367)
					(mid 250.283506 -1.559018)
					(end 250.305824 -1.6129)
				)
				(arc
					(start 250.305824 -2.71018)
					(mid 250.283506 -2.764062)
					(end 250.229624 -2.78638)
				)
				(arc
					(start 249.617484 -2.78638)
					(mid 249.563602 -2.764062)
					(end 249.541284 -2.71018)
				)
			)
		)
	)
	(zone
		(layer "In16.Cu")
		(hatch none 0.5)
		(connect_pads
			(clearance 0)
		)
		(min_thickness 0.25)
		(keepout
			(tracks not_allowed)
			(vias allowed)
			(pads allowed)
			(copperpour not_allowed)
			(footprints allowed)
		)
		(placement
			(enabled no)
			(sheetname "")
		)
		(fill
			(thermal_gap 0.5)
			(thermal_bridge_width 0.5)
			(island_removal_mode 0)
		)
		(polygon
			(pts
				(arc
					(start 187.764166 -21.263356)
					(mid 187.103766 -21.263356)
					(end 187.764166 -21.263356)
				)
			)
		)
	)
	(zone
		(layer "In16.Cu")
		(hatch none 0.5)
		(connect_pads
			(clearance 0)
		)
		(min_thickness 0.25)
		(keepout
			(tracks not_allowed)
			(vias allowed)
			(pads allowed)
			(copperpour not_allowed)
			(footprints allowed)
		)
		(placement
			(enabled no)
			(sheetname "")
		)
		(fill
			(thermal_gap 0.5)
			(thermal_bridge_width 0.5)
			(island_removal_mode 0)
		)
		(polygon
			(pts
				(arc
					(start 137.658348 -23.571962)
					(mid 137.697389 -23.564205)
					(end 137.73023 -23.541736)
				)
				(arc
					(start 137.73023 -23.541736)
					(mid 137.750272 -23.511048)
					(end 137.757916 -23.475188)
				)
				(xy 137.757916 -23.332948) (xy 137.757662 -23.332948)
				(arc
					(start 137.757662 -22.405594)
					(mid 137.728472 -22.342088)
					(end 137.664444 -22.314154)
				)
				(arc
					(start 137.357612 -22.314154)
					(mid 137.318571 -22.321911)
					(end 137.28573 -22.34438)
				)
				(arc
					(start 137.28573 -22.34438)
					(mid 137.265688 -22.375068)
					(end 137.258044 -22.410928)
				)
				(xy 137.258044 -23.442168) (xy 137.258298 -23.442168)
				(arc
					(start 137.258298 -23.480522)
					(mid 137.287488 -23.544028)
					(end 137.351516 -23.571962)
				)
			)
		)
	)
	(zone
		(layer "In16.Cu")
		(hatch none 0.5)
		(connect_pads
			(clearance 0)
		)
		(min_thickness 0.25)
		(keepout
			(tracks not_allowed)
			(vias allowed)
			(pads allowed)
			(copperpour not_allowed)
			(footprints allowed)
		)
		(placement
			(enabled no)
			(sheetname "")
		)
		(fill
			(thermal_gap 0.5)
			(thermal_bridge_width 0.5)
			(island_removal_mode 0)
		)
		(polygon
			(pts
				(arc
					(start 338.374482 -64.455548)
					(mid 338.352164 -64.401666)
					(end 338.298282 -64.379348)
				)
				(arc
					(start 337.968082 -64.379348)
					(mid 337.9142 -64.401666)
					(end 337.891882 -64.455548)
				)
				(arc
					(start 337.891882 -64.709548)
					(mid 337.9142 -64.76343)
					(end 337.968082 -64.785748)
				)
				(arc
					(start 338.298282 -64.785748)
					(mid 338.352164 -64.76343)
					(end 338.374482 -64.709548)
				)
			)
		)
	)
	(zone
		(layer "In16.Cu")
		(hatch none 0.5)
		(connect_pads
			(clearance 0)
		)
		(min_thickness 0.25)
		(keepout
			(tracks not_allowed)
			(vias allowed)
			(pads allowed)
			(copperpour not_allowed)
			(footprints allowed)
		)
		(placement
			(enabled no)
			(sheetname "")
		)
		(fill
			(thermal_gap 0.5)
			(thermal_bridge_width 0.5)
			(island_removal_mode 0)
		)
		(polygon
			(pts
				(arc
					(start 186.205622 -20.046696)
					(mid 186.244663 -20.038939)
					(end 186.277504 -20.01647)
				)
				(arc
					(start 186.277504 -20.01647)
					(mid 186.297546 -19.985782)
					(end 186.30519 -19.949922)
				)
				(xy 186.30519 -19.807682) (xy 186.304936 -19.807682)
				(arc
					(start 186.304936 -18.880328)
					(mid 186.275746 -18.816822)
					(end 186.211718 -18.788888)
				)
				(arc
					(start 185.904886 -18.788888)
					(mid 185.865845 -18.796645)
					(end 185.833004 -18.819114)
				)
				(arc
					(start 185.833004 -18.819114)
					(mid 185.812962 -18.849802)
					(end 185.805318 -18.885662)
				)
				(xy 185.805318 -19.916902) (xy 185.805572 -19.916902)
				(arc
					(start 185.805572 -19.955256)
					(mid 185.834762 -20.018762)
					(end 185.89879 -20.046696)
				)
			)
		)
	)
	(zone
		(layer "In16.Cu")
		(hatch none 0.5)
		(connect_pads
			(clearance 0)
		)
		(min_thickness 0.25)
		(keepout
			(tracks not_allowed)
			(vias allowed)
			(pads allowed)
			(copperpour not_allowed)
			(footprints allowed)
		)
		(placement
			(enabled no)
			(sheetname "")
		)
		(fill
			(thermal_gap 0.5)
			(thermal_bridge_width 0.5)
			(island_removal_mode 0)
		)
		(polygon
			(pts
				(arc
					(start 261.845044 7.457694)
					(mid 261.822726 7.403812)
					(end 261.768844 7.381494)
				)
				(arc
					(start 261.156704 7.381494)
					(mid 261.102822 7.403812)
					(end 261.080504 7.457694)
				)
				(arc
					(start 261.080504 8.554974)
					(mid 261.102822 8.608856)
					(end 261.156704 8.631174)
				)
				(arc
					(start 261.768844 8.631174)
					(mid 261.822726 8.608856)
					(end 261.845044 8.554974)
				)
			)
		)
	)
	(zone
		(layer "In16.Cu")
		(hatch none 0.5)
		(connect_pads
			(clearance 0)
		)
		(min_thickness 0.25)
		(keepout
			(tracks not_allowed)
			(vias allowed)
			(pads allowed)
			(copperpour not_allowed)
			(footprints allowed)
		)
		(placement
			(enabled no)
			(sheetname "")
		)
		(fill
			(thermal_gap 0.5)
			(thermal_bridge_width 0.5)
			(island_removal_mode 0)
		)
		(polygon
			(pts
				(arc
					(start 376.986038 -1.610106)
					(mid 377.008356 -1.556224)
					(end 377.062238 -1.533906)
				)
				(arc
					(start 377.674378 -1.533906)
					(mid 377.72826 -1.556224)
					(end 377.750578 -1.610106)
				)
				(arc
					(start 377.750578 -2.707386)
					(mid 377.72826 -2.761268)
					(end 377.674378 -2.783586)
				)
				(arc
					(start 377.062238 -2.783586)
					(mid 377.008356 -2.761268)
					(end 376.986038 -2.707386)
				)
			)
		)
	)
	(zone
		(layer "In16.Cu")
		(hatch none 0.5)
		(connect_pads
			(clearance 0)
		)
		(min_thickness 0.25)
		(keepout
			(tracks not_allowed)
			(vias allowed)
			(pads allowed)
			(copperpour not_allowed)
			(footprints allowed)
		)
		(placement
			(enabled no)
			(sheetname "")
		)
		(fill
			(thermal_gap 0.5)
			(thermal_bridge_width 0.5)
			(island_removal_mode 0)
		)
		(polygon
			(pts
				(arc
					(start 186.735466 -21.250656)
					(mid 186.075066 -21.250656)
					(end 186.735466 -21.250656)
				)
			)
		)
	)
	(zone
		(layer "In16.Cu")
		(hatch none 0.5)
		(connect_pads
			(clearance 0)
		)
		(min_thickness 0.25)
		(keepout
			(tracks not_allowed)
			(vias allowed)
			(pads allowed)
			(copperpour not_allowed)
			(footprints allowed)
		)
		(placement
			(enabled no)
			(sheetname "")
		)
		(fill
			(thermal_gap 0.5)
			(thermal_bridge_width 0.5)
			(island_removal_mode 0)
		)
		(polygon
			(pts
				(xy 11.789664 -113.430558) (xy 11.789664 -112.610138) (xy 11.959844 -112.610138) (xy 11.959844 -113.430558)
			)
		)
	)
	(zone
		(layer "In16.Cu")
		(hatch none 0.5)
		(connect_pads
			(clearance 0)
		)
		(min_thickness 0.25)
		(keepout
			(tracks not_allowed)
			(vias allowed)
			(pads allowed)
			(copperpour not_allowed)
			(footprints allowed)
		)
		(placement
			(enabled no)
			(sheetname "")
		)
		(fill
			(thermal_gap 0.5)
			(thermal_bridge_width 0.5)
			(island_removal_mode 0)
		)
		(polygon
			(pts
				(xy 125.522736 -24.745442) (xy 125.522736 -25.228042) (xy 125.116336 -25.228042) (xy 125.116336 -24.745442)
			)
		)
	)
)
